G04 ================== begin FILE IDENTIFICATION RECORD ==================*
G04 Layout Name:  E:/<user>/9332_F0TG_MB_C/brd/0417/9332_F0TG_MB_C_V02_0417_0820.brd*
G04 Film Name:    fab*
G04 File Format:  Gerber RS274X*
G04 File Origin:  Cadence Allegro 17.2-S081*
G04 Origin Date:  Wed Apr 19 14:50:15 2023*
G04 *
G04 Layer:  PIN/SPECIAL_DRILL*
G04 Layer:  MANUFACTURING/PHOTOPLOT_OUTLINE*
G04 Layer:  MANUFACTURING/NCDRILL_LEGEND*
G04 Layer:  MANUFACTURING/NCDRILL_FIGURE*
G04 Layer:  MANUFACTURING/NCBACKDRILL-18-9*
G04 Layer:  MANUFACTURING/NCBACKDRILL-1-15*
G04 Layer:  MANUFACTURING/NCBACKDRILL-18-7*
G04 Layer:  MANUFACTURING/NCBACKDRILL-18-2*
G04 Layer:  MANUFACTURING/NCBACKDRILL-18-17*
G04 Layer:  MANUFACTURING/NCBACKDRILL-1-13*
G04 Layer:  MANUFACTURING/NCBACKDRILL-1-2*
G04 Layer:  MANUFACTURING/NCBACKDRILL-1-4*
G04 Layer:  MANUFACTURING/NCBACKDRILL-1-6*
G04 Layer:  MANUFACTURING/NCBACKDRILL-1-11*
G04 Layer:  MANUFACTURING/NCBACKDRILL-18-15*
G04 Layer:  MANUFACTURING/NCBACKDRILL-18-4*
G04 Layer:  MANUFACTURING/NCBACKDRILL-18-8*
G04 Layer:  MANUFACTURING/NCBACKDRILL-18-13*
G04 Layer:  MANUFACTURING/NCBACKDRILL-18-6*
G04 Layer:  MANUFACTURING/NCLEGEND-1-18*
G04 Layer:  MANUFACTURING/DIMENSION*
G04 Layer:  MANUFACTURING/DETAILS*
G04 Layer:  DRAWING FORMAT/TITLE_BLOCK*
G04 Layer:  DRAWING FORMAT/TITLE_BLOCK_A*
G04 Layer:  DRAWING FORMAT/TITLE_DATA_FAB*
G04 Layer:  BOARD GEOMETRY/DESIGN_OUTLINE*
G04 Layer:  BOARD GEOMETRY/CUTOUT*
G04 *
G04 Offset:    (0.00 0.00)*
G04 Mirror:    No*
G04 Mode:      Positive*
G04 Rotation:  0*
G04 FullContactRelief:  No*
G04 UndefLineWidth:     6.00*
G04 ================== end FILE IDENTIFICATION RECORD ====================*
%FSLAX25Y25*MOIN*%
%IR0*IPPOS*OFA0.00000B0.00000*MIA0B0*SFA1.00000B1.00000*%
%AMMACRO23*
1,1,.006,.014497,-.035*
20,1,.006,.014497,-.035,-.014497,-.035,0.0*
1,1,.006,-.014497,-.035*
20,1,.006,-.014497,-.035,-.035,-.014497,0.0*
1,1,.006,-.035,-.014497*
20,1,.006,-.035,-.014497,-.035,.014497,0.0*
1,1,.006,-.035,.014497*
20,1,.006,-.035,.014497,-.014497,.035,0.0*
1,1,.006,-.014497,.035*
20,1,.006,-.014497,.035,.014497,.035,0.0*
1,1,.006,.014497,.035*
20,1,.006,.014497,.035,.035,.014497,0.0*
1,1,.006,.035,.014497*
20,1,.006,.035,.014497,.035,-.014497,0.0*
1,1,.006,.035,-.014497*
20,1,.006,.035,-.014497,.014497,-.035,0.0*
1,1,.006,.014497,-.035*
1,1,.006,-.0229,-.01041*
20,1,.006,-.0229,-.01041,-.0229,.00729,0.0*
1,1,.006,-.0229,.00729*
20,1,.006,-.0229,.00729,-.02221,.00902,0.0*
1,1,.006,-.02221,.00902*
20,1,.006,-.02221,.00902,-.02082,.01006,0.0*
1,1,.006,-.02082,.01006*
20,1,.006,-.02082,.01006,-.01874,.01041,0.0*
1,1,.006,-.01874,.01041*
20,1,.006,-.01874,.01041,-.01666,.00972,0.0*
1,1,.006,-.01666,.00972*
20,1,.006,-.01666,.00972,-.01562,.00798,0.0*
1,1,.006,-.01562,.00798*
1,1,.006,-.01978,.00208*
20,1,.006,-.01978,.00208,-.02672,.00208,0.0*
1,1,.006,-.02672,.00208*
1,1,.006,.00001,.00347*
20,1,.006,.00001,.00347,.00001,-.01041,0.0*
1,1,.006,.00001,-.01041*
1,1,.006,.00001,.00902*
20,1,.006,.00001,.00902,-.00068,.00937,0.0*
1,1,.006,-.00068,.00937*
20,1,.006,-.00068,.00937,-.00068,.01006,0.0*
1,1,.006,-.00068,.01006*
20,1,.006,-.00068,.01006,.00001,.01041,0.0*
1,1,.006,.00001,.01041*
20,1,.006,.00001,.01041,.0007,.01006,0.0*
1,1,.006,.0007,.01006*
20,1,.006,.0007,.01006,.0007,.00937,0.0*
1,1,.006,.0007,.00937*
20,1,.006,.0007,.00937,.00001,.00902,0.0*
1,1,.006,.00001,.00902*
1,1,.006,.02084,.01041*
20,1,.006,.02084,.01041,.02084,-.01041,0.0*
1,1,.006,.02084,-.01041*
1,1,.006,.01598,.00347*
20,1,.006,.01598,.00347,.0257,.00347,0.0*
1,1,.006,.0257,.00347*
%
%ADD23MACRO23*%
%AMMACRO32*
1,1,.006,.035,.035*
20,1,.006,.035,.035,.035,-.035,0.0*
1,1,.006,.035,-.035*
20,1,.006,.035,-.035,-.035,-.035,0.0*
1,1,.006,-.035,-.035*
20,1,.006,-.035,-.035,-.035,.035,0.0*
1,1,.006,-.035,.035*
20,1,.006,-.035,.035,.035,.035,0.0*
1,1,.006,.035,.035*
1,1,.006,-.03185,-.02042*
20,1,.006,-.03185,-.02042,-.03185,.00408,0.0*
1,1,.006,-.03185,.00408*
1,1,.006,-.03185,.00041*
20,1,.006,-.03185,.00041,-.02981,.00245,0.0*
1,1,.006,-.02981,.00245*
20,1,.006,-.02981,.00245,-.02777,.00367,0.0*
1,1,.006,-.02777,.00367*
20,1,.006,-.02777,.00367,-.0245,.00408,0.0*
1,1,.006,-.0245,.00408*
20,1,.006,-.0245,.00408,-.02164,.00367,0.0*
1,1,.006,-.02164,.00367*
20,1,.006,-.02164,.00367,-.01878,.00163,0.0*
1,1,.006,-.01878,.00163*
20,1,.006,-.01878,.00163,-.01756,-.00123,0.0*
1,1,.006,-.01756,-.00123*
20,1,.006,-.01756,-.00123,-.01715,-.00408,0.0*
1,1,.006,-.01715,-.00408*
20,1,.006,-.01715,-.00408,-.01756,-.00694,0.0*
1,1,.006,-.01756,-.00694*
20,1,.006,-.01756,-.00694,-.01878,-.0098,0.0*
1,1,.006,-.01878,-.0098*
20,1,.006,-.01878,-.0098,-.02123,-.01143,0.0*
1,1,.006,-.02123,-.01143*
20,1,.006,-.02123,-.01143,-.0245,-.01225,0.0*
1,1,.006,-.0245,-.01225*
20,1,.006,-.0245,-.01225,-.02736,-.01184,0.0*
1,1,.006,-.02736,-.01184*
20,1,.006,-.02736,-.01184,-.03022,-.01062,0.0*
1,1,.006,-.03022,-.01062*
20,1,.006,-.03022,-.01062,-.03185,-.00898,0.0*
1,1,.006,-.03185,-.00898*
1,1,.006,-.00611,-.00123*
20,1,.006,-.00611,-.00123,.00695,-.00123,0.0*
1,1,.006,.00695,-.00123*
20,1,.006,.00695,-.00123,.00573,.00163,0.0*
1,1,.006,.00573,.00163*
20,1,.006,.00573,.00163,.00369,.00327,0.0*
1,1,.006,.00369,.00327*
20,1,.006,.00369,.00327,.00083,.00408,0.0*
1,1,.006,.00083,.00408*
20,1,.006,.00083,.00408,-.00203,.00367,0.0*
1,1,.006,-.00203,.00367*
20,1,.006,-.00203,.00367,-.00448,.00245,0.0*
1,1,.006,-.00448,.00245*
20,1,.006,-.00448,.00245,-.00611,-.00041,0.0*
1,1,.006,-.00611,-.00041*
20,1,.006,-.00611,-.00041,-.00693,-.00286,0.0*
1,1,.006,-.00693,-.00286*
20,1,.006,-.00693,-.00286,-.00693,-.00531,0.0*
1,1,.006,-.00693,-.00531*
20,1,.006,-.00693,-.00531,-.00611,-.00776,0.0*
1,1,.006,-.00611,-.00776*
20,1,.006,-.00611,-.00776,-.00407,-.01021,0.0*
1,1,.006,-.00407,-.01021*
20,1,.006,-.00407,-.01021,-.00162,-.01184,0.0*
1,1,.006,-.00162,-.01184*
20,1,.006,-.00162,-.01184,.00124,-.01225,0.0*
1,1,.006,.00124,-.01225*
20,1,.006,.00124,-.01225,.00409,-.01143,0.0*
1,1,.006,.00409,-.01143*
20,1,.006,.00409,-.01143,.00695,-.00898,0.0*
1,1,.006,.00695,-.00898*
1,1,.006,.01717,-.02042*
20,1,.006,.01717,-.02042,.01717,.00408,0.0*
1,1,.006,.01717,.00408*
1,1,.006,.01717,.00041*
20,1,.006,.01717,.00041,.01921,.00245,0.0*
1,1,.006,.01921,.00245*
20,1,.006,.01921,.00245,.02125,.00367,0.0*
1,1,.006,.02125,.00367*
20,1,.006,.02125,.00367,.02452,.00408,0.0*
1,1,.006,.02452,.00408*
20,1,.006,.02452,.00408,.02738,.00367,0.0*
1,1,.006,.02738,.00367*
20,1,.006,.02738,.00367,.03024,.00163,0.0*
1,1,.006,.03024,.00163*
20,1,.006,.03024,.00163,.03146,-.00123,0.0*
1,1,.006,.03146,-.00123*
20,1,.006,.03146,-.00123,.03187,-.00408,0.0*
1,1,.006,.03187,-.00408*
20,1,.006,.03187,-.00408,.03146,-.00694,0.0*
1,1,.006,.03146,-.00694*
20,1,.006,.03146,-.00694,.03024,-.0098,0.0*
1,1,.006,.03024,-.0098*
20,1,.006,.03024,-.0098,.02779,-.01143,0.0*
1,1,.006,.02779,-.01143*
20,1,.006,.02779,-.01143,.02452,-.01225,0.0*
1,1,.006,.02452,-.01225*
20,1,.006,.02452,-.01225,.02166,-.01184,0.0*
1,1,.006,.02166,-.01184*
20,1,.006,.02166,-.01184,.0188,-.01062,0.0*
1,1,.006,.0188,-.01062*
20,1,.006,.0188,-.01062,.01717,-.00898,0.0*
1,1,.006,.01717,-.00898*
%
%ADD32MACRO32*%
%AMMACRO37*
1,1,.006,0.0,.0395*
20,1,.006,0.0,.0395,.034208,-.01975,0.0*
1,1,.006,.034208,-.01975*
20,1,.006,.034208,-.01975,-.034208,-.01975,0.0*
1,1,.006,-.034208,-.01975*
20,1,.006,-.034208,-.01975,0.0,.0395,0.0*
1,1,.006,0.0,.0395*
1,1,.006,-.01244,.00622*
20,1,.006,-.01244,.00622,-.0141,.00581,0.0*
1,1,.006,-.0141,.00581*
20,1,.006,-.0141,.00581,-.01534,.00477,0.0*
1,1,.006,-.01534,.00477*
20,1,.006,-.01534,.00477,-.01617,.00352,0.0*
1,1,.006,-.01617,.00352*
20,1,.006,-.01617,.00352,-.01679,.00187,0.0*
1,1,.006,-.01679,.00187*
20,1,.006,-.01679,.00187,-.017,0.0,0.0*
1,1,.006,-.017,0.0*
20,1,.006,-.017,0.0,-.01679,-.00187,0.0*
1,1,.006,-.01679,-.00187*
20,1,.006,-.01679,-.00187,-.01617,-.00352,0.0*
1,1,.006,-.01617,-.00352*
20,1,.006,-.01617,-.00352,-.01534,-.00477,0.0*
1,1,.006,-.01534,-.00477*
20,1,.006,-.01534,-.00477,-.0141,-.00581,0.0*
1,1,.006,-.0141,-.00581*
20,1,.006,-.0141,-.00581,-.01244,-.00622,0.0*
1,1,.006,-.01244,-.00622*
20,1,.006,-.01244,-.00622,-.01078,-.00581,0.0*
1,1,.006,-.01078,-.00581*
20,1,.006,-.01078,-.00581,-.00954,-.00477,0.0*
1,1,.006,-.00954,-.00477*
20,1,.006,-.00954,-.00477,-.00871,-.00352,0.0*
1,1,.006,-.00871,-.00352*
20,1,.006,-.00871,-.00352,-.00809,-.00187,0.0*
1,1,.006,-.00809,-.00187*
20,1,.006,-.00809,-.00187,-.00788,0.0,0.0*
1,1,.006,-.00788,0.0*
20,1,.006,-.00788,0.0,-.00809,.00187,0.0*
1,1,.006,-.00809,.00187*
20,1,.006,-.00809,.00187,-.00871,.00352,0.0*
1,1,.006,-.00871,.00352*
20,1,.006,-.00871,.00352,-.00954,.00477,0.0*
1,1,.006,-.00954,.00477*
20,1,.006,-.00954,.00477,-.01078,.00581,0.0*
1,1,.006,-.01078,.00581*
20,1,.006,-.01078,.00581,-.01244,.00622,0.0*
1,1,.006,-.01244,.00622*
1,1,.006,-.0004,-.00622*
20,1,.006,-.0004,-.00622,.00001,-.00352,0.0*
1,1,.006,.00001,-.00352*
20,1,.006,.00001,-.00352,.00063,-.00124,0.0*
1,1,.006,.00063,-.00124*
20,1,.006,.00063,-.00124,.00146,.00083,0.0*
1,1,.006,.00146,.00083*
20,1,.006,.00146,.00083,.0025,.00311,0.0*
1,1,.006,.0025,.00311*
20,1,.006,.0025,.00311,.00416,.00622,0.0*
1,1,.006,.00416,.00622*
20,1,.006,.00416,.00622,-.00414,.00622,0.0*
1,1,.006,-.00414,.00622*
1,1,.006,.00894,-.00477*
20,1,.006,.00894,-.00477,.01039,-.00581,0.0*
1,1,.006,.01039,-.00581*
20,1,.006,.01039,-.00581,.01205,-.00622,0.0*
1,1,.006,.01205,-.00622*
20,1,.006,.01205,-.00622,.0137,-.00581,0.0*
1,1,.006,.0137,-.00581*
20,1,.006,.0137,-.00581,.01516,-.00456,0.0*
1,1,.006,.01516,-.00456*
20,1,.006,.01516,-.00456,.01619,-.0027,0.0*
1,1,.006,.01619,-.0027*
20,1,.006,.01619,-.0027,.01661,-.00083,0.0*
1,1,.006,.01661,-.00083*
20,1,.006,.01661,-.00083,.01661,.00145,0.0*
1,1,.006,.01661,.00145*
20,1,.006,.01661,.00145,.01619,.00332,0.0*
1,1,.006,.01619,.00332*
20,1,.006,.01619,.00332,.01516,.00498,0.0*
1,1,.006,.01516,.00498*
20,1,.006,.01516,.00498,.01391,.00581,0.0*
1,1,.006,.01391,.00581*
20,1,.006,.01391,.00581,.01246,.00622,0.0*
1,1,.006,.01246,.00622*
20,1,.006,.01246,.00622,.0108,.00581,0.0*
1,1,.006,.0108,.00581*
20,1,.006,.0108,.00581,.00956,.00498,0.0*
1,1,.006,.00956,.00498*
20,1,.006,.00956,.00498,.00873,.00373,0.0*
1,1,.006,.00873,.00373*
20,1,.006,.00873,.00373,.00831,.00207,0.0*
1,1,.006,.00831,.00207*
20,1,.006,.00831,.00207,.00873,.00062,0.0*
1,1,.006,.00873,.00062*
20,1,.006,.00873,.00062,.00976,-.00083,0.0*
1,1,.006,.00976,-.00083*
20,1,.006,.00976,-.00083,.01101,-.00166,0.0*
1,1,.006,.01101,-.00166*
20,1,.006,.01101,-.00166,.01246,-.00187,0.0*
1,1,.006,.01246,-.00187*
20,1,.006,.01246,-.00187,.01412,-.00145,0.0*
1,1,.006,.01412,-.00145*
20,1,.006,.01412,-.00145,.01536,-.00041,0.0*
1,1,.006,.01536,-.00041*
20,1,.006,.01536,-.00041,.01661,.00145,0.0*
1,1,.006,.01661,.00145*
%
%ADD37MACRO37*%
%AMMACRO33*
1,1,.006,.06,0.0*
20,1,.006,.06,0.0,0.0,-.06,0.0*
1,1,.006,0.0,-.06*
20,1,.006,0.0,-.06,-.06,0.0,0.0*
1,1,.006,-.06,0.0*
20,1,.006,-.06,0.0,0.0,.06,0.0*
1,1,.006,0.0,.06*
20,1,.006,0.0,.06,.06,0.0,0.0*
1,1,.006,.06,0.0*
1,1,.006,-.0294,-.035*
20,1,.006,-.0294,-.035,-.0294,.007,0.0*
1,1,.006,-.0294,.007*
1,1,.006,-.0294,.0007*
20,1,.006,-.0294,.0007,-.0329,.0042,0.0*
1,1,.006,-.0329,.0042*
20,1,.006,-.0329,.0042,-.0371,.0063,0.0*
1,1,.006,-.0371,.0063*
20,1,.006,-.0371,.0063,-.042,.007,0.0*
1,1,.006,-.042,.007*
20,1,.006,-.042,.007,-.0462,.0063,0.0*
1,1,.006,-.0462,.0063*
20,1,.006,-.0462,.0063,-.0511,.0028,0.0*
1,1,.006,-.0511,.0028*
20,1,.006,-.0511,.0028,-.0539,-.0021,0.0*
1,1,.006,-.0539,-.0021*
20,1,.006,-.0539,-.0021,-.0546,-.007,0.0*
1,1,.006,-.0546,-.007*
20,1,.006,-.0546,-.007,-.0539,-.0119,0.0*
1,1,.006,-.0539,-.0119*
20,1,.006,-.0539,-.0119,-.0511,-.0168,0.0*
1,1,.006,-.0511,-.0168*
20,1,.006,-.0511,-.0168,-.0462,-.0203,0.0*
1,1,.006,-.0462,-.0203*
20,1,.006,-.0462,-.0203,-.042,-.021,0.0*
1,1,.006,-.042,-.021*
20,1,.006,-.042,-.021,-.0371,-.0203,0.0*
1,1,.006,-.0371,-.0203*
20,1,.006,-.0371,-.0203,-.0329,-.0182,0.0*
1,1,.006,-.0329,-.0182*
20,1,.006,-.0329,-.0182,-.0294,-.0147,0.0*
1,1,.006,-.0294,-.0147*
1,1,.006,-.01749,.007*
20,1,.006,-.01749,.007,-.00909,-.021,0.0*
1,1,.006,-.00909,-.021*
20,1,.006,-.00909,-.021,.00001,.007,0.0*
1,1,.006,.00001,.007*
20,1,.006,.00001,.007,.00911,-.021,0.0*
1,1,.006,.00911,-.021*
20,1,.006,.00911,-.021,.01751,.007,0.0*
1,1,.006,.01751,.007*
1,1,.006,.02942,-.035*
20,1,.006,.02942,-.035,.02942,.007,0.0*
1,1,.006,.02942,.007*
1,1,.006,.02942,.0007*
20,1,.006,.02942,.0007,.03292,.0042,0.0*
1,1,.006,.03292,.0042*
20,1,.006,.03292,.0042,.03642,.0063,0.0*
1,1,.006,.03642,.0063*
20,1,.006,.03642,.0063,.04202,.007,0.0*
1,1,.006,.04202,.007*
20,1,.006,.04202,.007,.04692,.0063,0.0*
1,1,.006,.04692,.0063*
20,1,.006,.04692,.0063,.05182,.0028,0.0*
1,1,.006,.05182,.0028*
20,1,.006,.05182,.0028,.05392,-.0021,0.0*
1,1,.006,.05392,-.0021*
20,1,.006,.05392,-.0021,.05462,-.007,0.0*
1,1,.006,.05462,-.007*
20,1,.006,.05462,-.007,.05392,-.0119,0.0*
1,1,.006,.05392,-.0119*
20,1,.006,.05392,-.0119,.05182,-.0168,0.0*
1,1,.006,.05182,-.0168*
20,1,.006,.05182,-.0168,.04762,-.0196,0.0*
1,1,.006,.04762,-.0196*
20,1,.006,.04762,-.0196,.04202,-.021,0.0*
1,1,.006,.04202,-.021*
20,1,.006,.04202,-.021,.03712,-.0203,0.0*
1,1,.006,.03712,-.0203*
20,1,.006,.03712,-.0203,.03222,-.0182,0.0*
1,1,.006,.03222,-.0182*
20,1,.006,.03222,-.0182,.02942,-.0154,0.0*
1,1,.006,.02942,-.0154*
%
%ADD33MACRO33*%
%AMMACRO20*
1,1,.006,.197,.197*
20,1,.006,.197,.197,.197,-.197,0.0*
1,1,.006,.197,-.197*
20,1,.006,.197,-.197,-.197,-.197,0.0*
1,1,.006,-.197,-.197*
20,1,.006,-.197,-.197,-.197,.197,0.0*
1,1,.006,-.197,.197*
20,1,.006,-.197,.197,.197,.197,0.0*
1,1,.006,.197,.197*
1,1,.006,-.17237,-.0069*
20,1,.006,-.17237,-.0069,-.09883,-.0069,0.0*
1,1,.006,-.09883,-.0069*
20,1,.006,-.09883,-.0069,-.10572,.00919,0.0*
1,1,.006,-.10572,.00919*
20,1,.006,-.10572,.00919,-.11721,.01838,0.0*
1,1,.006,-.11721,.01838*
20,1,.006,-.11721,.01838,-.1333,.02298,0.0*
1,1,.006,-.1333,.02298*
20,1,.006,-.1333,.02298,-.14939,.02068,0.0*
1,1,.006,-.14939,.02068*
20,1,.006,-.14939,.02068,-.16318,.01379,0.0*
1,1,.006,-.16318,.01379*
20,1,.006,-.16318,.01379,-.17237,-.0023,0.0*
1,1,.006,-.17237,-.0023*
20,1,.006,-.17237,-.0023,-.17697,-.01609,0.0*
1,1,.006,-.17697,-.01609*
20,1,.006,-.17697,-.01609,-.17697,-.02988,0.0*
1,1,.006,-.17697,-.02988*
20,1,.006,-.17697,-.02988,-.17237,-.04367,0.0*
1,1,.006,-.17237,-.04367*
20,1,.006,-.17237,-.04367,-.16088,-.05746,0.0*
1,1,.006,-.16088,-.05746*
20,1,.006,-.16088,-.05746,-.14709,-.06665,0.0*
1,1,.006,-.14709,-.06665*
20,1,.006,-.14709,-.06665,-.131,-.06895,0.0*
1,1,.006,-.131,-.06895*
20,1,.006,-.131,-.06895,-.11492,-.06435,0.0*
1,1,.006,-.11492,-.06435*
20,1,.006,-.11492,-.06435,-.09883,-.05057,0.0*
1,1,.006,-.09883,-.05057*
1,1,.006,.00001,-.06895*
20,1,.006,.00001,-.06895,-.01378,-.06665,0.0*
1,1,.006,-.01378,-.06665*
20,1,.006,-.01378,-.06665,-.02757,-.05746,0.0*
1,1,.006,-.02757,-.05746*
20,1,.006,-.02757,-.05746,-.03677,-.04137,0.0*
1,1,.006,-.03677,-.04137*
20,1,.006,-.03677,-.04137,-.04136,-.02298,0.0*
1,1,.006,-.04136,-.02298*
20,1,.006,-.04136,-.02298,-.03677,-.0046,0.0*
1,1,.006,-.03677,-.0046*
20,1,.006,-.03677,-.0046,-.02757,.01149,0.0*
1,1,.006,-.02757,.01149*
20,1,.006,-.02757,.01149,-.01378,.02068,0.0*
1,1,.006,-.01378,.02068*
20,1,.006,-.01378,.02068,.00001,.02298,0.0*
1,1,.006,.00001,.02298*
20,1,.006,.00001,.02298,.0138,.02068,0.0*
1,1,.006,.0138,.02068*
20,1,.006,.0138,.02068,.02759,.01149,0.0*
1,1,.006,.02759,.01149*
20,1,.006,.02759,.01149,.03678,-.0046,0.0*
1,1,.006,.03678,-.0046*
20,1,.006,.03678,-.0046,.03908,-.02298,0.0*
1,1,.006,.03908,-.02298*
20,1,.006,.03908,-.02298,.03678,-.04137,0.0*
1,1,.006,.03678,-.04137*
20,1,.006,.03678,-.04137,.02759,-.05746,0.0*
1,1,.006,.02759,-.05746*
20,1,.006,.02759,-.05746,.0138,-.06665,0.0*
1,1,.006,.0138,-.06665*
20,1,.006,.0138,-.06665,.00001,-.06895,0.0*
1,1,.006,.00001,-.06895*
1,1,.006,.10574,-.06895*
20,1,.006,.10574,-.06895,.10574,.02298,0.0*
1,1,.006,.10574,.02298*
1,1,.006,.10574,.0046*
20,1,.006,.10574,.0046,.11723,.01379,0.0*
1,1,.006,.11723,.01379*
20,1,.006,.11723,.01379,.12873,.02068,0.0*
1,1,.006,.12873,.02068*
20,1,.006,.12873,.02068,.14482,.02298,0.0*
1,1,.006,.14482,.02298*
20,1,.006,.14482,.02298,.1563,.02068,0.0*
1,1,.006,.1563,.02068*
20,1,.006,.1563,.02068,.1701,.01379,0.0*
1,1,.006,.1701,.01379*
%
%ADD20MACRO20*%
%AMMACRO12*
1,1,.006,.045771,-.1105*
20,1,.006,.045771,-.1105,-.045771,-.1105,0.0*
1,1,.006,-.045771,-.1105*
20,1,.006,-.045771,-.1105,-.1105,-.045771,0.0*
1,1,.006,-.1105,-.045771*
20,1,.006,-.1105,-.045771,-.1105,.045771,0.0*
1,1,.006,-.1105,.045771*
20,1,.006,-.1105,.045771,-.045771,.1105,0.0*
1,1,.006,-.045771,.1105*
20,1,.006,-.045771,.1105,.045771,.1105,0.0*
1,1,.006,.045771,.1105*
20,1,.006,.045771,.1105,.1105,.045771,0.0*
1,1,.006,.1105,.045771*
20,1,.006,.1105,.045771,.1105,-.045771,0.0*
1,1,.006,.1105,-.045771*
20,1,.006,.1105,-.045771,.045771,-.1105,0.0*
1,1,.006,.045771,-.1105*
1,1,.006,-.08657,.02192*
20,1,.006,-.08657,.02192,-.07999,.0285,0.0*
1,1,.006,-.07999,.0285*
20,1,.006,-.07999,.0285,-.07232,.03178,0.0*
1,1,.006,-.07232,.03178*
20,1,.006,-.07232,.03178,-.06355,.03288,0.0*
1,1,.006,-.06355,.03288*
20,1,.006,-.06355,.03288,-.05259,.03069,0.0*
1,1,.006,-.05259,.03069*
20,1,.006,-.05259,.03069,-.04492,.02521,0.0*
1,1,.006,-.04492,.02521*
20,1,.006,-.04492,.02521,-.04273,.01864,0.0*
1,1,.006,-.04273,.01864*
20,1,.006,-.04273,.01864,-.04383,.01206,0.0*
1,1,.006,-.04383,.01206*
20,1,.006,-.04383,.01206,-.04821,.00658,0.0*
1,1,.006,-.04821,.00658*
20,1,.006,-.04821,.00658,-.07013,-.00438,0.0*
1,1,.006,-.07013,-.00438*
20,1,.006,-.07013,-.00438,-.07999,-.01205,0.0*
1,1,.006,-.07999,-.01205*
20,1,.006,-.07999,-.01205,-.08657,-.02301,0.0*
1,1,.006,-.08657,-.02301*
20,1,.006,-.08657,-.02301,-.08876,-.03287,0.0*
1,1,.006,-.08876,-.03287*
20,1,.006,-.08876,-.03287,-.04273,-.03287,0.0*
1,1,.006,-.04273,-.03287*
1,1,.006,-.02081,.02192*
20,1,.006,-.02081,.02192,-.01423,.0285,0.0*
1,1,.006,-.01423,.0285*
20,1,.006,-.01423,.0285,-.00656,.03178,0.0*
1,1,.006,-.00656,.03178*
20,1,.006,-.00656,.03178,.00221,.03288,0.0*
1,1,.006,.00221,.03288*
20,1,.006,.00221,.03288,.01317,.03069,0.0*
1,1,.006,.01317,.03069*
20,1,.006,.01317,.03069,.02084,.02521,0.0*
1,1,.006,.02084,.02521*
20,1,.006,.02084,.02521,.02303,.01864,0.0*
1,1,.006,.02303,.01864*
20,1,.006,.02303,.01864,.02193,.01206,0.0*
1,1,.006,.02193,.01206*
20,1,.006,.02193,.01206,.01755,.00658,0.0*
1,1,.006,.01755,.00658*
20,1,.006,.01755,.00658,-.00437,-.00438,0.0*
1,1,.006,-.00437,-.00438*
20,1,.006,-.00437,-.00438,-.01423,-.01205,0.0*
1,1,.006,-.01423,-.01205*
20,1,.006,-.01423,-.01205,-.02081,-.02301,0.0*
1,1,.006,-.02081,-.02301*
20,1,.006,-.02081,-.02301,-.023,-.03287,0.0*
1,1,.006,-.023,-.03287*
20,1,.006,-.023,-.03287,.02303,-.03287,0.0*
1,1,.006,.02303,-.03287*
1,1,.006,.06577,-.03287*
20,1,.006,.06577,-.03287,.06577,.03288,0.0*
1,1,.006,.06577,.03288*
20,1,.006,.06577,.03288,.05262,.01973,0.0*
1,1,.006,.05262,.01973*
1,1,.006,.05262,-.03287*
20,1,.006,.05262,-.03287,.07892,-.03287,0.0*
1,1,.006,.07892,-.03287*
%
%ADD12MACRO12*%
%AMMACRO35*
1,1,.006,.044942,-.1085*
20,1,.006,.044942,-.1085,-.044942,-.1085,0.0*
1,1,.006,-.044942,-.1085*
20,1,.006,-.044942,-.1085,-.1085,-.044942,0.0*
1,1,.006,-.1085,-.044942*
20,1,.006,-.1085,-.044942,-.1085,.044942,0.0*
1,1,.006,-.1085,.044942*
20,1,.006,-.1085,.044942,-.044942,.1085,0.0*
1,1,.006,-.044942,.1085*
20,1,.006,-.044942,.1085,.044942,.1085,0.0*
1,1,.006,.044942,.1085*
20,1,.006,.044942,.1085,.1085,.044942,0.0*
1,1,.006,.1085,.044942*
20,1,.006,.1085,.044942,.1085,-.044942,0.0*
1,1,.006,.1085,-.044942*
20,1,.006,.1085,-.044942,.044942,-.1085,0.0*
1,1,.006,.044942,-.1085*
1,1,.006,-.09146,.01076*
20,1,.006,-.09146,.01076,-.07855,-.03228,0.0*
1,1,.006,-.07855,-.03228*
20,1,.006,-.07855,-.03228,-.06456,.01076,0.0*
1,1,.006,-.06456,.01076*
20,1,.006,-.06456,.01076,-.05057,-.03228,0.0*
1,1,.006,-.05057,-.03228*
20,1,.006,-.05057,-.03228,-.03766,.01076,0.0*
1,1,.006,-.03766,.01076*
1,1,.006,.01938,-.0538*
20,1,.006,.01938,-.0538,.01938,.01076,0.0*
1,1,.006,.01938,.01076*
1,1,.006,.01938,.00108*
20,1,.006,.01938,.00108,.014,.00646,0.0*
1,1,.006,.014,.00646*
20,1,.006,.014,.00646,.00754,.00968,0.0*
1,1,.006,.00754,.00968*
20,1,.006,.00754,.00968,.00001,.01076,0.0*
1,1,.006,.00001,.01076*
20,1,.006,.00001,.01076,-.00645,.00968,0.0*
1,1,.006,-.00645,.00968*
20,1,.006,-.00645,.00968,-.01398,.0043,0.0*
1,1,.006,-.01398,.0043*
20,1,.006,-.01398,.0043,-.01828,-.00323,0.0*
1,1,.006,-.01828,-.00323*
20,1,.006,-.01828,-.00323,-.01936,-.01076,0.0*
1,1,.006,-.01936,-.01076*
20,1,.006,-.01936,-.01076,-.01828,-.01829,0.0*
1,1,.006,-.01828,-.01829*
20,1,.006,-.01828,-.01829,-.01398,-.02583,0.0*
1,1,.006,-.01398,-.02583*
20,1,.006,-.01398,-.02583,-.00645,-.0312,0.0*
1,1,.006,-.00645,-.0312*
20,1,.006,-.00645,-.0312,.00001,-.03228,0.0*
1,1,.006,.00001,-.03228*
20,1,.006,.00001,-.03228,.00754,-.0312,0.0*
1,1,.006,.00754,-.0312*
20,1,.006,.00754,-.0312,.014,-.02798,0.0*
1,1,.006,.014,-.02798*
20,1,.006,.014,-.02798,.01938,-.0226,0.0*
1,1,.006,.01938,-.0226*
1,1,.006,.04629,.01076*
20,1,.006,.04629,.01076,.04629,-.01937,0.0*
1,1,.006,.04629,-.01937*
20,1,.006,.04629,-.01937,.05059,-.0269,0.0*
1,1,.006,.05059,-.0269*
20,1,.006,.05059,-.0269,.05705,-.0312,0.0*
1,1,.006,.05705,-.0312*
20,1,.006,.05705,-.0312,.06458,-.03228,0.0*
1,1,.006,.06458,-.03228*
20,1,.006,.06458,-.03228,.07211,-.0312,0.0*
1,1,.006,.07211,-.0312*
20,1,.006,.07211,-.0312,.07857,-.0269,0.0*
1,1,.006,.07857,-.0269*
20,1,.006,.07857,-.0269,.08287,-.01937,0.0*
1,1,.006,.08287,-.01937*
1,1,.006,.08287,-.03228*
20,1,.006,.08287,-.03228,.08287,.01076,0.0*
1,1,.006,.08287,.01076*
%
%ADD35MACRO35*%
%AMMACRO13*
1,1,.006,.035,0.0*
20,1,.006,.035,0.0,.034468,-.006078,0.0*
1,1,.006,.034468,-.006078*
20,1,.006,.034468,-.006078,.032889,-.011971,0.0*
1,1,.006,.032889,-.011971*
20,1,.006,.032889,-.011971,.030311,-.0175,0.0*
1,1,.006,.030311,-.0175*
20,1,.006,.030311,-.0175,.026812,-.022498,0.0*
1,1,.006,.026812,-.022498*
20,1,.006,.026812,-.022498,.022498,-.026812,0.0*
1,1,.006,.022498,-.026812*
20,1,.006,.022498,-.026812,.0175,-.030311,0.0*
1,1,.006,.0175,-.030311*
20,1,.006,.0175,-.030311,.011971,-.032889,0.0*
1,1,.006,.011971,-.032889*
20,1,.006,.011971,-.032889,.006078,-.034468,0.0*
1,1,.006,.006078,-.034468*
20,1,.006,.006078,-.034468,0.0,-.035,0.0*
1,1,.006,0.0,-.035*
20,1,.006,0.0,-.035,-.006078,-.034468,0.0*
1,1,.006,-.006078,-.034468*
20,1,.006,-.006078,-.034468,-.011971,-.032889,0.0*
1,1,.006,-.011971,-.032889*
20,1,.006,-.011971,-.032889,-.0175,-.030311,0.0*
1,1,.006,-.0175,-.030311*
20,1,.006,-.0175,-.030311,-.022498,-.026812,0.0*
1,1,.006,-.022498,-.026812*
20,1,.006,-.022498,-.026812,-.026812,-.022498,0.0*
1,1,.006,-.026812,-.022498*
20,1,.006,-.026812,-.022498,-.030311,-.0175,0.0*
1,1,.006,-.030311,-.0175*
20,1,.006,-.030311,-.0175,-.032889,-.011971,0.0*
1,1,.006,-.032889,-.011971*
20,1,.006,-.032889,-.011971,-.034468,-.006078,0.0*
1,1,.006,-.034468,-.006078*
20,1,.006,-.034468,-.006078,-.035,0.0,0.0*
1,1,.006,-.035,0.0*
20,1,.006,-.035,0.0,-.034468,.006078,0.0*
1,1,.006,-.034468,.006078*
20,1,.006,-.034468,.006078,-.032889,.011971,0.0*
1,1,.006,-.032889,.011971*
20,1,.006,-.032889,.011971,-.030311,.0175,0.0*
1,1,.006,-.030311,.0175*
20,1,.006,-.030311,.0175,-.026812,.022498,0.0*
1,1,.006,-.026812,.022498*
20,1,.006,-.026812,.022498,-.022498,.026812,0.0*
1,1,.006,-.022498,.026812*
20,1,.006,-.022498,.026812,-.0175,.030311,0.0*
1,1,.006,-.0175,.030311*
20,1,.006,-.0175,.030311,-.011971,.032889,0.0*
1,1,.006,-.011971,.032889*
20,1,.006,-.011971,.032889,-.006078,.034468,0.0*
1,1,.006,-.006078,.034468*
20,1,.006,-.006078,.034468,0.0,.035,0.0*
1,1,.006,0.0,.035*
20,1,.006,0.0,.035,.006078,.034468,0.0*
1,1,.006,.006078,.034468*
20,1,.006,.006078,.034468,.011971,.032889,0.0*
1,1,.006,.011971,.032889*
20,1,.006,.011971,.032889,.0175,.030311,0.0*
1,1,.006,.0175,.030311*
20,1,.006,.0175,.030311,.022498,.026812,0.0*
1,1,.006,.022498,.026812*
20,1,.006,.022498,.026812,.026812,.022498,0.0*
1,1,.006,.026812,.022498*
20,1,.006,.026812,.022498,.030311,.0175,0.0*
1,1,.006,.030311,.0175*
20,1,.006,.030311,.0175,.032889,.011971,0.0*
1,1,.006,.032889,.011971*
20,1,.006,.032889,.011971,.034468,.006078,0.0*
1,1,.006,.034468,.006078*
20,1,.006,.034468,.006078,.035,0.0,0.0*
1,1,.006,.035,0.0*
1,1,.006,-.02082,.01041*
20,1,.006,-.02082,.01041,-.02082,-.01041,0.0*
1,1,.006,-.02082,-.01041*
1,1,.006,-.0288,.01041*
20,1,.006,-.0288,.01041,-.01284,.01041,0.0*
1,1,.006,-.01284,.01041*
1,1,.006,-.00693,-.01041*
20,1,.006,-.00693,-.01041,-.00693,.01041,0.0*
1,1,.006,-.00693,.01041*
20,1,.006,-.00693,.01041,.0014,.01041,0.0*
1,1,.006,.0014,.01041*
20,1,.006,.0014,.01041,.00417,.00937,0.0*
1,1,.006,.00417,.00937*
20,1,.006,.00417,.00937,.00626,.00694,0.0*
1,1,.006,.00626,.00694*
20,1,.006,.00626,.00694,.00695,.00416,0.0*
1,1,.006,.00695,.00416*
20,1,.006,.00695,.00416,.00626,.00139,0.0*
1,1,.006,.00626,.00139*
20,1,.006,.00626,.00139,.00452,-.00069,0.0*
1,1,.006,.00452,-.00069*
20,1,.006,.00452,-.00069,.0014,-.00174,0.0*
1,1,.006,.0014,-.00174*
20,1,.006,.0014,-.00174,-.00693,-.00174,0.0*
1,1,.006,-.00693,-.00174*
1,1,.006,.01216,.01041*
20,1,.006,.01216,.01041,.02084,-.01041,0.0*
1,1,.006,.02084,-.01041*
20,1,.006,.02084,-.01041,.02952,.01041,0.0*
1,1,.006,.02952,.01041*
%
%ADD13MACRO13*%
%AMMACRO34*
1,1,.006,.035,.035*
20,1,.006,.035,.035,.035,-.035,0.0*
1,1,.006,.035,-.035*
20,1,.006,.035,-.035,-.035,-.035,0.0*
1,1,.006,-.035,-.035*
20,1,.006,-.035,-.035,-.035,.035,0.0*
1,1,.006,-.035,.035*
20,1,.006,-.035,.035,.035,.035,0.0*
1,1,.006,.035,.035*
1,1,.006,-.0245,.01225*
20,1,.006,-.0245,.01225,-.02777,.01143,0.0*
1,1,.006,-.02777,.01143*
20,1,.006,-.02777,.01143,-.03022,.00939,0.0*
1,1,.006,-.03022,.00939*
20,1,.006,-.03022,.00939,-.03185,.00694,0.0*
1,1,.006,-.03185,.00694*
20,1,.006,-.03185,.00694,-.03308,.00367,0.0*
1,1,.006,-.03308,.00367*
20,1,.006,-.03308,.00367,-.03348,0.0,0.0*
1,1,.006,-.03348,0.0*
20,1,.006,-.03348,0.0,-.03308,-.00368,0.0*
1,1,.006,-.03308,-.00368*
20,1,.006,-.03308,-.00368,-.03185,-.00694,0.0*
1,1,.006,-.03185,-.00694*
20,1,.006,-.03185,-.00694,-.03022,-.00939,0.0*
1,1,.006,-.03022,-.00939*
20,1,.006,-.03022,-.00939,-.02777,-.01143,0.0*
1,1,.006,-.02777,-.01143*
20,1,.006,-.02777,-.01143,-.0245,-.01225,0.0*
1,1,.006,-.0245,-.01225*
20,1,.006,-.0245,-.01225,-.02123,-.01143,0.0*
1,1,.006,-.02123,-.01143*
20,1,.006,-.02123,-.01143,-.01878,-.00939,0.0*
1,1,.006,-.01878,-.00939*
20,1,.006,-.01878,-.00939,-.01715,-.00694,0.0*
1,1,.006,-.01715,-.00694*
20,1,.006,-.01715,-.00694,-.01592,-.00368,0.0*
1,1,.006,-.01592,-.00368*
20,1,.006,-.01592,-.00368,-.01552,0.0,0.0*
1,1,.006,-.01552,0.0*
20,1,.006,-.01552,0.0,-.01592,.00367,0.0*
1,1,.006,-.01592,.00367*
20,1,.006,-.01592,.00367,-.01715,.00694,0.0*
1,1,.006,-.01715,.00694*
20,1,.006,-.01715,.00694,-.01878,.00939,0.0*
1,1,.006,-.01878,.00939*
20,1,.006,-.01878,.00939,-.02123,.01143,0.0*
1,1,.006,-.02123,.01143*
20,1,.006,-.02123,.01143,-.0245,.01225,0.0*
1,1,.006,-.0245,.01225*
1,1,.006,-.00775,.00817*
20,1,.006,-.00775,.00817,-.0053,.01062,0.0*
1,1,.006,-.0053,.01062*
20,1,.006,-.0053,.01062,-.00244,.01184,0.0*
1,1,.006,-.00244,.01184*
20,1,.006,-.00244,.01184,.00083,.01225,0.0*
1,1,.006,.00083,.01225*
20,1,.006,.00083,.01225,.00491,.01143,0.0*
1,1,.006,.00491,.01143*
20,1,.006,.00491,.01143,.00777,.00939,0.0*
1,1,.006,.00777,.00939*
20,1,.006,.00777,.00939,.00859,.00694,0.0*
1,1,.006,.00859,.00694*
20,1,.006,.00859,.00694,.00818,.00449,0.0*
1,1,.006,.00818,.00449*
20,1,.006,.00818,.00449,.00654,.00245,0.0*
1,1,.006,.00654,.00245*
20,1,.006,.00654,.00245,-.00162,-.00163,0.0*
1,1,.006,-.00162,-.00163*
20,1,.006,-.00162,-.00163,-.0053,-.00449,0.0*
1,1,.006,-.0053,-.00449*
20,1,.006,-.0053,-.00449,-.00775,-.00858,0.0*
1,1,.006,-.00775,-.00858*
20,1,.006,-.00775,-.00858,-.00857,-.01225,0.0*
1,1,.006,-.00857,-.01225*
20,1,.006,-.00857,-.01225,.00859,-.01225,0.0*
1,1,.006,.00859,-.01225*
1,1,.006,.01676,.00817*
20,1,.006,.01676,.00817,.01921,.01062,0.0*
1,1,.006,.01921,.01062*
20,1,.006,.01921,.01062,.02207,.01184,0.0*
1,1,.006,.02207,.01184*
20,1,.006,.02207,.01184,.02534,.01225,0.0*
1,1,.006,.02534,.01225*
20,1,.006,.02534,.01225,.02942,.01143,0.0*
1,1,.006,.02942,.01143*
20,1,.006,.02942,.01143,.03228,.00939,0.0*
1,1,.006,.03228,.00939*
20,1,.006,.03228,.00939,.0331,.00694,0.0*
1,1,.006,.0331,.00694*
20,1,.006,.0331,.00694,.03269,.00449,0.0*
1,1,.006,.03269,.00449*
20,1,.006,.03269,.00449,.03105,.00245,0.0*
1,1,.006,.03105,.00245*
20,1,.006,.03105,.00245,.02289,-.00163,0.0*
1,1,.006,.02289,-.00163*
20,1,.006,.02289,-.00163,.01921,-.00449,0.0*
1,1,.006,.01921,-.00449*
20,1,.006,.01921,-.00449,.01676,-.00858,0.0*
1,1,.006,.01676,-.00858*
20,1,.006,.01676,-.00858,.01594,-.01225,0.0*
1,1,.006,.01594,-.01225*
20,1,.006,.01594,-.01225,.0331,-.01225,0.0*
1,1,.006,.0331,-.01225*
%
%ADD34MACRO34*%
%AMMACRO27*
1,1,.006,.035,.035*
20,1,.006,.035,.035,.035,-.035,0.0*
1,1,.006,.035,-.035*
20,1,.006,.035,-.035,-.035,-.035,0.0*
1,1,.006,-.035,-.035*
20,1,.006,-.035,-.035,-.035,.035,0.0*
1,1,.006,-.035,.035*
20,1,.006,-.035,.035,.035,.035,0.0*
1,1,.006,.035,.035*
1,1,.006,-.0245,.01225*
20,1,.006,-.0245,.01225,-.02777,.01143,0.0*
1,1,.006,-.02777,.01143*
20,1,.006,-.02777,.01143,-.03022,.00939,0.0*
1,1,.006,-.03022,.00939*
20,1,.006,-.03022,.00939,-.03185,.00694,0.0*
1,1,.006,-.03185,.00694*
20,1,.006,-.03185,.00694,-.03308,.00367,0.0*
1,1,.006,-.03308,.00367*
20,1,.006,-.03308,.00367,-.03348,0.0,0.0*
1,1,.006,-.03348,0.0*
20,1,.006,-.03348,0.0,-.03308,-.00368,0.0*
1,1,.006,-.03308,-.00368*
20,1,.006,-.03308,-.00368,-.03185,-.00694,0.0*
1,1,.006,-.03185,-.00694*
20,1,.006,-.03185,-.00694,-.03022,-.00939,0.0*
1,1,.006,-.03022,-.00939*
20,1,.006,-.03022,-.00939,-.02777,-.01143,0.0*
1,1,.006,-.02777,-.01143*
20,1,.006,-.02777,-.01143,-.0245,-.01225,0.0*
1,1,.006,-.0245,-.01225*
20,1,.006,-.0245,-.01225,-.02123,-.01143,0.0*
1,1,.006,-.02123,-.01143*
20,1,.006,-.02123,-.01143,-.01878,-.00939,0.0*
1,1,.006,-.01878,-.00939*
20,1,.006,-.01878,-.00939,-.01715,-.00694,0.0*
1,1,.006,-.01715,-.00694*
20,1,.006,-.01715,-.00694,-.01592,-.00368,0.0*
1,1,.006,-.01592,-.00368*
20,1,.006,-.01592,-.00368,-.01552,0.0,0.0*
1,1,.006,-.01552,0.0*
20,1,.006,-.01552,0.0,-.01592,.00367,0.0*
1,1,.006,-.01592,.00367*
20,1,.006,-.01592,.00367,-.01715,.00694,0.0*
1,1,.006,-.01715,.00694*
20,1,.006,-.01715,.00694,-.01878,.00939,0.0*
1,1,.006,-.01878,.00939*
20,1,.006,-.01878,.00939,-.02123,.01143,0.0*
1,1,.006,-.02123,.01143*
20,1,.006,-.02123,.01143,-.0245,.01225,0.0*
1,1,.006,-.0245,.01225*
1,1,.006,.00491,-.01225*
20,1,.006,.00491,-.01225,.00491,.01225,0.0*
1,1,.006,.00491,.01225*
20,1,.006,.00491,.01225,-.0102,-.00531,0.0*
1,1,.006,-.0102,-.00531*
20,1,.006,-.0102,-.00531,.01022,-.00531,0.0*
1,1,.006,.01022,-.00531*
1,1,.006,.02452,.01225*
20,1,.006,.02452,.01225,.02125,.01143,0.0*
1,1,.006,.02125,.01143*
20,1,.006,.02125,.01143,.0188,.00939,0.0*
1,1,.006,.0188,.00939*
20,1,.006,.0188,.00939,.01717,.00694,0.0*
1,1,.006,.01717,.00694*
20,1,.006,.01717,.00694,.01594,.00367,0.0*
1,1,.006,.01594,.00367*
20,1,.006,.01594,.00367,.01554,0.0,0.0*
1,1,.006,.01554,0.0*
20,1,.006,.01554,0.0,.01594,-.00368,0.0*
1,1,.006,.01594,-.00368*
20,1,.006,.01594,-.00368,.01717,-.00694,0.0*
1,1,.006,.01717,-.00694*
20,1,.006,.01717,-.00694,.0188,-.00939,0.0*
1,1,.006,.0188,-.00939*
20,1,.006,.0188,-.00939,.02125,-.01143,0.0*
1,1,.006,.02125,-.01143*
20,1,.006,.02125,-.01143,.02452,-.01225,0.0*
1,1,.006,.02452,-.01225*
20,1,.006,.02452,-.01225,.02779,-.01143,0.0*
1,1,.006,.02779,-.01143*
20,1,.006,.02779,-.01143,.03024,-.00939,0.0*
1,1,.006,.03024,-.00939*
20,1,.006,.03024,-.00939,.03187,-.00694,0.0*
1,1,.006,.03187,-.00694*
20,1,.006,.03187,-.00694,.0331,-.00368,0.0*
1,1,.006,.0331,-.00368*
20,1,.006,.0331,-.00368,.0335,0.0,0.0*
1,1,.006,.0335,0.0*
20,1,.006,.0335,0.0,.0331,.00367,0.0*
1,1,.006,.0331,.00367*
20,1,.006,.0331,.00367,.03187,.00694,0.0*
1,1,.006,.03187,.00694*
20,1,.006,.03187,.00694,.03024,.00939,0.0*
1,1,.006,.03024,.00939*
20,1,.006,.03024,.00939,.02779,.01143,0.0*
1,1,.006,.02779,.01143*
20,1,.006,.02779,.01143,.02452,.01225,0.0*
1,1,.006,.02452,.01225*
%
%ADD27MACRO27*%
%AMMACRO40*
1,1,.006,.035,.035*
20,1,.006,.035,.035,.035,-.035,0.0*
1,1,.006,.035,-.035*
20,1,.006,.035,-.035,-.035,-.035,0.0*
1,1,.006,-.035,-.035*
20,1,.006,-.035,-.035,-.035,.035,0.0*
1,1,.006,-.035,.035*
20,1,.006,-.035,.035,.035,.035,0.0*
1,1,.006,.035,.035*
1,1,.006,-.0245,.01225*
20,1,.006,-.0245,.01225,-.02777,.01143,0.0*
1,1,.006,-.02777,.01143*
20,1,.006,-.02777,.01143,-.03022,.00939,0.0*
1,1,.006,-.03022,.00939*
20,1,.006,-.03022,.00939,-.03185,.00694,0.0*
1,1,.006,-.03185,.00694*
20,1,.006,-.03185,.00694,-.03308,.00367,0.0*
1,1,.006,-.03308,.00367*
20,1,.006,-.03308,.00367,-.03348,0.0,0.0*
1,1,.006,-.03348,0.0*
20,1,.006,-.03348,0.0,-.03308,-.00368,0.0*
1,1,.006,-.03308,-.00368*
20,1,.006,-.03308,-.00368,-.03185,-.00694,0.0*
1,1,.006,-.03185,-.00694*
20,1,.006,-.03185,-.00694,-.03022,-.00939,0.0*
1,1,.006,-.03022,-.00939*
20,1,.006,-.03022,-.00939,-.02777,-.01143,0.0*
1,1,.006,-.02777,-.01143*
20,1,.006,-.02777,-.01143,-.0245,-.01225,0.0*
1,1,.006,-.0245,-.01225*
20,1,.006,-.0245,-.01225,-.02123,-.01143,0.0*
1,1,.006,-.02123,-.01143*
20,1,.006,-.02123,-.01143,-.01878,-.00939,0.0*
1,1,.006,-.01878,-.00939*
20,1,.006,-.01878,-.00939,-.01715,-.00694,0.0*
1,1,.006,-.01715,-.00694*
20,1,.006,-.01715,-.00694,-.01592,-.00368,0.0*
1,1,.006,-.01592,-.00368*
20,1,.006,-.01592,-.00368,-.01552,0.0,0.0*
1,1,.006,-.01552,0.0*
20,1,.006,-.01552,0.0,-.01592,.00367,0.0*
1,1,.006,-.01592,.00367*
20,1,.006,-.01592,.00367,-.01715,.00694,0.0*
1,1,.006,-.01715,.00694*
20,1,.006,-.01715,.00694,-.01878,.00939,0.0*
1,1,.006,-.01878,.00939*
20,1,.006,-.01878,.00939,-.02123,.01143,0.0*
1,1,.006,-.02123,.01143*
20,1,.006,-.02123,.01143,-.0245,.01225,0.0*
1,1,.006,-.0245,.01225*
1,1,.006,-.00897,-.00735*
20,1,.006,-.00897,-.00735,-.00652,-.01021,0.0*
1,1,.006,-.00652,-.01021*
20,1,.006,-.00652,-.01021,-.00326,-.01184,0.0*
1,1,.006,-.00326,-.01184*
20,1,.006,-.00326,-.01184,.00042,-.01225,0.0*
1,1,.006,.00042,-.01225*
20,1,.006,.00042,-.01225,.00369,-.01184,0.0*
1,1,.006,.00369,-.01184*
20,1,.006,.00369,-.01184,.00695,-.0098,0.0*
1,1,.006,.00695,-.0098*
20,1,.006,.00695,-.0098,.00899,-.00735,0.0*
1,1,.006,.00899,-.00735*
20,1,.006,.00899,-.00735,.0094,-.0049,0.0*
1,1,.006,.0094,-.0049*
20,1,.006,.0094,-.0049,.00859,-.00204,0.0*
1,1,.006,.00859,-.00204*
20,1,.006,.00859,-.00204,.00573,0.0,0.0*
1,1,.006,.00573,0.0*
20,1,.006,.00573,0.0,.00287,.00082,0.0*
1,1,.006,.00287,.00082*
20,1,.006,.00287,.00082,-.00081,.00082,0.0*
1,1,.006,-.00081,.00082*
1,1,.006,.00287,.00082*
20,1,.006,.00287,.00082,.00532,.00204,0.0*
1,1,.006,.00532,.00204*
20,1,.006,.00532,.00204,.00736,.00408,0.0*
1,1,.006,.00736,.00408*
20,1,.006,.00736,.00408,.00818,.00653,0.0*
1,1,.006,.00818,.00653*
20,1,.006,.00818,.00653,.00736,.00898,0.0*
1,1,.006,.00736,.00898*
20,1,.006,.00736,.00898,.00532,.01102,0.0*
1,1,.006,.00532,.01102*
20,1,.006,.00532,.01102,.00164,.01225,0.0*
1,1,.006,.00164,.01225*
20,1,.006,.00164,.01225,-.00203,.01184,0.0*
1,1,.006,-.00203,.01184*
20,1,.006,-.00203,.01184,-.00571,.01021,0.0*
1,1,.006,-.00571,.01021*
1,1,.006,.01676,.00817*
20,1,.006,.01676,.00817,.01921,.01062,0.0*
1,1,.006,.01921,.01062*
20,1,.006,.01921,.01062,.02207,.01184,0.0*
1,1,.006,.02207,.01184*
20,1,.006,.02207,.01184,.02534,.01225,0.0*
1,1,.006,.02534,.01225*
20,1,.006,.02534,.01225,.02942,.01143,0.0*
1,1,.006,.02942,.01143*
20,1,.006,.02942,.01143,.03228,.00939,0.0*
1,1,.006,.03228,.00939*
20,1,.006,.03228,.00939,.0331,.00694,0.0*
1,1,.006,.0331,.00694*
20,1,.006,.0331,.00694,.03269,.00449,0.0*
1,1,.006,.03269,.00449*
20,1,.006,.03269,.00449,.03105,.00245,0.0*
1,1,.006,.03105,.00245*
20,1,.006,.03105,.00245,.02289,-.00163,0.0*
1,1,.006,.02289,-.00163*
20,1,.006,.02289,-.00163,.01921,-.00449,0.0*
1,1,.006,.01921,-.00449*
20,1,.006,.01921,-.00449,.01676,-.00858,0.0*
1,1,.006,.01676,-.00858*
20,1,.006,.01676,-.00858,.01594,-.01225,0.0*
1,1,.006,.01594,-.01225*
20,1,.006,.01594,-.01225,.0331,-.01225,0.0*
1,1,.006,.0331,-.01225*
%
%ADD40MACRO40*%
%AMMACRO36*
1,1,.006,-.166,-.083*
20,1,.006,-.166,-.083,-.166,.083,0.0*
1,1,.006,-.166,.083*
20,1,.006,-.166,.083,-.1992,.0498,0.0*
1,1,.006,-.1992,.0498*
1,1,.006,-.1992,-.083*
20,1,.006,-.1992,-.083,-.1328,-.083,0.0*
1,1,.006,-.1328,-.083*
1,1,.006,-.05256,-.01384*
20,1,.006,-.05256,-.01384,-.03319,.00553,0.0*
1,1,.006,-.03319,.00553*
20,1,.006,-.03319,.00553,-.01659,.0166,0.0*
1,1,.006,-.01659,.0166*
20,1,.006,-.01659,.0166,.00554,.02213,0.0*
1,1,.006,.00554,.02213*
20,1,.006,.00554,.02213,.02491,.0166,0.0*
1,1,.006,.02491,.0166*
20,1,.006,.02491,.0166,.03874,.00553,0.0*
1,1,.006,.03874,.00553*
20,1,.006,.03874,.00553,.04981,-.01107,0.0*
1,1,.006,.04981,-.01107*
20,1,.006,.04981,-.01107,.05258,-.03043,0.0*
1,1,.006,.05258,-.03043*
20,1,.006,.05258,-.03043,.04981,-.04704,0.0*
1,1,.006,.04981,-.04704*
20,1,.006,.04981,-.04704,.03874,-.06364,0.0*
1,1,.006,.03874,-.06364*
20,1,.006,.03874,-.06364,.02214,-.07747,0.0*
1,1,.006,.02214,-.07747*
20,1,.006,.02214,-.07747,.00278,-.083,0.0*
1,1,.006,.00278,-.083*
20,1,.006,.00278,-.083,-.01936,-.07747,0.0*
1,1,.006,-.01936,-.07747*
20,1,.006,-.01936,-.07747,-.03872,-.06087,0.0*
1,1,.006,-.03872,-.06087*
20,1,.006,-.03872,-.06087,-.04979,-.03597,0.0*
1,1,.006,-.04979,-.03597*
20,1,.006,-.04979,-.03597,-.05256,-.0083,0.0*
1,1,.006,-.05256,-.0083*
20,1,.006,-.05256,-.0083,-.04703,.02766,0.0*
1,1,.006,-.04703,.02766*
20,1,.006,-.04703,.02766,-.03872,.04704,0.0*
1,1,.006,-.03872,.04704*
20,1,.006,-.03872,.04704,-.02489,.0664,0.0*
1,1,.006,-.02489,.0664*
20,1,.006,-.02489,.0664,-.00552,.08023,0.0*
1,1,.006,-.00552,.08023*
20,1,.006,-.00552,.08023,.01384,.083,0.0*
1,1,.006,.01384,.083*
20,1,.006,.01384,.083,.03321,.07747,0.0*
1,1,.006,.03321,.07747*
20,1,.006,.03321,.07747,.04705,.06363,0.0*
1,1,.006,.04705,.06363*
1,1,.006,.11345,-.01384*
20,1,.006,.11345,-.01384,.13282,.00553,0.0*
1,1,.006,.13282,.00553*
20,1,.006,.13282,.00553,.14942,.0166,0.0*
1,1,.006,.14942,.0166*
20,1,.006,.14942,.0166,.17155,.02213,0.0*
1,1,.006,.17155,.02213*
20,1,.006,.17155,.02213,.19092,.0166,0.0*
1,1,.006,.19092,.0166*
20,1,.006,.19092,.0166,.20475,.00553,0.0*
1,1,.006,.20475,.00553*
20,1,.006,.20475,.00553,.21582,-.01107,0.0*
1,1,.006,.21582,-.01107*
20,1,.006,.21582,-.01107,.21859,-.03043,0.0*
1,1,.006,.21859,-.03043*
20,1,.006,.21859,-.03043,.21582,-.04704,0.0*
1,1,.006,.21582,-.04704*
20,1,.006,.21582,-.04704,.20475,-.06364,0.0*
1,1,.006,.20475,-.06364*
20,1,.006,.20475,-.06364,.18815,-.07747,0.0*
1,1,.006,.18815,-.07747*
20,1,.006,.18815,-.07747,.16879,-.083,0.0*
1,1,.006,.16879,-.083*
20,1,.006,.16879,-.083,.14665,-.07747,0.0*
1,1,.006,.14665,-.07747*
20,1,.006,.14665,-.07747,.12729,-.06087,0.0*
1,1,.006,.12729,-.06087*
20,1,.006,.12729,-.06087,.11622,-.03597,0.0*
1,1,.006,.11622,-.03597*
20,1,.006,.11622,-.03597,.11345,-.0083,0.0*
1,1,.006,.11345,-.0083*
20,1,.006,.11345,-.0083,.11898,.02766,0.0*
1,1,.006,.11898,.02766*
20,1,.006,.11898,.02766,.12729,.04704,0.0*
1,1,.006,.12729,.04704*
20,1,.006,.12729,.04704,.14112,.0664,0.0*
1,1,.006,.14112,.0664*
20,1,.006,.14112,.0664,.16049,.08023,0.0*
1,1,.006,.16049,.08023*
20,1,.006,.16049,.08023,.17985,.083,0.0*
1,1,.006,.17985,.083*
20,1,.006,.17985,.083,.19922,.07747,0.0*
1,1,.006,.19922,.07747*
20,1,.006,.19922,.07747,.21306,.06363,0.0*
1,1,.006,.21306,.06363*
%
%ADD36MACRO36*%
%AMMACRO44*
1,1,.006,.035,0.0*
20,1,.006,.035,0.0,.034468,-.006078,0.0*
1,1,.006,.034468,-.006078*
20,1,.006,.034468,-.006078,.032889,-.011971,0.0*
1,1,.006,.032889,-.011971*
20,1,.006,.032889,-.011971,.030311,-.0175,0.0*
1,1,.006,.030311,-.0175*
20,1,.006,.030311,-.0175,.026812,-.022498,0.0*
1,1,.006,.026812,-.022498*
20,1,.006,.026812,-.022498,.022498,-.026812,0.0*
1,1,.006,.022498,-.026812*
20,1,.006,.022498,-.026812,.0175,-.030311,0.0*
1,1,.006,.0175,-.030311*
20,1,.006,.0175,-.030311,.011971,-.032889,0.0*
1,1,.006,.011971,-.032889*
20,1,.006,.011971,-.032889,.006078,-.034468,0.0*
1,1,.006,.006078,-.034468*
20,1,.006,.006078,-.034468,0.0,-.035,0.0*
1,1,.006,0.0,-.035*
20,1,.006,0.0,-.035,-.006078,-.034468,0.0*
1,1,.006,-.006078,-.034468*
20,1,.006,-.006078,-.034468,-.011971,-.032889,0.0*
1,1,.006,-.011971,-.032889*
20,1,.006,-.011971,-.032889,-.0175,-.030311,0.0*
1,1,.006,-.0175,-.030311*
20,1,.006,-.0175,-.030311,-.022498,-.026812,0.0*
1,1,.006,-.022498,-.026812*
20,1,.006,-.022498,-.026812,-.026812,-.022498,0.0*
1,1,.006,-.026812,-.022498*
20,1,.006,-.026812,-.022498,-.030311,-.0175,0.0*
1,1,.006,-.030311,-.0175*
20,1,.006,-.030311,-.0175,-.032889,-.011971,0.0*
1,1,.006,-.032889,-.011971*
20,1,.006,-.032889,-.011971,-.034468,-.006078,0.0*
1,1,.006,-.034468,-.006078*
20,1,.006,-.034468,-.006078,-.035,0.0,0.0*
1,1,.006,-.035,0.0*
20,1,.006,-.035,0.0,-.034468,.006078,0.0*
1,1,.006,-.034468,.006078*
20,1,.006,-.034468,.006078,-.032889,.011971,0.0*
1,1,.006,-.032889,.011971*
20,1,.006,-.032889,.011971,-.030311,.0175,0.0*
1,1,.006,-.030311,.0175*
20,1,.006,-.030311,.0175,-.026812,.022498,0.0*
1,1,.006,-.026812,.022498*
20,1,.006,-.026812,.022498,-.022498,.026812,0.0*
1,1,.006,-.022498,.026812*
20,1,.006,-.022498,.026812,-.0175,.030311,0.0*
1,1,.006,-.0175,.030311*
20,1,.006,-.0175,.030311,-.011971,.032889,0.0*
1,1,.006,-.011971,.032889*
20,1,.006,-.011971,.032889,-.006078,.034468,0.0*
1,1,.006,-.006078,.034468*
20,1,.006,-.006078,.034468,0.0,.035,0.0*
1,1,.006,0.0,.035*
20,1,.006,0.0,.035,.006078,.034468,0.0*
1,1,.006,.006078,.034468*
20,1,.006,.006078,.034468,.011971,.032889,0.0*
1,1,.006,.011971,.032889*
20,1,.006,.011971,.032889,.0175,.030311,0.0*
1,1,.006,.0175,.030311*
20,1,.006,.0175,.030311,.022498,.026812,0.0*
1,1,.006,.022498,.026812*
20,1,.006,.022498,.026812,.026812,.022498,0.0*
1,1,.006,.026812,.022498*
20,1,.006,.026812,.022498,.030311,.0175,0.0*
1,1,.006,.030311,.0175*
20,1,.006,.030311,.0175,.032889,.011971,0.0*
1,1,.006,.032889,.011971*
20,1,.006,.032889,.011971,.034468,.006078,0.0*
1,1,.006,.034468,.006078*
20,1,.006,.034468,.006078,.035,0.0,0.0*
1,1,.006,.035,0.0*
1,1,.006,-.01488,.01488*
20,1,.006,-.01488,.01488,-.01488,-.01487,0.0*
1,1,.006,-.01488,-.01487*
1,1,.006,-.02628,.01488*
20,1,.006,-.02628,.01488,-.00347,.01488,0.0*
1,1,.006,-.00347,.01488*
1,1,.006,.00497,-.01487*
20,1,.006,.00497,-.01487,.00497,.01488,0.0*
1,1,.006,.00497,.01488*
20,1,.006,.00497,.01488,.01687,.01488,0.0*
1,1,.006,.01687,.01488*
20,1,.006,.01687,.01488,.02084,.01339,0.0*
1,1,.006,.02084,.01339*
20,1,.006,.02084,.01339,.02381,.00992,0.0*
1,1,.006,.02381,.00992*
20,1,.006,.02381,.00992,.0248,.00596,0.0*
1,1,.006,.0248,.00596*
20,1,.006,.0248,.00596,.02381,.00199,0.0*
1,1,.006,.02381,.00199*
20,1,.006,.02381,.00199,.02133,-.00099,0.0*
1,1,.006,.02133,-.00099*
20,1,.006,.02133,-.00099,.01687,-.00247,0.0*
1,1,.006,.01687,-.00247*
20,1,.006,.01687,-.00247,.00497,-.00247,0.0*
1,1,.006,.00497,-.00247*
%
%ADD44MACRO44*%
%AMMACRO39*
1,1,.006,-.0275,.1*
20,1,.006,-.0275,.1,.0275,.1,0.0*
1,1,.006,.0275,.1*
20,1,.006,.0275,.1,.044865,.098481,0.0*
1,1,.006,.044865,.098481*
20,1,.006,.044865,.098481,.061702,.093969,0.0*
1,1,.006,.061702,.093969*
20,1,.006,.061702,.093969,.0775,.086603,0.0*
1,1,.006,.0775,.086603*
20,1,.006,.0775,.086603,.091779,.076604,0.0*
1,1,.006,.091779,.076604*
20,1,.006,.091779,.076604,.104104,.064279,0.0*
1,1,.006,.104104,.064279*
20,1,.006,.104104,.064279,.114103,.05,0.0*
1,1,.006,.114103,.05*
20,1,.006,.114103,.05,.121469,.034202,0.0*
1,1,.006,.121469,.034202*
20,1,.006,.121469,.034202,.125981,.017365,0.0*
1,1,.006,.125981,.017365*
20,1,.006,.125981,.017365,.1275,0.0,0.0*
1,1,.006,.1275,0.0*
20,1,.006,.1275,0.0,.125981,-.017365,0.0*
1,1,.006,.125981,-.017365*
20,1,.006,.125981,-.017365,.121469,-.034202,0.0*
1,1,.006,.121469,-.034202*
20,1,.006,.121469,-.034202,.114103,-.05,0.0*
1,1,.006,.114103,-.05*
20,1,.006,.114103,-.05,.104104,-.064279,0.0*
1,1,.006,.104104,-.064279*
20,1,.006,.104104,-.064279,.091779,-.076604,0.0*
1,1,.006,.091779,-.076604*
20,1,.006,.091779,-.076604,.0775,-.086603,0.0*
1,1,.006,.0775,-.086603*
20,1,.006,.0775,-.086603,.061702,-.093969,0.0*
1,1,.006,.061702,-.093969*
20,1,.006,.061702,-.093969,.044865,-.098481,0.0*
1,1,.006,.044865,-.098481*
20,1,.006,.044865,-.098481,.0275,-.1,0.0*
1,1,.006,.0275,-.1*
20,1,.006,.0275,-.1,-.0275,-.1,0.0*
1,1,.006,-.0275,-.1*
20,1,.006,-.0275,-.1,-.044865,-.098481,0.0*
1,1,.006,-.044865,-.098481*
20,1,.006,-.044865,-.098481,-.061702,-.093969,0.0*
1,1,.006,-.061702,-.093969*
20,1,.006,-.061702,-.093969,-.0775,-.086603,0.0*
1,1,.006,-.0775,-.086603*
20,1,.006,-.0775,-.086603,-.091779,-.076604,0.0*
1,1,.006,-.091779,-.076604*
20,1,.006,-.091779,-.076604,-.104104,-.064279,0.0*
1,1,.006,-.104104,-.064279*
20,1,.006,-.104104,-.064279,-.114103,-.05,0.0*
1,1,.006,-.114103,-.05*
20,1,.006,-.114103,-.05,-.121469,-.034202,0.0*
1,1,.006,-.121469,-.034202*
20,1,.006,-.121469,-.034202,-.125981,-.017365,0.0*
1,1,.006,-.125981,-.017365*
20,1,.006,-.125981,-.017365,-.1275,0.0,0.0*
1,1,.006,-.1275,0.0*
20,1,.006,-.1275,0.0,-.125981,.017365,0.0*
1,1,.006,-.125981,.017365*
20,1,.006,-.125981,.017365,-.121469,.034202,0.0*
1,1,.006,-.121469,.034202*
20,1,.006,-.121469,.034202,-.114103,.05,0.0*
1,1,.006,-.114103,.05*
20,1,.006,-.114103,.05,-.104104,.064279,0.0*
1,1,.006,-.104104,.064279*
20,1,.006,-.104104,.064279,-.091779,.076604,0.0*
1,1,.006,-.091779,.076604*
20,1,.006,-.091779,.076604,-.0775,.086603,0.0*
1,1,.006,-.0775,.086603*
20,1,.006,-.0775,.086603,-.061702,.093969,0.0*
1,1,.006,-.061702,.093969*
20,1,.006,-.061702,.093969,-.044865,.098481,0.0*
1,1,.006,-.044865,.098481*
20,1,.006,-.044865,.098481,-.0275,.1,0.0*
1,1,.006,-.0275,.1*
1,1,.006,-.08167,-.05833*
20,1,.006,-.08167,-.05833,-.05833,-.05833,0.0*
1,1,.006,-.05833,-.05833*
20,1,.006,-.05833,-.05833,-.05833,.035,0.0*
1,1,.006,-.05833,.035*
20,1,.006,-.05833,.035,-.08167,.035,0.0*
1,1,.006,-.08167,.035*
1,1,.006,.02334,-.035*
20,1,.006,.02334,-.035,-.02332,-.035,0.0*
1,1,.006,-.02332,-.035*
20,1,.006,-.02332,-.035,-.02332,.035,0.0*
1,1,.006,-.02332,.035*
20,1,.006,-.02332,.035,.02334,.035,0.0*
1,1,.006,.02334,.035*
1,1,.006,.00468,.00117*
20,1,.006,.00468,.00117,-.02332,.00117,0.0*
1,1,.006,-.02332,.00117*
1,1,.006,.09335,-.035*
20,1,.006,.09335,-.035,.04669,-.035,0.0*
1,1,.006,.04669,-.035*
20,1,.006,.04669,-.035,.04669,.035,0.0*
1,1,.006,.04669,.035*
20,1,.006,.04669,.035,.09335,.035,0.0*
1,1,.006,.09335,.035*
1,1,.006,.07469,.00117*
20,1,.006,.07469,.00117,.04669,.00117,0.0*
1,1,.006,.04669,.00117*
%
%ADD39MACRO39*%
%AMMACRO10*
1,1,.006,.035,0.0*
20,1,.006,.035,0.0,.034468,-.006078,0.0*
1,1,.006,.034468,-.006078*
20,1,.006,.034468,-.006078,.032889,-.011971,0.0*
1,1,.006,.032889,-.011971*
20,1,.006,.032889,-.011971,.030311,-.0175,0.0*
1,1,.006,.030311,-.0175*
20,1,.006,.030311,-.0175,.026812,-.022498,0.0*
1,1,.006,.026812,-.022498*
20,1,.006,.026812,-.022498,.022498,-.026812,0.0*
1,1,.006,.022498,-.026812*
20,1,.006,.022498,-.026812,.0175,-.030311,0.0*
1,1,.006,.0175,-.030311*
20,1,.006,.0175,-.030311,.011971,-.032889,0.0*
1,1,.006,.011971,-.032889*
20,1,.006,.011971,-.032889,.006078,-.034468,0.0*
1,1,.006,.006078,-.034468*
20,1,.006,.006078,-.034468,0.0,-.035,0.0*
1,1,.006,0.0,-.035*
20,1,.006,0.0,-.035,-.006078,-.034468,0.0*
1,1,.006,-.006078,-.034468*
20,1,.006,-.006078,-.034468,-.011971,-.032889,0.0*
1,1,.006,-.011971,-.032889*
20,1,.006,-.011971,-.032889,-.0175,-.030311,0.0*
1,1,.006,-.0175,-.030311*
20,1,.006,-.0175,-.030311,-.022498,-.026812,0.0*
1,1,.006,-.022498,-.026812*
20,1,.006,-.022498,-.026812,-.026812,-.022498,0.0*
1,1,.006,-.026812,-.022498*
20,1,.006,-.026812,-.022498,-.030311,-.0175,0.0*
1,1,.006,-.030311,-.0175*
20,1,.006,-.030311,-.0175,-.032889,-.011971,0.0*
1,1,.006,-.032889,-.011971*
20,1,.006,-.032889,-.011971,-.034468,-.006078,0.0*
1,1,.006,-.034468,-.006078*
20,1,.006,-.034468,-.006078,-.035,0.0,0.0*
1,1,.006,-.035,0.0*
20,1,.006,-.035,0.0,-.034468,.006078,0.0*
1,1,.006,-.034468,.006078*
20,1,.006,-.034468,.006078,-.032889,.011971,0.0*
1,1,.006,-.032889,.011971*
20,1,.006,-.032889,.011971,-.030311,.0175,0.0*
1,1,.006,-.030311,.0175*
20,1,.006,-.030311,.0175,-.026812,.022498,0.0*
1,1,.006,-.026812,.022498*
20,1,.006,-.026812,.022498,-.022498,.026812,0.0*
1,1,.006,-.022498,.026812*
20,1,.006,-.022498,.026812,-.0175,.030311,0.0*
1,1,.006,-.0175,.030311*
20,1,.006,-.0175,.030311,-.011971,.032889,0.0*
1,1,.006,-.011971,.032889*
20,1,.006,-.011971,.032889,-.006078,.034468,0.0*
1,1,.006,-.006078,.034468*
20,1,.006,-.006078,.034468,0.0,.035,0.0*
1,1,.006,0.0,.035*
20,1,.006,0.0,.035,.006078,.034468,0.0*
1,1,.006,.006078,.034468*
20,1,.006,.006078,.034468,.011971,.032889,0.0*
1,1,.006,.011971,.032889*
20,1,.006,.011971,.032889,.0175,.030311,0.0*
1,1,.006,.0175,.030311*
20,1,.006,.0175,.030311,.022498,.026812,0.0*
1,1,.006,.022498,.026812*
20,1,.006,.022498,.026812,.026812,.022498,0.0*
1,1,.006,.026812,.022498*
20,1,.006,.026812,.022498,.030311,.0175,0.0*
1,1,.006,.030311,.0175*
20,1,.006,.030311,.0175,.032889,.011971,0.0*
1,1,.006,.032889,.011971*
20,1,.006,.032889,.011971,.034468,.006078,0.0*
1,1,.006,.034468,.006078*
20,1,.006,.034468,.006078,.035,0.0,0.0*
1,1,.006,.035,0.0*
1,1,.006,-.0295,.01041*
20,1,.006,-.0295,.01041,-.02082,-.01041,0.0*
1,1,.006,-.02082,-.01041*
20,1,.006,-.02082,-.01041,-.01214,.01041,0.0*
1,1,.006,-.01214,.01041*
1,1,.006,.00001,-.01041*
20,1,.006,.00001,-.01041,.00001,.01041,0.0*
1,1,.006,.00001,.01041*
20,1,.006,.00001,.01041,-.00415,.00625,0.0*
1,1,.006,-.00415,.00625*
1,1,.006,-.00415,-.01041*
20,1,.006,-.00415,-.01041,.00417,-.01041,0.0*
1,1,.006,.00417,-.01041*
1,1,.006,.02084,.01041*
20,1,.006,.02084,.01041,.01806,.00972,0.0*
1,1,.006,.01806,.00972*
20,1,.006,.01806,.00972,.01598,.00798,0.0*
1,1,.006,.01598,.00798*
20,1,.006,.01598,.00798,.01459,.0059,0.0*
1,1,.006,.01459,.0059*
20,1,.006,.01459,.0059,.01355,.00312,0.0*
1,1,.006,.01355,.00312*
20,1,.006,.01355,.00312,.01321,0.0,0.0*
1,1,.006,.01321,0.0*
20,1,.006,.01321,0.0,.01355,-.00312,0.0*
1,1,.006,.01355,-.00312*
20,1,.006,.01355,-.00312,.01459,-.0059,0.0*
1,1,.006,.01459,-.0059*
20,1,.006,.01459,-.0059,.01598,-.00798,0.0*
1,1,.006,.01598,-.00798*
20,1,.006,.01598,-.00798,.01806,-.00972,0.0*
1,1,.006,.01806,-.00972*
20,1,.006,.01806,-.00972,.02084,-.01041,0.0*
1,1,.006,.02084,-.01041*
20,1,.006,.02084,-.01041,.02362,-.00972,0.0*
1,1,.006,.02362,-.00972*
20,1,.006,.02362,-.00972,.0257,-.00798,0.0*
1,1,.006,.0257,-.00798*
20,1,.006,.0257,-.00798,.02709,-.0059,0.0*
1,1,.006,.02709,-.0059*
20,1,.006,.02709,-.0059,.02813,-.00312,0.0*
1,1,.006,.02813,-.00312*
20,1,.006,.02813,-.00312,.02847,0.0,0.0*
1,1,.006,.02847,0.0*
20,1,.006,.02847,0.0,.02813,.00312,0.0*
1,1,.006,.02813,.00312*
20,1,.006,.02813,.00312,.02709,.0059,0.0*
1,1,.006,.02709,.0059*
20,1,.006,.02709,.0059,.0257,.00798,0.0*
1,1,.006,.0257,.00798*
20,1,.006,.0257,.00798,.02362,.00972,0.0*
1,1,.006,.02362,.00972*
20,1,.006,.02362,.00972,.02084,.01041,0.0*
1,1,.006,.02084,.01041*
%
%ADD10MACRO10*%
%ADD11C,.125*%
%AMMACRO21*
1,1,.006,.035,0.0*
20,1,.006,.035,0.0,.034468,-.006078,0.0*
1,1,.006,.034468,-.006078*
20,1,.006,.034468,-.006078,.032889,-.011971,0.0*
1,1,.006,.032889,-.011971*
20,1,.006,.032889,-.011971,.030311,-.0175,0.0*
1,1,.006,.030311,-.0175*
20,1,.006,.030311,-.0175,.026812,-.022498,0.0*
1,1,.006,.026812,-.022498*
20,1,.006,.026812,-.022498,.022498,-.026812,0.0*
1,1,.006,.022498,-.026812*
20,1,.006,.022498,-.026812,.0175,-.030311,0.0*
1,1,.006,.0175,-.030311*
20,1,.006,.0175,-.030311,.011971,-.032889,0.0*
1,1,.006,.011971,-.032889*
20,1,.006,.011971,-.032889,.006078,-.034468,0.0*
1,1,.006,.006078,-.034468*
20,1,.006,.006078,-.034468,0.0,-.035,0.0*
1,1,.006,0.0,-.035*
20,1,.006,0.0,-.035,-.006078,-.034468,0.0*
1,1,.006,-.006078,-.034468*
20,1,.006,-.006078,-.034468,-.011971,-.032889,0.0*
1,1,.006,-.011971,-.032889*
20,1,.006,-.011971,-.032889,-.0175,-.030311,0.0*
1,1,.006,-.0175,-.030311*
20,1,.006,-.0175,-.030311,-.022498,-.026812,0.0*
1,1,.006,-.022498,-.026812*
20,1,.006,-.022498,-.026812,-.026812,-.022498,0.0*
1,1,.006,-.026812,-.022498*
20,1,.006,-.026812,-.022498,-.030311,-.0175,0.0*
1,1,.006,-.030311,-.0175*
20,1,.006,-.030311,-.0175,-.032889,-.011971,0.0*
1,1,.006,-.032889,-.011971*
20,1,.006,-.032889,-.011971,-.034468,-.006078,0.0*
1,1,.006,-.034468,-.006078*
20,1,.006,-.034468,-.006078,-.035,0.0,0.0*
1,1,.006,-.035,0.0*
20,1,.006,-.035,0.0,-.034468,.006078,0.0*
1,1,.006,-.034468,.006078*
20,1,.006,-.034468,.006078,-.032889,.011971,0.0*
1,1,.006,-.032889,.011971*
20,1,.006,-.032889,.011971,-.030311,.0175,0.0*
1,1,.006,-.030311,.0175*
20,1,.006,-.030311,.0175,-.026812,.022498,0.0*
1,1,.006,-.026812,.022498*
20,1,.006,-.026812,.022498,-.022498,.026812,0.0*
1,1,.006,-.022498,.026812*
20,1,.006,-.022498,.026812,-.0175,.030311,0.0*
1,1,.006,-.0175,.030311*
20,1,.006,-.0175,.030311,-.011971,.032889,0.0*
1,1,.006,-.011971,.032889*
20,1,.006,-.011971,.032889,-.006078,.034468,0.0*
1,1,.006,-.006078,.034468*
20,1,.006,-.006078,.034468,0.0,.035,0.0*
1,1,.006,0.0,.035*
20,1,.006,0.0,.035,.006078,.034468,0.0*
1,1,.006,.006078,.034468*
20,1,.006,.006078,.034468,.011971,.032889,0.0*
1,1,.006,.011971,.032889*
20,1,.006,.011971,.032889,.0175,.030311,0.0*
1,1,.006,.0175,.030311*
20,1,.006,.0175,.030311,.022498,.026812,0.0*
1,1,.006,.022498,.026812*
20,1,.006,.022498,.026812,.026812,.022498,0.0*
1,1,.006,.026812,.022498*
20,1,.006,.026812,.022498,.030311,.0175,0.0*
1,1,.006,.030311,.0175*
20,1,.006,.030311,.0175,.032889,.011971,0.0*
1,1,.006,.032889,.011971*
20,1,.006,.032889,.011971,.034468,.006078,0.0*
1,1,.006,.034468,.006078*
20,1,.006,.034468,.006078,.035,0.0,0.0*
1,1,.006,.035,0.0*
1,1,.006,-.0295,.01041*
20,1,.006,-.0295,.01041,-.02082,-.01041,0.0*
1,1,.006,-.02082,-.01041*
20,1,.006,-.02082,-.01041,-.01214,.01041,0.0*
1,1,.006,-.01214,.01041*
1,1,.006,.00001,.01041*
20,1,.006,.00001,.01041,-.00277,.00972,0.0*
1,1,.006,-.00277,.00972*
20,1,.006,-.00277,.00972,-.00485,.00798,0.0*
1,1,.006,-.00485,.00798*
20,1,.006,-.00485,.00798,-.00624,.0059,0.0*
1,1,.006,-.00624,.0059*
20,1,.006,-.00624,.0059,-.00728,.00312,0.0*
1,1,.006,-.00728,.00312*
20,1,.006,-.00728,.00312,-.00762,0.0,0.0*
1,1,.006,-.00762,0.0*
20,1,.006,-.00762,0.0,-.00728,-.00312,0.0*
1,1,.006,-.00728,-.00312*
20,1,.006,-.00728,-.00312,-.00624,-.0059,0.0*
1,1,.006,-.00624,-.0059*
20,1,.006,-.00624,-.0059,-.00485,-.00798,0.0*
1,1,.006,-.00485,-.00798*
20,1,.006,-.00485,-.00798,-.00277,-.00972,0.0*
1,1,.006,-.00277,-.00972*
20,1,.006,-.00277,-.00972,.00001,-.01041,0.0*
1,1,.006,.00001,-.01041*
20,1,.006,.00001,-.01041,.00279,-.00972,0.0*
1,1,.006,.00279,-.00972*
20,1,.006,.00279,-.00972,.00487,-.00798,0.0*
1,1,.006,.00487,-.00798*
20,1,.006,.00487,-.00798,.00626,-.0059,0.0*
1,1,.006,.00626,-.0059*
20,1,.006,.00626,-.0059,.0073,-.00312,0.0*
1,1,.006,.0073,-.00312*
20,1,.006,.0073,-.00312,.00764,0.0,0.0*
1,1,.006,.00764,0.0*
20,1,.006,.00764,0.0,.0073,.00312,0.0*
1,1,.006,.0073,.00312*
20,1,.006,.0073,.00312,.00626,.0059,0.0*
1,1,.006,.00626,.0059*
20,1,.006,.00626,.0059,.00487,.00798,0.0*
1,1,.006,.00487,.00798*
20,1,.006,.00487,.00798,.00279,.00972,0.0*
1,1,.006,.00279,.00972*
20,1,.006,.00279,.00972,.00001,.01041,0.0*
1,1,.006,.00001,.01041*
1,1,.006,.02084,-.01041*
20,1,.006,.02084,-.01041,.02327,-.01006,0.0*
1,1,.006,.02327,-.01006*
20,1,.006,.02327,-.01006,.02604,-.00902,0.0*
1,1,.006,.02604,-.00902*
20,1,.006,.02604,-.00902,.02778,-.00729,0.0*
1,1,.006,.02778,-.00729*
20,1,.006,.02778,-.00729,.02847,-.00486,0.0*
1,1,.006,.02847,-.00486*
20,1,.006,.02847,-.00486,.02778,-.00243,0.0*
1,1,.006,.02778,-.00243*
20,1,.006,.02778,-.00243,.0257,-.00035,0.0*
1,1,.006,.0257,-.00035*
20,1,.006,.0257,-.00035,.02257,.00069,0.0*
1,1,.006,.02257,.00069*
20,1,.006,.02257,.00069,.01911,.00069,0.0*
1,1,.006,.01911,.00069*
20,1,.006,.01911,.00069,.01702,.00139,0.0*
1,1,.006,.01702,.00139*
20,1,.006,.01702,.00139,.01529,.00312,0.0*
1,1,.006,.01529,.00312*
20,1,.006,.01529,.00312,.01459,.00555,0.0*
1,1,.006,.01459,.00555*
20,1,.006,.01459,.00555,.01564,.00798,0.0*
1,1,.006,.01564,.00798*
20,1,.006,.01564,.00798,.01806,.00972,0.0*
1,1,.006,.01806,.00972*
20,1,.006,.01806,.00972,.02084,.01041,0.0*
1,1,.006,.02084,.01041*
20,1,.006,.02084,.01041,.02362,.00972,0.0*
1,1,.006,.02362,.00972*
20,1,.006,.02362,.00972,.02604,.00798,0.0*
1,1,.006,.02604,.00798*
20,1,.006,.02604,.00798,.02709,.00555,0.0*
1,1,.006,.02709,.00555*
20,1,.006,.02709,.00555,.02639,.00312,0.0*
1,1,.006,.02639,.00312*
20,1,.006,.02639,.00312,.02466,.00139,0.0*
1,1,.006,.02466,.00139*
20,1,.006,.02466,.00139,.02257,.00069,0.0*
1,1,.006,.02257,.00069*
20,1,.006,.02257,.00069,.01911,.00069,0.0*
1,1,.006,.01911,.00069*
20,1,.006,.01911,.00069,.01598,-.00035,0.0*
1,1,.006,.01598,-.00035*
20,1,.006,.01598,-.00035,.0139,-.00243,0.0*
1,1,.006,.0139,-.00243*
20,1,.006,.0139,-.00243,.01321,-.00486,0.0*
1,1,.006,.01321,-.00486*
20,1,.006,.01321,-.00486,.0139,-.00729,0.0*
1,1,.006,.0139,-.00729*
20,1,.006,.0139,-.00729,.01564,-.00902,0.0*
1,1,.006,.01564,-.00902*
20,1,.006,.01564,-.00902,.01841,-.01006,0.0*
1,1,.006,.01841,-.01006*
20,1,.006,.01841,-.01006,.02084,-.01041,0.0*
1,1,.006,.02084,-.01041*
%
%ADD21MACRO21*%
%AMMACRO42*
1,1,.006,.061,0.0*
20,1,.006,.061,0.0,.0305,.052828,0.0*
1,1,.006,.0305,.052828*
20,1,.006,.0305,.052828,-.0305,.052828,0.0*
1,1,.006,-.0305,.052828*
20,1,.006,-.0305,.052828,-.061,0.0,0.0*
1,1,.006,-.061,0.0*
20,1,.006,-.061,0.0,-.0305,-.052828,0.0*
1,1,.006,-.0305,-.052828*
20,1,.006,-.0305,-.052828,.0305,-.052828,0.0*
1,1,.006,.0305,-.052828*
20,1,.006,.0305,-.052828,.061,0.0,0.0*
1,1,.006,.061,0.0*
1,1,.006,-.02092,-.0249*
20,1,.006,-.02092,-.0249,-.02092,.00499,0.0*
1,1,.006,-.02092,.00499*
1,1,.006,-.02092,.0005*
20,1,.006,-.02092,.0005,-.02341,.00299,0.0*
1,1,.006,-.02341,.00299*
20,1,.006,-.02341,.00299,-.0264,.00449,0.0*
1,1,.006,-.0264,.00449*
20,1,.006,-.0264,.00449,-.02989,.00499,0.0*
1,1,.006,-.02989,.00499*
20,1,.006,-.02989,.00499,-.03287,.00449,0.0*
1,1,.006,-.03287,.00449*
20,1,.006,-.03287,.00449,-.03636,.002,0.0*
1,1,.006,-.03636,.002*
20,1,.006,-.03636,.002,-.03835,-.00149,0.0*
1,1,.006,-.03835,-.00149*
20,1,.006,-.03835,-.00149,-.03885,-.00498,0.0*
1,1,.006,-.03885,-.00498*
20,1,.006,-.03885,-.00498,-.03835,-.00846,0.0*
1,1,.006,-.03835,-.00846*
20,1,.006,-.03835,-.00846,-.03636,-.01195,0.0*
1,1,.006,-.03636,-.01195*
20,1,.006,-.03636,-.01195,-.03287,-.01444,0.0*
1,1,.006,-.03287,-.01444*
20,1,.006,-.03287,-.01444,-.02989,-.01494,0.0*
1,1,.006,-.02989,-.01494*
20,1,.006,-.02989,-.01494,-.0264,-.01444,0.0*
1,1,.006,-.0264,-.01444*
20,1,.006,-.0264,-.01444,-.02341,-.01295,0.0*
1,1,.006,-.02341,-.01295*
20,1,.006,-.02341,-.01295,-.02092,-.01046,0.0*
1,1,.006,-.02092,-.01046*
1,1,.006,-.01244,.00499*
20,1,.006,-.01244,.00499,-.00646,-.01494,0.0*
1,1,.006,-.00646,-.01494*
20,1,.006,-.00646,-.01494,.00001,.00499,0.0*
1,1,.006,.00001,.00499*
20,1,.006,.00001,.00499,.00649,-.01494,0.0*
1,1,.006,.00649,-.01494*
20,1,.006,.00649,-.01494,.01247,.00499,0.0*
1,1,.006,.01247,.00499*
1,1,.006,.01746,.00499*
20,1,.006,.01746,.00499,.02344,-.01494,0.0*
1,1,.006,.02344,-.01494*
20,1,.006,.02344,-.01494,.02991,.00499,0.0*
1,1,.006,.02991,.00499*
20,1,.006,.02991,.00499,.03639,-.01494,0.0*
1,1,.006,.03639,-.01494*
20,1,.006,.03639,-.01494,.04237,.00499,0.0*
1,1,.006,.04237,.00499*
%
%ADD42MACRO42*%
%AMMACRO28*
1,1,.006,0.0,.035*
20,1,.006,0.0,.035,.030311,-.0175,0.0*
1,1,.006,.030311,-.0175*
20,1,.006,.030311,-.0175,-.030311,-.0175,0.0*
1,1,.006,-.030311,-.0175*
20,1,.006,-.030311,-.0175,0.0,.035,0.0*
1,1,.006,0.0,.035*
1,1,.006,-.01433,-.00918*
20,1,.006,-.01433,-.00918,-.01433,.00184,0.0*
1,1,.006,-.01433,.00184*
1,1,.006,-.01433,.00018*
20,1,.006,-.01433,.00018,-.01341,.0011,0.0*
1,1,.006,-.01341,.0011*
20,1,.006,-.01341,.0011,-.01249,.00165,0.0*
1,1,.006,-.01249,.00165*
20,1,.006,-.01249,.00165,-.01102,.00184,0.0*
1,1,.006,-.01102,.00184*
20,1,.006,-.01102,.00184,-.00973,.00165,0.0*
1,1,.006,-.00973,.00165*
20,1,.006,-.00973,.00165,-.00845,.00073,0.0*
1,1,.006,-.00845,.00073*
20,1,.006,-.00845,.00073,-.0079,-.00055,0.0*
1,1,.006,-.0079,-.00055*
20,1,.006,-.0079,-.00055,-.00771,-.00184,0.0*
1,1,.006,-.00771,-.00184*
20,1,.006,-.00771,-.00184,-.0079,-.00312,0.0*
1,1,.006,-.0079,-.00312*
20,1,.006,-.0079,-.00312,-.00845,-.00441,0.0*
1,1,.006,-.00845,-.00441*
20,1,.006,-.00845,-.00441,-.00955,-.00514,0.0*
1,1,.006,-.00955,-.00514*
20,1,.006,-.00955,-.00514,-.01102,-.00551,0.0*
1,1,.006,-.01102,-.00551*
20,1,.006,-.01102,-.00551,-.01231,-.00533,0.0*
1,1,.006,-.01231,-.00533*
20,1,.006,-.01231,-.00533,-.01359,-.00478,0.0*
1,1,.006,-.01359,-.00478*
20,1,.006,-.01359,-.00478,-.01433,-.00404,0.0*
1,1,.006,-.01433,-.00404*
1,1,.006,-.00256,-.00551*
20,1,.006,-.00256,-.00551,-.00256,.00184,0.0*
1,1,.006,-.00256,.00184*
1,1,.006,-.00256,.00037*
20,1,.006,-.00256,.00037,-.00164,.0011,0.0*
1,1,.006,-.00164,.0011*
20,1,.006,-.00164,.0011,-.00072,.00165,0.0*
1,1,.006,-.00072,.00165*
20,1,.006,-.00072,.00165,.00056,.00184,0.0*
1,1,.006,.00056,.00184*
20,1,.006,.00056,.00184,.00148,.00165,0.0*
1,1,.006,.00148,.00165*
20,1,.006,.00148,.00165,.00258,.0011,0.0*
1,1,.006,.00258,.0011*
1,1,.006,.01435,-.00918*
20,1,.006,.01435,-.00918,.01435,.00184,0.0*
1,1,.006,.01435,.00184*
1,1,.006,.01435,.00018*
20,1,.006,.01435,.00018,.01343,.0011,0.0*
1,1,.006,.01343,.0011*
20,1,.006,.01343,.0011,.01233,.00165,0.0*
1,1,.006,.01233,.00165*
20,1,.006,.01233,.00165,.01104,.00184,0.0*
1,1,.006,.01104,.00184*
20,1,.006,.01104,.00184,.00994,.00165,0.0*
1,1,.006,.00994,.00165*
20,1,.006,.00994,.00165,.00865,.00073,0.0*
1,1,.006,.00865,.00073*
20,1,.006,.00865,.00073,.00792,-.00055,0.0*
1,1,.006,.00792,-.00055*
20,1,.006,.00792,-.00055,.00773,-.00184,0.0*
1,1,.006,.00773,-.00184*
20,1,.006,.00773,-.00184,.00792,-.00312,0.0*
1,1,.006,.00792,-.00312*
20,1,.006,.00792,-.00312,.00865,-.00441,0.0*
1,1,.006,.00865,-.00441*
20,1,.006,.00865,-.00441,.00994,-.00533,0.0*
1,1,.006,.00994,-.00533*
20,1,.006,.00994,-.00533,.01104,-.00551,0.0*
1,1,.006,.01104,-.00551*
20,1,.006,.01104,-.00551,.01233,-.00533,0.0*
1,1,.006,.01233,-.00533*
20,1,.006,.01233,-.00533,.01343,-.00478,0.0*
1,1,.006,.01343,-.00478*
20,1,.006,.01343,-.00478,.01435,-.00386,0.0*
1,1,.006,.01435,-.00386*
%
%ADD28MACRO28*%
%AMMACRO26*
1,1,.006,.079,0.0*
20,1,.006,.079,0.0,.0395,.068416,0.0*
1,1,.006,.0395,.068416*
20,1,.006,.0395,.068416,-.0395,.068416,0.0*
1,1,.006,-.0395,.068416*
20,1,.006,-.0395,.068416,-.079,0.0,0.0*
1,1,.006,-.079,0.0*
20,1,.006,-.079,0.0,-.0395,-.068416,0.0*
1,1,.006,-.0395,-.068416*
20,1,.006,-.0395,-.068416,.0395,-.068416,0.0*
1,1,.006,.0395,-.068416*
20,1,.006,.0395,-.068416,.079,0.0,0.0*
1,1,.006,.079,0.0*
1,1,.006,-.02709,-.03225*
20,1,.006,-.02709,-.03225,-.02709,.00646,0.0*
1,1,.006,-.02709,.00646*
1,1,.006,-.02709,.00065*
20,1,.006,-.02709,.00065,-.03032,.00388,0.0*
1,1,.006,-.03032,.00388*
20,1,.006,-.03032,.00388,-.03419,.00581,0.0*
1,1,.006,-.03419,.00581*
20,1,.006,-.03419,.00581,-.03871,.00646,0.0*
1,1,.006,-.03871,.00646*
20,1,.006,-.03871,.00646,-.04258,.00581,0.0*
1,1,.006,-.04258,.00581*
20,1,.006,-.04258,.00581,-.04709,.00259,0.0*
1,1,.006,-.04709,.00259*
20,1,.006,-.04709,.00259,-.04967,-.00193,0.0*
1,1,.006,-.04967,-.00193*
20,1,.006,-.04967,-.00193,-.05032,-.00645,0.0*
1,1,.006,-.05032,-.00645*
20,1,.006,-.05032,-.00645,-.04967,-.01096,0.0*
1,1,.006,-.04967,-.01096*
20,1,.006,-.04967,-.01096,-.04709,-.01548,0.0*
1,1,.006,-.04709,-.01548*
20,1,.006,-.04709,-.01548,-.04258,-.0187,0.0*
1,1,.006,-.04258,-.0187*
20,1,.006,-.04258,-.0187,-.03871,-.01935,0.0*
1,1,.006,-.03871,-.01935*
20,1,.006,-.03871,-.01935,-.03419,-.0187,0.0*
1,1,.006,-.03419,-.0187*
20,1,.006,-.03419,-.0187,-.03032,-.01677,0.0*
1,1,.006,-.03032,-.01677*
20,1,.006,-.03032,-.01677,-.02709,-.01354,0.0*
1,1,.006,-.02709,-.01354*
1,1,.006,.00001,.01936*
20,1,.006,.00001,.01936,.00001,-.01935,0.0*
1,1,.006,.00001,-.01935*
1,1,.006,-.00902,.00646*
20,1,.006,-.00902,.00646,.00905,.00646,0.0*
1,1,.006,.00905,.00646*
1,1,.006,.03873,.00646*
20,1,.006,.03873,.00646,.03873,-.01935,0.0*
1,1,.006,.03873,-.01935*
1,1,.006,.03873,.01678*
20,1,.006,.03873,.01678,.03744,.01742,0.0*
1,1,.006,.03744,.01742*
20,1,.006,.03744,.01742,.03744,.01871,0.0*
1,1,.006,.03744,.01871*
20,1,.006,.03744,.01871,.03873,.01936,0.0*
1,1,.006,.03873,.01936*
20,1,.006,.03873,.01936,.04003,.01871,0.0*
1,1,.006,.04003,.01871*
20,1,.006,.04003,.01871,.04003,.01742,0.0*
1,1,.006,.04003,.01742*
20,1,.006,.04003,.01742,.03873,.01678,0.0*
1,1,.006,.03873,.01678*
%
%ADD26MACRO26*%
%AMMACRO17*
1,1,.006,0.0,.035*
20,1,.006,0.0,.035,.030311,-.0175,0.0*
1,1,.006,.030311,-.0175*
20,1,.006,.030311,-.0175,-.030311,-.0175,0.0*
1,1,.006,-.030311,-.0175*
20,1,.006,-.030311,-.0175,0.0,.035,0.0*
1,1,.006,0.0,.035*
1,1,.006,-.01433,-.00918*
20,1,.006,-.01433,-.00918,-.01433,.00184,0.0*
1,1,.006,-.01433,.00184*
1,1,.006,-.01433,.00018*
20,1,.006,-.01433,.00018,-.01341,.0011,0.0*
1,1,.006,-.01341,.0011*
20,1,.006,-.01341,.0011,-.01249,.00165,0.0*
1,1,.006,-.01249,.00165*
20,1,.006,-.01249,.00165,-.01102,.00184,0.0*
1,1,.006,-.01102,.00184*
20,1,.006,-.01102,.00184,-.00973,.00165,0.0*
1,1,.006,-.00973,.00165*
20,1,.006,-.00973,.00165,-.00845,.00073,0.0*
1,1,.006,-.00845,.00073*
20,1,.006,-.00845,.00073,-.0079,-.00055,0.0*
1,1,.006,-.0079,-.00055*
20,1,.006,-.0079,-.00055,-.00771,-.00184,0.0*
1,1,.006,-.00771,-.00184*
20,1,.006,-.00771,-.00184,-.0079,-.00312,0.0*
1,1,.006,-.0079,-.00312*
20,1,.006,-.0079,-.00312,-.00845,-.00441,0.0*
1,1,.006,-.00845,-.00441*
20,1,.006,-.00845,-.00441,-.00955,-.00514,0.0*
1,1,.006,-.00955,-.00514*
20,1,.006,-.00955,-.00514,-.01102,-.00551,0.0*
1,1,.006,-.01102,-.00551*
20,1,.006,-.01102,-.00551,-.01231,-.00533,0.0*
1,1,.006,-.01231,-.00533*
20,1,.006,-.01231,-.00533,-.01359,-.00478,0.0*
1,1,.006,-.01359,-.00478*
20,1,.006,-.01359,-.00478,-.01433,-.00404,0.0*
1,1,.006,-.01433,-.00404*
1,1,.006,-.00256,-.00551*
20,1,.006,-.00256,-.00551,-.00256,.00184,0.0*
1,1,.006,-.00256,.00184*
1,1,.006,-.00256,.00037*
20,1,.006,-.00256,.00037,-.00164,.0011,0.0*
1,1,.006,-.00164,.0011*
20,1,.006,-.00164,.0011,-.00072,.00165,0.0*
1,1,.006,-.00072,.00165*
20,1,.006,-.00072,.00165,.00056,.00184,0.0*
1,1,.006,.00056,.00184*
20,1,.006,.00056,.00184,.00148,.00165,0.0*
1,1,.006,.00148,.00165*
20,1,.006,.00148,.00165,.00258,.0011,0.0*
1,1,.006,.00258,.0011*
1,1,.006,.00847,-.00551*
20,1,.006,.00847,-.00551,.00847,.00184,0.0*
1,1,.006,.00847,.00184*
1,1,.006,.00847,.00037*
20,1,.006,.00847,.00037,.00939,.0011,0.0*
1,1,.006,.00939,.0011*
20,1,.006,.00939,.0011,.01031,.00165,0.0*
1,1,.006,.01031,.00165*
20,1,.006,.01031,.00165,.01159,.00184,0.0*
1,1,.006,.01159,.00184*
20,1,.006,.01159,.00184,.01251,.00165,0.0*
1,1,.006,.01251,.00165*
20,1,.006,.01251,.00165,.01361,.0011,0.0*
1,1,.006,.01361,.0011*
%
%ADD17MACRO17*%
%AMMACRO41*
1,1,.006,0.0,.035*
20,1,.006,0.0,.035,.030311,-.0175,0.0*
1,1,.006,.030311,-.0175*
20,1,.006,.030311,-.0175,-.030311,-.0175,0.0*
1,1,.006,-.030311,-.0175*
20,1,.006,-.030311,-.0175,0.0,.035,0.0*
1,1,.006,0.0,.035*
1,1,.006,-.01433,-.00918*
20,1,.006,-.01433,-.00918,-.01433,.00184,0.0*
1,1,.006,-.01433,.00184*
1,1,.006,-.01433,.00018*
20,1,.006,-.01433,.00018,-.01341,.0011,0.0*
1,1,.006,-.01341,.0011*
20,1,.006,-.01341,.0011,-.01249,.00165,0.0*
1,1,.006,-.01249,.00165*
20,1,.006,-.01249,.00165,-.01102,.00184,0.0*
1,1,.006,-.01102,.00184*
20,1,.006,-.01102,.00184,-.00973,.00165,0.0*
1,1,.006,-.00973,.00165*
20,1,.006,-.00973,.00165,-.00845,.00073,0.0*
1,1,.006,-.00845,.00073*
20,1,.006,-.00845,.00073,-.0079,-.00055,0.0*
1,1,.006,-.0079,-.00055*
20,1,.006,-.0079,-.00055,-.00771,-.00184,0.0*
1,1,.006,-.00771,-.00184*
20,1,.006,-.00771,-.00184,-.0079,-.00312,0.0*
1,1,.006,-.0079,-.00312*
20,1,.006,-.0079,-.00312,-.00845,-.00441,0.0*
1,1,.006,-.00845,-.00441*
20,1,.006,-.00845,-.00441,-.00955,-.00514,0.0*
1,1,.006,-.00955,-.00514*
20,1,.006,-.00955,-.00514,-.01102,-.00551,0.0*
1,1,.006,-.01102,-.00551*
20,1,.006,-.01102,-.00551,-.01231,-.00533,0.0*
1,1,.006,-.01231,-.00533*
20,1,.006,-.01231,-.00533,-.01359,-.00478,0.0*
1,1,.006,-.01359,-.00478*
20,1,.006,-.01359,-.00478,-.01433,-.00404,0.0*
1,1,.006,-.01433,-.00404*
1,1,.006,-.00256,-.00551*
20,1,.006,-.00256,-.00551,-.00256,.00184,0.0*
1,1,.006,-.00256,.00184*
1,1,.006,-.00256,.00037*
20,1,.006,-.00256,.00037,-.00164,.0011,0.0*
1,1,.006,-.00164,.0011*
20,1,.006,-.00164,.0011,-.00072,.00165,0.0*
1,1,.006,-.00072,.00165*
20,1,.006,-.00072,.00165,.00056,.00184,0.0*
1,1,.006,.00056,.00184*
20,1,.006,.00056,.00184,.00148,.00165,0.0*
1,1,.006,.00148,.00165*
20,1,.006,.00148,.00165,.00258,.0011,0.0*
1,1,.006,.00258,.0011*
1,1,.006,.01104,.00551*
20,1,.006,.01104,.00551,.01104,-.00551,0.0*
1,1,.006,.01104,-.00551*
1,1,.006,.00847,.00184*
20,1,.006,.00847,.00184,.01361,.00184,0.0*
1,1,.006,.01361,.00184*
%
%ADD41MACRO41*%
%AMMACRO25*
1,1,.006,.075,0.0*
20,1,.006,.075,0.0,.0375,.064952,0.0*
1,1,.006,.0375,.064952*
20,1,.006,.0375,.064952,-.0375,.064952,0.0*
1,1,.006,-.0375,.064952*
20,1,.006,-.0375,.064952,-.075,0.0,0.0*
1,1,.006,-.075,0.0*
20,1,.006,-.075,0.0,-.0375,-.064952,0.0*
1,1,.006,-.0375,-.064952*
20,1,.006,-.0375,-.064952,.0375,-.064952,0.0*
1,1,.006,.0375,-.064952*
20,1,.006,.0375,-.064952,.075,0.0,0.0*
1,1,.006,.075,0.0*
1,1,.006,-.03675,-.01837*
20,1,.006,-.03675,-.01837,-.03675,.01838,0.0*
1,1,.006,-.03675,.01838*
20,1,.006,-.03675,.01838,-.0441,.01103,0.0*
1,1,.006,-.0441,.01103*
1,1,.006,-.0441,-.01837*
20,1,.006,-.0441,-.01837,-.0294,-.01837,0.0*
1,1,.006,-.0294,-.01837*
1,1,.006,-.01346,-.01286*
20,1,.006,-.01346,-.01286,-.00979,-.01592,0.0*
1,1,.006,-.00979,-.01592*
20,1,.006,-.00979,-.01592,-.0055,-.01776,0.0*
1,1,.006,-.0055,-.01776*
20,1,.006,-.0055,-.01776,.00001,-.01837,0.0*
1,1,.006,.00001,-.01837*
20,1,.006,.00001,-.01837,.00553,-.01715,0.0*
1,1,.006,.00553,-.01715*
20,1,.006,.00553,-.01715,.00981,-.0147,0.0*
1,1,.006,.00981,-.0147*
20,1,.006,.00981,-.0147,.01288,-.01041,0.0*
1,1,.006,.01288,-.01041*
20,1,.006,.01288,-.01041,.01349,-.00551,0.0*
1,1,.006,.01349,-.00551*
20,1,.006,.01349,-.00551,.01227,-.00061,0.0*
1,1,.006,.01227,-.00061*
20,1,.006,.01227,-.00061,.0092,.00246,0.0*
1,1,.006,.0092,.00246*
20,1,.006,.0092,.00246,.00491,.0049,0.0*
1,1,.006,.00491,.0049*
20,1,.006,.00491,.0049,.00063,.00552,0.0*
1,1,.006,.00063,.00552*
20,1,.006,.00063,.00552,-.00366,.0049,0.0*
1,1,.006,-.00366,.0049*
20,1,.006,-.00366,.0049,-.00917,.00246,0.0*
1,1,.006,-.00917,.00246*
20,1,.006,-.00917,.00246,-.00734,.01838,0.0*
1,1,.006,-.00734,.01838*
20,1,.006,-.00734,.01838,.0092,.01838,0.0*
1,1,.006,.0092,.01838*
1,1,.006,.03677,.01838*
20,1,.006,.03677,.01838,.03187,.01716,0.0*
1,1,.006,.03187,.01716*
20,1,.006,.03187,.01716,.0282,.01409,0.0*
1,1,.006,.0282,.01409*
20,1,.006,.0282,.01409,.02575,.01042,0.0*
1,1,.006,.02575,.01042*
20,1,.006,.02575,.01042,.02391,.00552,0.0*
1,1,.006,.02391,.00552*
20,1,.006,.02391,.00552,.0233,0.0,0.0*
1,1,.006,.0233,0.0*
20,1,.006,.0233,0.0,.02391,-.00551,0.0*
1,1,.006,.02391,-.00551*
20,1,.006,.02391,-.00551,.02575,-.01041,0.0*
1,1,.006,.02575,-.01041*
20,1,.006,.02575,-.01041,.0282,-.01408,0.0*
1,1,.006,.0282,-.01408*
20,1,.006,.0282,-.01408,.03187,-.01715,0.0*
1,1,.006,.03187,-.01715*
20,1,.006,.03187,-.01715,.03677,-.01837,0.0*
1,1,.006,.03677,-.01837*
20,1,.006,.03677,-.01837,.04167,-.01715,0.0*
1,1,.006,.04167,-.01715*
20,1,.006,.04167,-.01715,.04535,-.01408,0.0*
1,1,.006,.04535,-.01408*
20,1,.006,.04535,-.01408,.0478,-.01041,0.0*
1,1,.006,.0478,-.01041*
20,1,.006,.0478,-.01041,.04964,-.00551,0.0*
1,1,.006,.04964,-.00551*
20,1,.006,.04964,-.00551,.05025,0.0,0.0*
1,1,.006,.05025,0.0*
20,1,.006,.05025,0.0,.04964,.00552,0.0*
1,1,.006,.04964,.00552*
20,1,.006,.04964,.00552,.0478,.01042,0.0*
1,1,.006,.0478,.01042*
20,1,.006,.0478,.01042,.04535,.01409,0.0*
1,1,.006,.04535,.01409*
20,1,.006,.04535,.01409,.04167,.01716,0.0*
1,1,.006,.04167,.01716*
20,1,.006,.04167,.01716,.03677,.01838,0.0*
1,1,.006,.03677,.01838*
%
%ADD25MACRO25*%
%AMMACRO15*
1,1,.006,.0625,0.0*
20,1,.006,.0625,0.0,.03125,.054127,0.0*
1,1,.006,.03125,.054127*
20,1,.006,.03125,.054127,-.03125,.054127,0.0*
1,1,.006,-.03125,.054127*
20,1,.006,-.03125,.054127,-.0625,0.0,0.0*
1,1,.006,-.0625,0.0*
20,1,.006,-.0625,0.0,-.03125,-.054127,0.0*
1,1,.006,-.03125,-.054127*
20,1,.006,-.03125,-.054127,.03125,-.054127,0.0*
1,1,.006,.03125,-.054127*
20,1,.006,.03125,-.054127,.0625,0.0,0.0*
1,1,.006,.0625,0.0*
1,1,.006,-.02143,-.02552*
20,1,.006,-.02143,-.02552,-.02143,.0051,0.0*
1,1,.006,-.02143,.0051*
1,1,.006,-.02143,.00051*
20,1,.006,-.02143,.00051,-.02399,.00306,0.0*
1,1,.006,-.02399,.00306*
20,1,.006,-.02399,.00306,-.02705,.00459,0.0*
1,1,.006,-.02705,.00459*
20,1,.006,-.02705,.00459,-.03062,.0051,0.0*
1,1,.006,-.03062,.0051*
20,1,.006,-.03062,.0051,-.03368,.00459,0.0*
1,1,.006,-.03368,.00459*
20,1,.006,-.03368,.00459,-.03725,.00204,0.0*
1,1,.006,-.03725,.00204*
20,1,.006,-.03725,.00204,-.0393,-.00153,0.0*
1,1,.006,-.0393,-.00153*
20,1,.006,-.0393,-.00153,-.03981,-.0051,0.0*
1,1,.006,-.03981,-.0051*
20,1,.006,-.03981,-.0051,-.0393,-.00868,0.0*
1,1,.006,-.0393,-.00868*
20,1,.006,-.0393,-.00868,-.03725,-.01225,0.0*
1,1,.006,-.03725,-.01225*
20,1,.006,-.03725,-.01225,-.03368,-.0148,0.0*
1,1,.006,-.03368,-.0148*
20,1,.006,-.03368,-.0148,-.03062,-.01531,0.0*
1,1,.006,-.03062,-.01531*
20,1,.006,-.03062,-.01531,-.02705,-.0148,0.0*
1,1,.006,-.02705,-.0148*
20,1,.006,-.02705,-.0148,-.02399,-.01327,0.0*
1,1,.006,-.02399,-.01327*
20,1,.006,-.02399,-.01327,-.02143,-.01072,0.0*
1,1,.006,-.02143,-.01072*
1,1,.006,-.01275,.0051*
20,1,.006,-.01275,.0051,-.00662,-.01531,0.0*
1,1,.006,-.00662,-.01531*
20,1,.006,-.00662,-.01531,.00001,.0051,0.0*
1,1,.006,.00001,.0051*
20,1,.006,.00001,.0051,.00664,-.01531,0.0*
1,1,.006,.00664,-.01531*
20,1,.006,.00664,-.01531,.01277,.0051,0.0*
1,1,.006,.01277,.0051*
1,1,.006,.03064,.01531*
20,1,.006,.03064,.01531,.03064,-.01531,0.0*
1,1,.006,.03064,-.01531*
1,1,.006,.0235,.0051*
20,1,.006,.0235,.0051,.03778,.0051,0.0*
1,1,.006,.03778,.0051*
%
%ADD15MACRO15*%
%AMMACRO31*
1,1,.006,0.0,.035*
20,1,.006,0.0,.035,.030311,-.0175,0.0*
1,1,.006,.030311,-.0175*
20,1,.006,.030311,-.0175,-.030311,-.0175,0.0*
1,1,.006,-.030311,-.0175*
20,1,.006,-.030311,-.0175,0.0,.035,0.0*
1,1,.006,0.0,.035*
1,1,.006,-.01433,-.00918*
20,1,.006,-.01433,-.00918,-.01433,.00184,0.0*
1,1,.006,-.01433,.00184*
1,1,.006,-.01433,.00018*
20,1,.006,-.01433,.00018,-.01341,.0011,0.0*
1,1,.006,-.01341,.0011*
20,1,.006,-.01341,.0011,-.01249,.00165,0.0*
1,1,.006,-.01249,.00165*
20,1,.006,-.01249,.00165,-.01102,.00184,0.0*
1,1,.006,-.01102,.00184*
20,1,.006,-.01102,.00184,-.00973,.00165,0.0*
1,1,.006,-.00973,.00165*
20,1,.006,-.00973,.00165,-.00845,.00073,0.0*
1,1,.006,-.00845,.00073*
20,1,.006,-.00845,.00073,-.0079,-.00055,0.0*
1,1,.006,-.0079,-.00055*
20,1,.006,-.0079,-.00055,-.00771,-.00184,0.0*
1,1,.006,-.00771,-.00184*
20,1,.006,-.00771,-.00184,-.0079,-.00312,0.0*
1,1,.006,-.0079,-.00312*
20,1,.006,-.0079,-.00312,-.00845,-.00441,0.0*
1,1,.006,-.00845,-.00441*
20,1,.006,-.00845,-.00441,-.00955,-.00514,0.0*
1,1,.006,-.00955,-.00514*
20,1,.006,-.00955,-.00514,-.01102,-.00551,0.0*
1,1,.006,-.01102,-.00551*
20,1,.006,-.01102,-.00551,-.01231,-.00533,0.0*
1,1,.006,-.01231,-.00533*
20,1,.006,-.01231,-.00533,-.01359,-.00478,0.0*
1,1,.006,-.01359,-.00478*
20,1,.006,-.01359,-.00478,-.01433,-.00404,0.0*
1,1,.006,-.01433,-.00404*
1,1,.006,-.00256,-.00551*
20,1,.006,-.00256,-.00551,-.00256,.00184,0.0*
1,1,.006,-.00256,.00184*
1,1,.006,-.00256,.00037*
20,1,.006,-.00256,.00037,-.00164,.0011,0.0*
1,1,.006,-.00164,.0011*
20,1,.006,-.00164,.0011,-.00072,.00165,0.0*
1,1,.006,-.00072,.00165*
20,1,.006,-.00072,.00165,.00056,.00184,0.0*
1,1,.006,.00056,.00184*
20,1,.006,.00056,.00184,.00148,.00165,0.0*
1,1,.006,.00148,.00165*
20,1,.006,.00148,.00165,.00258,.0011,0.0*
1,1,.006,.00258,.0011*
1,1,.006,.00718,-.00882*
20,1,.006,.00718,-.00882,.00829,-.00918,0.0*
1,1,.006,.00829,-.00918*
20,1,.006,.00829,-.00918,.00975,-.00882,0.0*
1,1,.006,.00975,-.00882*
20,1,.006,.00975,-.00882,.01067,-.00808,0.0*
1,1,.006,.01067,-.00808*
20,1,.006,.01067,-.00808,.01141,-.00716,0.0*
1,1,.006,.01141,-.00716*
20,1,.006,.01141,-.00716,.01251,-.00422,0.0*
1,1,.006,.01251,-.00422*
20,1,.006,.01251,-.00422,.0149,.00184,0.0*
1,1,.006,.0149,.00184*
1,1,.006,.00902,.00184*
20,1,.006,.00902,.00184,.01251,-.00422,0.0*
1,1,.006,.01251,-.00422*
%
%ADD31MACRO31*%
%AMMACRO24*
1,1,.006,-.0315,.063*
20,1,.006,-.0315,.063,.0315,.063,0.0*
1,1,.006,.0315,.063*
20,1,.006,.0315,.063,.04244,.062043,0.0*
1,1,.006,.04244,.062043*
20,1,.006,.04244,.062043,.053047,.059201,0.0*
1,1,.006,.053047,.059201*
20,1,.006,.053047,.059201,.063,.05456,0.0*
1,1,.006,.063,.05456*
20,1,.006,.063,.05456,.071996,.048261,0.0*
1,1,.006,.071996,.048261*
20,1,.006,.071996,.048261,.079761,.040496,0.0*
1,1,.006,.079761,.040496*
20,1,.006,.079761,.040496,.08606,.0315,0.0*
1,1,.006,.08606,.0315*
20,1,.006,.08606,.0315,.090701,.021547,0.0*
1,1,.006,.090701,.021547*
20,1,.006,.090701,.021547,.093543,.01094,0.0*
1,1,.006,.093543,.01094*
20,1,.006,.093543,.01094,.0945,0.0,0.0*
1,1,.006,.0945,0.0*
20,1,.006,.0945,0.0,.093543,-.01094,0.0*
1,1,.006,.093543,-.01094*
20,1,.006,.093543,-.01094,.090701,-.021547,0.0*
1,1,.006,.090701,-.021547*
20,1,.006,.090701,-.021547,.08606,-.0315,0.0*
1,1,.006,.08606,-.0315*
20,1,.006,.08606,-.0315,.079761,-.040496,0.0*
1,1,.006,.079761,-.040496*
20,1,.006,.079761,-.040496,.071996,-.048261,0.0*
1,1,.006,.071996,-.048261*
20,1,.006,.071996,-.048261,.063,-.05456,0.0*
1,1,.006,.063,-.05456*
20,1,.006,.063,-.05456,.053047,-.059201,0.0*
1,1,.006,.053047,-.059201*
20,1,.006,.053047,-.059201,.04244,-.062043,0.0*
1,1,.006,.04244,-.062043*
20,1,.006,.04244,-.062043,.0315,-.063,0.0*
1,1,.006,.0315,-.063*
20,1,.006,.0315,-.063,-.0315,-.063,0.0*
1,1,.006,-.0315,-.063*
20,1,.006,-.0315,-.063,-.04244,-.062043,0.0*
1,1,.006,-.04244,-.062043*
20,1,.006,-.04244,-.062043,-.053047,-.059201,0.0*
1,1,.006,-.053047,-.059201*
20,1,.006,-.053047,-.059201,-.063,-.05456,0.0*
1,1,.006,-.063,-.05456*
20,1,.006,-.063,-.05456,-.071996,-.048261,0.0*
1,1,.006,-.071996,-.048261*
20,1,.006,-.071996,-.048261,-.079761,-.040496,0.0*
1,1,.006,-.079761,-.040496*
20,1,.006,-.079761,-.040496,-.08606,-.0315,0.0*
1,1,.006,-.08606,-.0315*
20,1,.006,-.08606,-.0315,-.090701,-.021547,0.0*
1,1,.006,-.090701,-.021547*
20,1,.006,-.090701,-.021547,-.093543,-.01094,0.0*
1,1,.006,-.093543,-.01094*
20,1,.006,-.093543,-.01094,-.0945,0.0,0.0*
1,1,.006,-.0945,0.0*
20,1,.006,-.0945,0.0,-.093543,.01094,0.0*
1,1,.006,-.093543,.01094*
20,1,.006,-.093543,.01094,-.090701,.021547,0.0*
1,1,.006,-.090701,.021547*
20,1,.006,-.090701,.021547,-.08606,.0315,0.0*
1,1,.006,-.08606,.0315*
20,1,.006,-.08606,.0315,-.079761,.040496,0.0*
1,1,.006,-.079761,.040496*
20,1,.006,-.079761,.040496,-.071996,.048261,0.0*
1,1,.006,-.071996,.048261*
20,1,.006,-.071996,.048261,-.063,.05456,0.0*
1,1,.006,-.063,.05456*
20,1,.006,-.063,.05456,-.053047,.059201,0.0*
1,1,.006,-.053047,.059201*
20,1,.006,-.053047,.059201,-.04244,.062043,0.0*
1,1,.006,-.04244,.062043*
20,1,.006,-.04244,.062043,-.0315,.063,0.0*
1,1,.006,-.0315,.063*
1,1,.006,-.0588,-.00735*
20,1,.006,-.0588,-.00735,-.0441,.02205,0.0*
1,1,.006,-.0441,.02205*
20,1,.006,-.0441,.02205,-.0294,-.00735,0.0*
1,1,.006,-.0294,-.00735*
1,1,.006,-.0441,.02205*
20,1,.006,-.0441,.02205,-.0441,-.03675,0.0*
1,1,.006,-.0441,-.03675*
1,1,.006,-.01616,-.02205*
20,1,.006,-.01616,-.02205,-.01616,.02205,0.0*
1,1,.006,-.01616,.02205*
20,1,.006,-.01616,.02205,-.00146,.02205,0.0*
1,1,.006,-.00146,.02205*
20,1,.006,-.00146,.02205,.00442,.01984,0.0*
1,1,.006,.00442,.01984*
20,1,.006,.00442,.01984,.00883,.0169,0.0*
1,1,.006,.00883,.0169*
20,1,.006,.00883,.0169,.01251,.0125,0.0*
1,1,.006,.01251,.0125*
20,1,.006,.01251,.0125,.01545,.00735,0.0*
1,1,.006,.01545,.00735*
20,1,.006,.01545,.00735,.01618,0.0,0.0*
1,1,.006,.01618,0.0*
20,1,.006,.01618,0.0,.01545,-.00735,0.0*
1,1,.006,.01545,-.00735*
20,1,.006,.01545,-.00735,.01251,-.0125,0.0*
1,1,.006,.01251,-.0125*
20,1,.006,.01251,-.0125,.00883,-.01691,0.0*
1,1,.006,.00883,-.01691*
20,1,.006,.00883,-.01691,.00442,-.01985,0.0*
1,1,.006,.00442,-.01985*
20,1,.006,.00442,-.01985,-.00146,-.02205,0.0*
1,1,.006,-.00146,-.02205*
20,1,.006,-.00146,-.02205,-.01616,-.02205,0.0*
1,1,.006,-.01616,-.02205*
1,1,.006,.02868,-.01617*
20,1,.006,.02868,-.01617,.03457,-.01985,0.0*
1,1,.006,.03457,-.01985*
20,1,.006,.03457,-.01985,.04118,-.02205,0.0*
1,1,.006,.04118,-.02205*
20,1,.006,.04118,-.02205,.04706,-.02205,0.0*
1,1,.006,.04706,-.02205*
20,1,.006,.04706,-.02205,.05294,-.01985,0.0*
1,1,.006,.05294,-.01985*
20,1,.006,.05294,-.01985,.05735,-.01617,0.0*
1,1,.006,.05735,-.01617*
20,1,.006,.05735,-.01617,.05956,-.01102,0.0*
1,1,.006,.05956,-.01102*
20,1,.006,.05956,-.01102,.05809,-.00588,0.0*
1,1,.006,.05809,-.00588*
20,1,.006,.05809,-.00588,.05441,-.00147,0.0*
1,1,.006,.05441,-.00147*
20,1,.006,.05441,-.00147,.04779,.00147,0.0*
1,1,.006,.04779,.00147*
20,1,.006,.04779,.00147,.03898,.00294,0.0*
1,1,.006,.03898,.00294*
20,1,.006,.03898,.00294,.03383,.00588,0.0*
1,1,.006,.03383,.00588*
20,1,.006,.03383,.00588,.03162,.01102,0.0*
1,1,.006,.03162,.01102*
20,1,.006,.03162,.01102,.0331,.01617,0.0*
1,1,.006,.0331,.01617*
20,1,.006,.0331,.01617,.03677,.01984,0.0*
1,1,.006,.03677,.01984*
20,1,.006,.03677,.01984,.04191,.02205,0.0*
1,1,.006,.04191,.02205*
20,1,.006,.04191,.02205,.04706,.02205,0.0*
1,1,.006,.04706,.02205*
20,1,.006,.04706,.02205,.05221,.02058,0.0*
1,1,.006,.05221,.02058*
20,1,.006,.05221,.02058,.05662,.0169,0.0*
1,1,.006,.05662,.0169*
%
%ADD24MACRO24*%
%AMMACRO30*
1,1,.006,0.0,.035*
20,1,.006,0.0,.035,.030311,-.0175,0.0*
1,1,.006,.030311,-.0175*
20,1,.006,.030311,-.0175,-.030311,-.0175,0.0*
1,1,.006,-.030311,-.0175*
20,1,.006,-.030311,-.0175,0.0,.035,0.0*
1,1,.006,0.0,.035*
1,1,.006,-.01433,-.00918*
20,1,.006,-.01433,-.00918,-.01433,.00184,0.0*
1,1,.006,-.01433,.00184*
1,1,.006,-.01433,.00018*
20,1,.006,-.01433,.00018,-.01341,.0011,0.0*
1,1,.006,-.01341,.0011*
20,1,.006,-.01341,.0011,-.01249,.00165,0.0*
1,1,.006,-.01249,.00165*
20,1,.006,-.01249,.00165,-.01102,.00184,0.0*
1,1,.006,-.01102,.00184*
20,1,.006,-.01102,.00184,-.00973,.00165,0.0*
1,1,.006,-.00973,.00165*
20,1,.006,-.00973,.00165,-.00845,.00073,0.0*
1,1,.006,-.00845,.00073*
20,1,.006,-.00845,.00073,-.0079,-.00055,0.0*
1,1,.006,-.0079,-.00055*
20,1,.006,-.0079,-.00055,-.00771,-.00184,0.0*
1,1,.006,-.00771,-.00184*
20,1,.006,-.00771,-.00184,-.0079,-.00312,0.0*
1,1,.006,-.0079,-.00312*
20,1,.006,-.0079,-.00312,-.00845,-.00441,0.0*
1,1,.006,-.00845,-.00441*
20,1,.006,-.00845,-.00441,-.00955,-.00514,0.0*
1,1,.006,-.00955,-.00514*
20,1,.006,-.00955,-.00514,-.01102,-.00551,0.0*
1,1,.006,-.01102,-.00551*
20,1,.006,-.01102,-.00551,-.01231,-.00533,0.0*
1,1,.006,-.01231,-.00533*
20,1,.006,-.01231,-.00533,-.01359,-.00478,0.0*
1,1,.006,-.01359,-.00478*
20,1,.006,-.01359,-.00478,-.01433,-.00404,0.0*
1,1,.006,-.01433,-.00404*
1,1,.006,-.00385,-.00882*
20,1,.006,-.00385,-.00882,-.00274,-.00918,0.0*
1,1,.006,-.00274,-.00918*
20,1,.006,-.00274,-.00918,-.00128,-.00882,0.0*
1,1,.006,-.00128,-.00882*
20,1,.006,-.00128,-.00882,-.00036,-.00808,0.0*
1,1,.006,-.00036,-.00808*
20,1,.006,-.00036,-.00808,.00038,-.00716,0.0*
1,1,.006,.00038,-.00716*
20,1,.006,.00038,-.00716,.00148,-.00422,0.0*
1,1,.006,.00148,-.00422*
20,1,.006,.00148,-.00422,.00387,.00184,0.0*
1,1,.006,.00387,.00184*
1,1,.006,-.00201,.00184*
20,1,.006,-.00201,.00184,.00148,-.00422,0.0*
1,1,.006,.00148,-.00422*
1,1,.006,.01104,.00551*
20,1,.006,.01104,.00551,.01104,-.00551,0.0*
1,1,.006,.01104,-.00551*
1,1,.006,.00847,.00184*
20,1,.006,.00847,.00184,.01361,.00184,0.0*
1,1,.006,.01361,.00184*
%
%ADD30MACRO30*%
%AMMACRO18*
1,1,.006,0.0,.035*
20,1,.006,0.0,.035,.030311,-.0175,0.0*
1,1,.006,.030311,-.0175*
20,1,.006,.030311,-.0175,-.030311,-.0175,0.0*
1,1,.006,-.030311,-.0175*
20,1,.006,-.030311,-.0175,0.0,.035,0.0*
1,1,.006,0.0,.035*
1,1,.006,-.01102,.00551*
20,1,.006,-.01102,.00551,-.01249,.00514,0.0*
1,1,.006,-.01249,.00514*
20,1,.006,-.01249,.00514,-.01359,.00422,0.0*
1,1,.006,-.01359,.00422*
20,1,.006,-.01359,.00422,-.01433,.00312,0.0*
1,1,.006,-.01433,.00312*
20,1,.006,-.01433,.00312,-.01488,.00165,0.0*
1,1,.006,-.01488,.00165*
20,1,.006,-.01488,.00165,-.01506,0.0,0.0*
1,1,.006,-.01506,0.0*
20,1,.006,-.01506,0.0,-.01488,-.00165,0.0*
1,1,.006,-.01488,-.00165*
20,1,.006,-.01488,-.00165,-.01433,-.00312,0.0*
1,1,.006,-.01433,-.00312*
20,1,.006,-.01433,-.00312,-.01359,-.00422,0.0*
1,1,.006,-.01359,-.00422*
20,1,.006,-.01359,-.00422,-.01249,-.00514,0.0*
1,1,.006,-.01249,-.00514*
20,1,.006,-.01249,-.00514,-.01102,-.00551,0.0*
1,1,.006,-.01102,-.00551*
20,1,.006,-.01102,-.00551,-.00955,-.00514,0.0*
1,1,.006,-.00955,-.00514*
20,1,.006,-.00955,-.00514,-.00845,-.00422,0.0*
1,1,.006,-.00845,-.00422*
20,1,.006,-.00845,-.00422,-.00771,-.00312,0.0*
1,1,.006,-.00771,-.00312*
20,1,.006,-.00771,-.00312,-.00716,-.00165,0.0*
1,1,.006,-.00716,-.00165*
20,1,.006,-.00716,-.00165,-.00698,0.0,0.0*
1,1,.006,-.00698,0.0*
20,1,.006,-.00698,0.0,-.00716,.00165,0.0*
1,1,.006,-.00716,.00165*
20,1,.006,-.00716,.00165,-.00771,.00312,0.0*
1,1,.006,-.00771,.00312*
20,1,.006,-.00771,.00312,-.00845,.00422,0.0*
1,1,.006,-.00845,.00422*
20,1,.006,-.00845,.00422,-.00955,.00514,0.0*
1,1,.006,-.00955,.00514*
20,1,.006,-.00955,.00514,-.01102,.00551,0.0*
1,1,.006,-.01102,.00551*
1,1,.006,.00221,-.00551*
20,1,.006,.00221,-.00551,.00221,.00551,0.0*
1,1,.006,.00221,.00551*
20,1,.006,.00221,.00551,-.00458,-.00239,0.0*
1,1,.006,-.00458,-.00239*
20,1,.006,-.00458,-.00239,.0046,-.00239,0.0*
1,1,.006,.0046,-.00239*
1,1,.006,.01104,-.00551*
20,1,.006,.01104,-.00551,.01104,.00551,0.0*
1,1,.006,.01104,.00551*
20,1,.006,.01104,.00551,.00884,.00331,0.0*
1,1,.006,.00884,.00331*
1,1,.006,.00884,-.00551*
20,1,.006,.00884,-.00551,.01324,-.00551,0.0*
1,1,.006,.01324,-.00551*
%
%ADD18MACRO18*%
%AMMACRO16*
1,1,.006,0.0,.035*
20,1,.006,0.0,.035,.030311,-.0175,0.0*
1,1,.006,.030311,-.0175*
20,1,.006,.030311,-.0175,-.030311,-.0175,0.0*
1,1,.006,-.030311,-.0175*
20,1,.006,-.030311,-.0175,0.0,.035,0.0*
1,1,.006,0.0,.035*
1,1,.006,-.01102,.00551*
20,1,.006,-.01102,.00551,-.01249,.00514,0.0*
1,1,.006,-.01249,.00514*
20,1,.006,-.01249,.00514,-.01359,.00422,0.0*
1,1,.006,-.01359,.00422*
20,1,.006,-.01359,.00422,-.01433,.00312,0.0*
1,1,.006,-.01433,.00312*
20,1,.006,-.01433,.00312,-.01488,.00165,0.0*
1,1,.006,-.01488,.00165*
20,1,.006,-.01488,.00165,-.01506,0.0,0.0*
1,1,.006,-.01506,0.0*
20,1,.006,-.01506,0.0,-.01488,-.00165,0.0*
1,1,.006,-.01488,-.00165*
20,1,.006,-.01488,-.00165,-.01433,-.00312,0.0*
1,1,.006,-.01433,-.00312*
20,1,.006,-.01433,-.00312,-.01359,-.00422,0.0*
1,1,.006,-.01359,-.00422*
20,1,.006,-.01359,-.00422,-.01249,-.00514,0.0*
1,1,.006,-.01249,-.00514*
20,1,.006,-.01249,-.00514,-.01102,-.00551,0.0*
1,1,.006,-.01102,-.00551*
20,1,.006,-.01102,-.00551,-.00955,-.00514,0.0*
1,1,.006,-.00955,-.00514*
20,1,.006,-.00955,-.00514,-.00845,-.00422,0.0*
1,1,.006,-.00845,-.00422*
20,1,.006,-.00845,-.00422,-.00771,-.00312,0.0*
1,1,.006,-.00771,-.00312*
20,1,.006,-.00771,-.00312,-.00716,-.00165,0.0*
1,1,.006,-.00716,-.00165*
20,1,.006,-.00716,-.00165,-.00698,0.0,0.0*
1,1,.006,-.00698,0.0*
20,1,.006,-.00698,0.0,-.00716,.00165,0.0*
1,1,.006,-.00716,.00165*
20,1,.006,-.00716,.00165,-.00771,.00312,0.0*
1,1,.006,-.00771,.00312*
20,1,.006,-.00771,.00312,-.00845,.00422,0.0*
1,1,.006,-.00845,.00422*
20,1,.006,-.00845,.00422,-.00955,.00514,0.0*
1,1,.006,-.00955,.00514*
20,1,.006,-.00955,.00514,-.01102,.00551,0.0*
1,1,.006,-.01102,.00551*
1,1,.006,.00221,-.00551*
20,1,.006,.00221,-.00551,.00221,.00551,0.0*
1,1,.006,.00221,.00551*
20,1,.006,.00221,.00551,-.00458,-.00239,0.0*
1,1,.006,-.00458,-.00239*
20,1,.006,-.00458,-.00239,.0046,-.00239,0.0*
1,1,.006,.0046,-.00239*
1,1,.006,.01324,-.00551*
20,1,.006,.01324,-.00551,.01324,.00551,0.0*
1,1,.006,.01324,.00551*
20,1,.006,.01324,.00551,.00645,-.00239,0.0*
1,1,.006,.00645,-.00239*
20,1,.006,.00645,-.00239,.01563,-.00239,0.0*
1,1,.006,.01563,-.00239*
%
%ADD16MACRO16*%
%AMMACRO29*
1,1,.006,0.0,.035*
20,1,.006,0.0,.035,.030311,-.0175,0.0*
1,1,.006,.030311,-.0175*
20,1,.006,.030311,-.0175,-.030311,-.0175,0.0*
1,1,.006,-.030311,-.0175*
20,1,.006,-.030311,-.0175,0.0,.035,0.0*
1,1,.006,0.0,.035*
1,1,.006,-.01102,.00551*
20,1,.006,-.01102,.00551,-.01249,.00514,0.0*
1,1,.006,-.01249,.00514*
20,1,.006,-.01249,.00514,-.01359,.00422,0.0*
1,1,.006,-.01359,.00422*
20,1,.006,-.01359,.00422,-.01433,.00312,0.0*
1,1,.006,-.01433,.00312*
20,1,.006,-.01433,.00312,-.01488,.00165,0.0*
1,1,.006,-.01488,.00165*
20,1,.006,-.01488,.00165,-.01506,0.0,0.0*
1,1,.006,-.01506,0.0*
20,1,.006,-.01506,0.0,-.01488,-.00165,0.0*
1,1,.006,-.01488,-.00165*
20,1,.006,-.01488,-.00165,-.01433,-.00312,0.0*
1,1,.006,-.01433,-.00312*
20,1,.006,-.01433,-.00312,-.01359,-.00422,0.0*
1,1,.006,-.01359,-.00422*
20,1,.006,-.01359,-.00422,-.01249,-.00514,0.0*
1,1,.006,-.01249,-.00514*
20,1,.006,-.01249,-.00514,-.01102,-.00551,0.0*
1,1,.006,-.01102,-.00551*
20,1,.006,-.01102,-.00551,-.00955,-.00514,0.0*
1,1,.006,-.00955,-.00514*
20,1,.006,-.00955,-.00514,-.00845,-.00422,0.0*
1,1,.006,-.00845,-.00422*
20,1,.006,-.00845,-.00422,-.00771,-.00312,0.0*
1,1,.006,-.00771,-.00312*
20,1,.006,-.00771,-.00312,-.00716,-.00165,0.0*
1,1,.006,-.00716,-.00165*
20,1,.006,-.00716,-.00165,-.00698,0.0,0.0*
1,1,.006,-.00698,0.0*
20,1,.006,-.00698,0.0,-.00716,.00165,0.0*
1,1,.006,-.00716,.00165*
20,1,.006,-.00716,.00165,-.00771,.00312,0.0*
1,1,.006,-.00771,.00312*
20,1,.006,-.00771,.00312,-.00845,.00422,0.0*
1,1,.006,-.00845,.00422*
20,1,.006,-.00845,.00422,-.00955,.00514,0.0*
1,1,.006,-.00955,.00514*
20,1,.006,-.00955,.00514,-.01102,.00551,0.0*
1,1,.006,-.01102,.00551*
1,1,.006,.00221,-.00551*
20,1,.006,.00221,-.00551,.00221,.00551,0.0*
1,1,.006,.00221,.00551*
20,1,.006,.00221,.00551,-.00458,-.00239,0.0*
1,1,.006,-.00458,-.00239*
20,1,.006,-.00458,-.00239,.0046,-.00239,0.0*
1,1,.006,.0046,-.00239*
1,1,.006,.00755,-.00092*
20,1,.006,.00755,-.00092,.00884,.00037,0.0*
1,1,.006,.00884,.00037*
20,1,.006,.00884,.00037,.00994,.0011,0.0*
1,1,.006,.00994,.0011*
20,1,.006,.00994,.0011,.01141,.00147,0.0*
1,1,.006,.01141,.00147*
20,1,.006,.01141,.00147,.01269,.0011,0.0*
1,1,.006,.01269,.0011*
20,1,.006,.01269,.0011,.01361,.00037,0.0*
1,1,.006,.01361,.00037*
20,1,.006,.01361,.00037,.01435,-.00073,0.0*
1,1,.006,.01435,-.00073*
20,1,.006,.01435,-.00073,.01453,-.00202,0.0*
1,1,.006,.01453,-.00202*
20,1,.006,.01453,-.00202,.01435,-.00312,0.0*
1,1,.006,.01435,-.00312*
20,1,.006,.01435,-.00312,.01361,-.00422,0.0*
1,1,.006,.01361,-.00422*
20,1,.006,.01361,-.00422,.01251,-.00514,0.0*
1,1,.006,.01251,-.00514*
20,1,.006,.01251,-.00514,.01122,-.00551,0.0*
1,1,.006,.01122,-.00551*
20,1,.006,.01122,-.00551,.00975,-.00514,0.0*
1,1,.006,.00975,-.00514*
20,1,.006,.00975,-.00514,.00847,-.00404,0.0*
1,1,.006,.00847,-.00404*
20,1,.006,.00847,-.00404,.00773,-.00239,0.0*
1,1,.006,.00773,-.00239*
20,1,.006,.00773,-.00239,.00755,-.00055,0.0*
1,1,.006,.00755,-.00055*
20,1,.006,.00755,-.00055,.00792,.00184,0.0*
1,1,.006,.00792,.00184*
20,1,.006,.00792,.00184,.00847,.00312,0.0*
1,1,.006,.00847,.00312*
20,1,.006,.00847,.00312,.00939,.00441,0.0*
1,1,.006,.00939,.00441*
20,1,.006,.00939,.00441,.01067,.00533,0.0*
1,1,.006,.01067,.00533*
20,1,.006,.01067,.00533,.01196,.00551,0.0*
1,1,.006,.01196,.00551*
20,1,.006,.01196,.00551,.01324,.00514,0.0*
1,1,.006,.01324,.00514*
20,1,.006,.01324,.00514,.01416,.00422,0.0*
1,1,.006,.01416,.00422*
%
%ADD29MACRO29*%
%AMMACRO38*
1,1,.006,-.0265,.022*
20,1,.006,-.0265,.022,.0265,.022,0.0*
1,1,.006,.0265,.022*
20,1,.006,.0265,.022,.03032,.021666,0.0*
1,1,.006,.03032,.021666*
20,1,.006,.03032,.021666,.034024,.020673,0.0*
1,1,.006,.034024,.020673*
20,1,.006,.034024,.020673,.0375,.019053,0.0*
1,1,.006,.0375,.019053*
20,1,.006,.0375,.019053,.040641,.016853,0.0*
1,1,.006,.040641,.016853*
20,1,.006,.040641,.016853,.043353,.014141,0.0*
1,1,.006,.043353,.014141*
20,1,.006,.043353,.014141,.045553,.011,0.0*
1,1,.006,.045553,.011*
20,1,.006,.045553,.011,.047173,.007524,0.0*
1,1,.006,.047173,.007524*
20,1,.006,.047173,.007524,.048166,.00382,0.0*
1,1,.006,.048166,.00382*
20,1,.006,.048166,.00382,.0485,0.0,0.0*
1,1,.006,.0485,0.0*
20,1,.006,.0485,0.0,.048166,-.00382,0.0*
1,1,.006,.048166,-.00382*
20,1,.006,.048166,-.00382,.047173,-.007524,0.0*
1,1,.006,.047173,-.007524*
20,1,.006,.047173,-.007524,.045553,-.011,0.0*
1,1,.006,.045553,-.011*
20,1,.006,.045553,-.011,.043353,-.014141,0.0*
1,1,.006,.043353,-.014141*
20,1,.006,.043353,-.014141,.040641,-.016853,0.0*
1,1,.006,.040641,-.016853*
20,1,.006,.040641,-.016853,.0375,-.019053,0.0*
1,1,.006,.0375,-.019053*
20,1,.006,.0375,-.019053,.034024,-.020673,0.0*
1,1,.006,.034024,-.020673*
20,1,.006,.034024,-.020673,.03032,-.021666,0.0*
1,1,.006,.03032,-.021666*
20,1,.006,.03032,-.021666,.0265,-.022,0.0*
1,1,.006,.0265,-.022*
20,1,.006,.0265,-.022,-.0265,-.022,0.0*
1,1,.006,-.0265,-.022*
20,1,.006,-.0265,-.022,-.03032,-.021666,0.0*
1,1,.006,-.03032,-.021666*
20,1,.006,-.03032,-.021666,-.034024,-.020673,0.0*
1,1,.006,-.034024,-.020673*
20,1,.006,-.034024,-.020673,-.0375,-.019053,0.0*
1,1,.006,-.0375,-.019053*
20,1,.006,-.0375,-.019053,-.040641,-.016853,0.0*
1,1,.006,-.040641,-.016853*
20,1,.006,-.040641,-.016853,-.043353,-.014141,0.0*
1,1,.006,-.043353,-.014141*
20,1,.006,-.043353,-.014141,-.045553,-.011,0.0*
1,1,.006,-.045553,-.011*
20,1,.006,-.045553,-.011,-.047173,-.007524,0.0*
1,1,.006,-.047173,-.007524*
20,1,.006,-.047173,-.007524,-.048166,-.00382,0.0*
1,1,.006,-.048166,-.00382*
20,1,.006,-.048166,-.00382,-.0485,0.0,0.0*
1,1,.006,-.0485,0.0*
20,1,.006,-.0485,0.0,-.048166,.00382,0.0*
1,1,.006,-.048166,.00382*
20,1,.006,-.048166,.00382,-.047173,.007524,0.0*
1,1,.006,-.047173,.007524*
20,1,.006,-.047173,.007524,-.045553,.011,0.0*
1,1,.006,-.045553,.011*
20,1,.006,-.045553,.011,-.043353,.014141,0.0*
1,1,.006,-.043353,.014141*
20,1,.006,-.043353,.014141,-.040641,.016853,0.0*
1,1,.006,-.040641,.016853*
20,1,.006,-.040641,.016853,-.0375,.019053,0.0*
1,1,.006,-.0375,.019053*
20,1,.006,-.0375,.019053,-.034024,.020673,0.0*
1,1,.006,-.034024,.020673*
20,1,.006,-.034024,.020673,-.03032,.021666,0.0*
1,1,.006,-.03032,.021666*
20,1,.006,-.03032,.021666,-.0265,.022,0.0*
1,1,.006,-.0265,.022*
1,1,.006,-.01232,-.0077*
20,1,.006,-.01232,-.0077,-.01232,.0077,0.0*
1,1,.006,-.01232,.0077*
20,1,.006,-.01232,.0077,-.02182,-.00334,0.0*
1,1,.006,-.02182,-.00334*
20,1,.006,-.02182,-.00334,-.00898,-.00334,0.0*
1,1,.006,-.00898,-.00334*
1,1,.006,-.00461,-.0077*
20,1,.006,-.00461,-.0077,-.00461,.0077,0.0*
1,1,.006,-.00461,.0077*
1,1,.006,-.00461,0.0*
20,1,.006,-.00461,0.0,-.00333,.00154,0.0*
1,1,.006,-.00333,.00154*
20,1,.006,-.00333,.00154,-.00179,.00231,0.0*
1,1,.006,-.00179,.00231*
20,1,.006,-.00179,.00231,-.00025,.00257,0.0*
1,1,.006,-.00025,.00257*
20,1,.006,-.00025,.00257,.00206,.00205,0.0*
1,1,.006,.00206,.00205*
20,1,.006,.00206,.00205,.0036,.00103,0.0*
1,1,.006,.0036,.00103*
20,1,.006,.0036,.00103,.00463,-.00077,0.0*
1,1,.006,.00463,-.00077*
20,1,.006,.00463,-.00077,.00463,-.00282,0.0*
1,1,.006,.00463,-.00282*
20,1,.006,.00463,-.00282,.00412,-.00488,0.0*
1,1,.006,.00412,-.00488*
20,1,.006,.00412,-.00488,.00309,-.00642,0.0*
1,1,.006,.00309,-.00642*
20,1,.006,.00309,-.00642,.00129,-.00744,0.0*
1,1,.006,.00129,-.00744*
20,1,.006,.00129,-.00744,-.00025,-.0077,0.0*
1,1,.006,-.00025,-.0077*
20,1,.006,-.00025,-.0077,-.00179,-.00744,0.0*
1,1,.006,-.00179,-.00744*
20,1,.006,-.00179,-.00744,-.00333,-.00667,0.0*
1,1,.006,-.00333,-.00667*
20,1,.006,-.00333,-.00667,-.00461,-.00539,0.0*
1,1,.006,-.00461,-.00539*
1,1,.006,.01183,-.01155*
20,1,.006,.01183,-.01155,.01362,-.01258,0.0*
1,1,.006,.01362,-.01258*
20,1,.006,.01362,-.01258,.01568,-.01283,0.0*
1,1,.006,.01568,-.01283*
20,1,.006,.01568,-.01283,.01747,-.01258,0.0*
1,1,.006,.01747,-.01258*
20,1,.006,.01747,-.01258,.01901,-.01129,0.0*
1,1,.006,.01901,-.01129*
20,1,.006,.01901,-.01129,.02004,-.0095,0.0*
1,1,.006,.02004,-.0095*
20,1,.006,.02004,-.0095,.02004,.00257,0.0*
1,1,.006,.02004,.00257*
1,1,.006,.02004,.00051*
20,1,.006,.02004,.00051,.01901,.00154,0.0*
1,1,.006,.01901,.00154*
20,1,.006,.01901,.00154,.01747,.00231,0.0*
1,1,.006,.01747,.00231*
20,1,.006,.01747,.00231,.01568,.00257,0.0*
1,1,.006,.01568,.00257*
20,1,.006,.01568,.00257,.01362,.00205,0.0*
1,1,.006,.01362,.00205*
20,1,.006,.01362,.00205,.01234,.00103,0.0*
1,1,.006,.01234,.00103*
20,1,.006,.01234,.00103,.01131,-.00077,0.0*
1,1,.006,.01131,-.00077*
20,1,.006,.01131,-.00077,.0108,-.00257,0.0*
1,1,.006,.0108,-.00257*
20,1,.006,.0108,-.00257,.01106,-.00411,0.0*
1,1,.006,.01106,-.00411*
20,1,.006,.01106,-.00411,.01208,-.0059,0.0*
1,1,.006,.01208,-.0059*
20,1,.006,.01208,-.0059,.01362,-.00719,0.0*
1,1,.006,.01362,-.00719*
20,1,.006,.01362,-.00719,.01568,-.0077,0.0*
1,1,.006,.01568,-.0077*
20,1,.006,.01568,-.0077,.01722,-.00744,0.0*
1,1,.006,.01722,-.00744*
20,1,.006,.01722,-.00744,.01901,-.00642,0.0*
1,1,.006,.01901,-.00642*
20,1,.006,.01901,-.00642,.02004,-.00539,0.0*
1,1,.006,.02004,-.00539*
%
%ADD38MACRO38*%
%AMMACRO43*
1,1,.006,0.0,.035*
20,1,.006,0.0,.035,.030311,-.0175,0.0*
1,1,.006,.030311,-.0175*
20,1,.006,.030311,-.0175,-.030311,-.0175,0.0*
1,1,.006,-.030311,-.0175*
20,1,.006,-.030311,-.0175,0.0,.035,0.0*
1,1,.006,0.0,.035*
1,1,.006,-.01102,.00551*
20,1,.006,-.01102,.00551,-.01249,.00514,0.0*
1,1,.006,-.01249,.00514*
20,1,.006,-.01249,.00514,-.01359,.00422,0.0*
1,1,.006,-.01359,.00422*
20,1,.006,-.01359,.00422,-.01433,.00312,0.0*
1,1,.006,-.01433,.00312*
20,1,.006,-.01433,.00312,-.01488,.00165,0.0*
1,1,.006,-.01488,.00165*
20,1,.006,-.01488,.00165,-.01506,0.0,0.0*
1,1,.006,-.01506,0.0*
20,1,.006,-.01506,0.0,-.01488,-.00165,0.0*
1,1,.006,-.01488,-.00165*
20,1,.006,-.01488,-.00165,-.01433,-.00312,0.0*
1,1,.006,-.01433,-.00312*
20,1,.006,-.01433,-.00312,-.01359,-.00422,0.0*
1,1,.006,-.01359,-.00422*
20,1,.006,-.01359,-.00422,-.01249,-.00514,0.0*
1,1,.006,-.01249,-.00514*
20,1,.006,-.01249,-.00514,-.01102,-.00551,0.0*
1,1,.006,-.01102,-.00551*
20,1,.006,-.01102,-.00551,-.00955,-.00514,0.0*
1,1,.006,-.00955,-.00514*
20,1,.006,-.00955,-.00514,-.00845,-.00422,0.0*
1,1,.006,-.00845,-.00422*
20,1,.006,-.00845,-.00422,-.00771,-.00312,0.0*
1,1,.006,-.00771,-.00312*
20,1,.006,-.00771,-.00312,-.00716,-.00165,0.0*
1,1,.006,-.00716,-.00165*
20,1,.006,-.00716,-.00165,-.00698,0.0,0.0*
1,1,.006,-.00698,0.0*
20,1,.006,-.00698,0.0,-.00716,.00165,0.0*
1,1,.006,-.00716,.00165*
20,1,.006,-.00716,.00165,-.00771,.00312,0.0*
1,1,.006,-.00771,.00312*
20,1,.006,-.00771,.00312,-.00845,.00422,0.0*
1,1,.006,-.00845,.00422*
20,1,.006,-.00845,.00422,-.00955,.00514,0.0*
1,1,.006,-.00955,.00514*
20,1,.006,-.00955,.00514,-.01102,.00551,0.0*
1,1,.006,-.01102,.00551*
1,1,.006,-.00348,-.00092*
20,1,.006,-.00348,-.00092,-.00219,.00037,0.0*
1,1,.006,-.00219,.00037*
20,1,.006,-.00219,.00037,-.00109,.0011,0.0*
1,1,.006,-.00109,.0011*
20,1,.006,-.00109,.0011,.00038,.00147,0.0*
1,1,.006,.00038,.00147*
20,1,.006,.00038,.00147,.00166,.0011,0.0*
1,1,.006,.00166,.0011*
20,1,.006,.00166,.0011,.00258,.00037,0.0*
1,1,.006,.00258,.00037*
20,1,.006,.00258,.00037,.00332,-.00073,0.0*
1,1,.006,.00332,-.00073*
20,1,.006,.00332,-.00073,.0035,-.00202,0.0*
1,1,.006,.0035,-.00202*
20,1,.006,.0035,-.00202,.00332,-.00312,0.0*
1,1,.006,.00332,-.00312*
20,1,.006,.00332,-.00312,.00258,-.00422,0.0*
1,1,.006,.00258,-.00422*
20,1,.006,.00258,-.00422,.00148,-.00514,0.0*
1,1,.006,.00148,-.00514*
20,1,.006,.00148,-.00514,.00019,-.00551,0.0*
1,1,.006,.00019,-.00551*
20,1,.006,.00019,-.00551,-.00128,-.00514,0.0*
1,1,.006,-.00128,-.00514*
20,1,.006,-.00128,-.00514,-.00256,-.00404,0.0*
1,1,.006,-.00256,-.00404*
20,1,.006,-.00256,-.00404,-.0033,-.00239,0.0*
1,1,.006,-.0033,-.00239*
20,1,.006,-.0033,-.00239,-.00348,-.00055,0.0*
1,1,.006,-.00348,-.00055*
20,1,.006,-.00348,-.00055,-.00311,.00184,0.0*
1,1,.006,-.00311,.00184*
20,1,.006,-.00311,.00184,-.00256,.00312,0.0*
1,1,.006,-.00256,.00312*
20,1,.006,-.00256,.00312,-.00164,.00441,0.0*
1,1,.006,-.00164,.00441*
20,1,.006,-.00164,.00441,-.00036,.00533,0.0*
1,1,.006,-.00036,.00533*
20,1,.006,-.00036,.00533,.00093,.00551,0.0*
1,1,.006,.00093,.00551*
20,1,.006,.00093,.00551,.00221,.00514,0.0*
1,1,.006,.00221,.00514*
20,1,.006,.00221,.00514,.00313,.00422,0.0*
1,1,.006,.00313,.00422*
1,1,.006,.01067,-.00551*
20,1,.006,.01067,-.00551,.01104,-.00312,0.0*
1,1,.006,.01104,-.00312*
20,1,.006,.01104,-.00312,.01159,-.0011,0.0*
1,1,.006,.01159,-.0011*
20,1,.006,.01159,-.0011,.01233,.00073,0.0*
1,1,.006,.01233,.00073*
20,1,.006,.01233,.00073,.01324,.00275,0.0*
1,1,.006,.01324,.00275*
20,1,.006,.01324,.00275,.01471,.00551,0.0*
1,1,.006,.01471,.00551*
20,1,.006,.01471,.00551,.00737,.00551,0.0*
1,1,.006,.00737,.00551*
%
%ADD43MACRO43*%
%AMMACRO14*
1,1,.006,.0735,0.0*
20,1,.006,.0735,0.0,.03675,.063653,0.0*
1,1,.006,.03675,.063653*
20,1,.006,.03675,.063653,-.03675,.063653,0.0*
1,1,.006,-.03675,.063653*
20,1,.006,-.03675,.063653,-.0735,0.0,0.0*
1,1,.006,-.0735,0.0*
20,1,.006,-.0735,0.0,-.03675,-.063653,0.0*
1,1,.006,-.03675,-.063653*
20,1,.006,-.03675,-.063653,.03675,-.063653,0.0*
1,1,.006,.03675,-.063653*
20,1,.006,.03675,-.063653,.0735,0.0,0.0*
1,1,.006,.0735,0.0*
1,1,.006,-.03601,-.018*
20,1,.006,-.03601,-.018,-.03601,.01801,0.0*
1,1,.006,-.03601,.01801*
20,1,.006,-.03601,.01801,-.04321,.01081,0.0*
1,1,.006,-.04321,.01081*
1,1,.006,-.04321,-.018*
20,1,.006,-.04321,-.018,-.0288,-.018,0.0*
1,1,.006,-.0288,-.018*
1,1,.006,.00722,-.018*
20,1,.006,.00722,-.018,.00722,.01801,0.0*
1,1,.006,.00722,.01801*
20,1,.006,.00722,.01801,-.01499,-.0078,0.0*
1,1,.006,-.01499,-.0078*
20,1,.006,-.01499,-.0078,.01502,-.0078,0.0*
1,1,.006,.01502,-.0078*
1,1,.006,.03483,-.018*
20,1,.006,.03483,-.018,.03603,-.0102,0.0*
1,1,.006,.03603,-.0102*
20,1,.006,.03603,-.0102,.03784,-.0036,0.0*
1,1,.006,.03784,-.0036*
20,1,.006,.03784,-.0036,.04024,.00241,0.0*
1,1,.006,.04024,.00241*
20,1,.006,.04024,.00241,.04324,.00901,0.0*
1,1,.006,.04324,.00901*
20,1,.006,.04324,.00901,.04804,.01801,0.0*
1,1,.006,.04804,.01801*
20,1,.006,.04804,.01801,.02403,.01801,0.0*
1,1,.006,.02403,.01801*
%
%ADD14MACRO14*%
%AMMACRO19*
1,1,.006,-.0245,.024*
20,1,.006,-.0245,.024,.0245,.024,0.0*
1,1,.006,.0245,.024*
20,1,.006,.0245,.024,.028668,.023635,0.0*
1,1,.006,.028668,.023635*
20,1,.006,.028668,.023635,.032708,.022553,0.0*
1,1,.006,.032708,.022553*
20,1,.006,.032708,.022553,.0365,.020785,0.0*
1,1,.006,.0365,.020785*
20,1,.006,.0365,.020785,.039927,.018385,0.0*
1,1,.006,.039927,.018385*
20,1,.006,.039927,.018385,.042885,.015427,0.0*
1,1,.006,.042885,.015427*
20,1,.006,.042885,.015427,.045285,.012,0.0*
1,1,.006,.045285,.012*
20,1,.006,.045285,.012,.047053,.008208,0.0*
1,1,.006,.047053,.008208*
20,1,.006,.047053,.008208,.048135,.004168,0.0*
1,1,.006,.048135,.004168*
20,1,.006,.048135,.004168,.0485,0.0,0.0*
1,1,.006,.0485,0.0*
20,1,.006,.0485,0.0,.048135,-.004168,0.0*
1,1,.006,.048135,-.004168*
20,1,.006,.048135,-.004168,.047053,-.008208,0.0*
1,1,.006,.047053,-.008208*
20,1,.006,.047053,-.008208,.045285,-.012,0.0*
1,1,.006,.045285,-.012*
20,1,.006,.045285,-.012,.042885,-.015427,0.0*
1,1,.006,.042885,-.015427*
20,1,.006,.042885,-.015427,.039927,-.018385,0.0*
1,1,.006,.039927,-.018385*
20,1,.006,.039927,-.018385,.0365,-.020785,0.0*
1,1,.006,.0365,-.020785*
20,1,.006,.0365,-.020785,.032708,-.022553,0.0*
1,1,.006,.032708,-.022553*
20,1,.006,.032708,-.022553,.028668,-.023635,0.0*
1,1,.006,.028668,-.023635*
20,1,.006,.028668,-.023635,.0245,-.024,0.0*
1,1,.006,.0245,-.024*
20,1,.006,.0245,-.024,-.0245,-.024,0.0*
1,1,.006,-.0245,-.024*
20,1,.006,-.0245,-.024,-.028668,-.023635,0.0*
1,1,.006,-.028668,-.023635*
20,1,.006,-.028668,-.023635,-.032708,-.022553,0.0*
1,1,.006,-.032708,-.022553*
20,1,.006,-.032708,-.022553,-.0365,-.020785,0.0*
1,1,.006,-.0365,-.020785*
20,1,.006,-.0365,-.020785,-.039927,-.018385,0.0*
1,1,.006,-.039927,-.018385*
20,1,.006,-.039927,-.018385,-.042885,-.015427,0.0*
1,1,.006,-.042885,-.015427*
20,1,.006,-.042885,-.015427,-.045285,-.012,0.0*
1,1,.006,-.045285,-.012*
20,1,.006,-.045285,-.012,-.047053,-.008208,0.0*
1,1,.006,-.047053,-.008208*
20,1,.006,-.047053,-.008208,-.048135,-.004168,0.0*
1,1,.006,-.048135,-.004168*
20,1,.006,-.048135,-.004168,-.0485,0.0,0.0*
1,1,.006,-.0485,0.0*
20,1,.006,-.0485,0.0,-.048135,.004168,0.0*
1,1,.006,-.048135,.004168*
20,1,.006,-.048135,.004168,-.047053,.008208,0.0*
1,1,.006,-.047053,.008208*
20,1,.006,-.047053,.008208,-.045285,.012,0.0*
1,1,.006,-.045285,.012*
20,1,.006,-.045285,.012,-.042885,.015427,0.0*
1,1,.006,-.042885,.015427*
20,1,.006,-.042885,.015427,-.039927,.018385,0.0*
1,1,.006,-.039927,.018385*
20,1,.006,-.039927,.018385,-.0365,.020785,0.0*
1,1,.006,-.0365,.020785*
20,1,.006,-.0365,.020785,-.032708,.022553,0.0*
1,1,.006,-.032708,.022553*
20,1,.006,-.032708,.022553,-.028668,.023635,0.0*
1,1,.006,-.028668,.023635*
20,1,.006,-.028668,.023635,-.0245,.024,0.0*
1,1,.006,-.0245,.024*
1,1,.006,-.0168,-.0084*
20,1,.006,-.0168,-.0084,-.01484,-.00812,0.0*
1,1,.006,-.01484,-.00812*
20,1,.006,-.01484,-.00812,-.0126,-.00728,0.0*
1,1,.006,-.0126,-.00728*
20,1,.006,-.0126,-.00728,-.0112,-.00588,0.0*
1,1,.006,-.0112,-.00588*
20,1,.006,-.0112,-.00588,-.01064,-.00392,0.0*
1,1,.006,-.01064,-.00392*
20,1,.006,-.01064,-.00392,-.0112,-.00196,0.0*
1,1,.006,-.0112,-.00196*
20,1,.006,-.0112,-.00196,-.01288,-.00028,0.0*
1,1,.006,-.01288,-.00028*
20,1,.006,-.01288,-.00028,-.0154,.00056,0.0*
1,1,.006,-.0154,.00056*
20,1,.006,-.0154,.00056,-.0182,.00056,0.0*
1,1,.006,-.0182,.00056*
20,1,.006,-.0182,.00056,-.01988,.00112,0.0*
1,1,.006,-.01988,.00112*
20,1,.006,-.01988,.00112,-.02128,.00252,0.0*
1,1,.006,-.02128,.00252*
20,1,.006,-.02128,.00252,-.02184,.00448,0.0*
1,1,.006,-.02184,.00448*
20,1,.006,-.02184,.00448,-.021,.00644,0.0*
1,1,.006,-.021,.00644*
20,1,.006,-.021,.00644,-.01904,.00784,0.0*
1,1,.006,-.01904,.00784*
20,1,.006,-.01904,.00784,-.0168,.0084,0.0*
1,1,.006,-.0168,.0084*
20,1,.006,-.0168,.0084,-.01456,.00784,0.0*
1,1,.006,-.01456,.00784*
20,1,.006,-.01456,.00784,-.0126,.00644,0.0*
1,1,.006,-.0126,.00644*
20,1,.006,-.0126,.00644,-.01176,.00448,0.0*
1,1,.006,-.01176,.00448*
20,1,.006,-.01176,.00448,-.01232,.00252,0.0*
1,1,.006,-.01232,.00252*
20,1,.006,-.01232,.00252,-.01372,.00112,0.0*
1,1,.006,-.01372,.00112*
20,1,.006,-.01372,.00112,-.0154,.00056,0.0*
1,1,.006,-.0154,.00056*
20,1,.006,-.0154,.00056,-.0182,.00056,0.0*
1,1,.006,-.0182,.00056*
20,1,.006,-.0182,.00056,-.02072,-.00028,0.0*
1,1,.006,-.02072,-.00028*
20,1,.006,-.02072,-.00028,-.0224,-.00196,0.0*
1,1,.006,-.0224,-.00196*
20,1,.006,-.0224,-.00196,-.02296,-.00392,0.0*
1,1,.006,-.02296,-.00392*
20,1,.006,-.02296,-.00392,-.0224,-.00588,0.0*
1,1,.006,-.0224,-.00588*
20,1,.006,-.0224,-.00588,-.021,-.00728,0.0*
1,1,.006,-.021,-.00728*
20,1,.006,-.021,-.00728,-.01876,-.00812,0.0*
1,1,.006,-.01876,-.00812*
20,1,.006,-.01876,-.00812,-.0168,-.0084,0.0*
1,1,.006,-.0168,-.0084*
1,1,.006,-.00503,-.0084*
20,1,.006,-.00503,-.0084,-.00503,.0084,0.0*
1,1,.006,-.00503,.0084*
1,1,.006,-.00503,0.0*
20,1,.006,-.00503,0.0,-.00363,.00168,0.0*
1,1,.006,-.00363,.00168*
20,1,.006,-.00363,.00168,-.00195,.00252,0.0*
1,1,.006,-.00195,.00252*
20,1,.006,-.00195,.00252,-.00027,.0028,0.0*
1,1,.006,-.00027,.0028*
20,1,.006,-.00027,.0028,.00225,.00224,0.0*
1,1,.006,.00225,.00224*
20,1,.006,.00225,.00224,.00393,.00112,0.0*
1,1,.006,.00393,.00112*
20,1,.006,.00393,.00112,.00505,-.00084,0.0*
1,1,.006,.00505,-.00084*
20,1,.006,.00505,-.00084,.00505,-.00308,0.0*
1,1,.006,.00505,-.00308*
20,1,.006,.00505,-.00308,.00449,-.00532,0.0*
1,1,.006,.00449,-.00532*
20,1,.006,.00449,-.00532,.00337,-.007,0.0*
1,1,.006,.00337,-.007*
20,1,.006,.00337,-.007,.00141,-.00812,0.0*
1,1,.006,.00141,-.00812*
20,1,.006,.00141,-.00812,-.00027,-.0084,0.0*
1,1,.006,-.00027,-.0084*
20,1,.006,-.00027,-.0084,-.00195,-.00812,0.0*
1,1,.006,-.00195,-.00812*
20,1,.006,-.00195,-.00812,-.00363,-.00728,0.0*
1,1,.006,-.00363,-.00728*
20,1,.006,-.00363,-.00728,-.00503,-.00588,0.0*
1,1,.006,-.00503,-.00588*
1,1,.006,.0129,-.0126*
20,1,.006,.0129,-.0126,.01486,-.01372,0.0*
1,1,.006,.01486,-.01372*
20,1,.006,.01486,-.01372,.0171,-.014,0.0*
1,1,.006,.0171,-.014*
20,1,.006,.0171,-.014,.01906,-.01372,0.0*
1,1,.006,.01906,-.01372*
20,1,.006,.01906,-.01372,.02074,-.01232,0.0*
1,1,.006,.02074,-.01232*
20,1,.006,.02074,-.01232,.02186,-.01036,0.0*
1,1,.006,.02186,-.01036*
20,1,.006,.02186,-.01036,.02186,.0028,0.0*
1,1,.006,.02186,.0028*
1,1,.006,.02186,.00056*
20,1,.006,.02186,.00056,.02074,.00168,0.0*
1,1,.006,.02074,.00168*
20,1,.006,.02074,.00168,.01906,.00252,0.0*
1,1,.006,.01906,.00252*
20,1,.006,.01906,.00252,.0171,.0028,0.0*
1,1,.006,.0171,.0028*
20,1,.006,.0171,.0028,.01486,.00224,0.0*
1,1,.006,.01486,.00224*
20,1,.006,.01486,.00224,.01346,.00112,0.0*
1,1,.006,.01346,.00112*
20,1,.006,.01346,.00112,.01234,-.00084,0.0*
1,1,.006,.01234,-.00084*
20,1,.006,.01234,-.00084,.01178,-.0028,0.0*
1,1,.006,.01178,-.0028*
20,1,.006,.01178,-.0028,.01206,-.00448,0.0*
1,1,.006,.01206,-.00448*
20,1,.006,.01206,-.00448,.01318,-.00644,0.0*
1,1,.006,.01318,-.00644*
20,1,.006,.01318,-.00644,.01486,-.00784,0.0*
1,1,.006,.01486,-.00784*
20,1,.006,.01486,-.00784,.0171,-.0084,0.0*
1,1,.006,.0171,-.0084*
20,1,.006,.0171,-.0084,.01878,-.00812,0.0*
1,1,.006,.01878,-.00812*
20,1,.006,.01878,-.00812,.02074,-.007,0.0*
1,1,.006,.02074,-.007*
20,1,.006,.02074,-.007,.02186,-.00588,0.0*
1,1,.006,.02186,-.00588*
%
%ADD19MACRO19*%
%AMMACRO22*
1,1,.006,.035,0.0*
20,1,.006,.035,0.0,.034468,-.006078,0.0*
1,1,.006,.034468,-.006078*
20,1,.006,.034468,-.006078,.032889,-.011971,0.0*
1,1,.006,.032889,-.011971*
20,1,.006,.032889,-.011971,.030311,-.0175,0.0*
1,1,.006,.030311,-.0175*
20,1,.006,.030311,-.0175,.026812,-.022498,0.0*
1,1,.006,.026812,-.022498*
20,1,.006,.026812,-.022498,.022498,-.026812,0.0*
1,1,.006,.022498,-.026812*
20,1,.006,.022498,-.026812,.0175,-.030311,0.0*
1,1,.006,.0175,-.030311*
20,1,.006,.0175,-.030311,.011971,-.032889,0.0*
1,1,.006,.011971,-.032889*
20,1,.006,.011971,-.032889,.006078,-.034468,0.0*
1,1,.006,.006078,-.034468*
20,1,.006,.006078,-.034468,0.0,-.035,0.0*
1,1,.006,0.0,-.035*
20,1,.006,0.0,-.035,-.006078,-.034468,0.0*
1,1,.006,-.006078,-.034468*
20,1,.006,-.006078,-.034468,-.011971,-.032889,0.0*
1,1,.006,-.011971,-.032889*
20,1,.006,-.011971,-.032889,-.0175,-.030311,0.0*
1,1,.006,-.0175,-.030311*
20,1,.006,-.0175,-.030311,-.022498,-.026812,0.0*
1,1,.006,-.022498,-.026812*
20,1,.006,-.022498,-.026812,-.026812,-.022498,0.0*
1,1,.006,-.026812,-.022498*
20,1,.006,-.026812,-.022498,-.030311,-.0175,0.0*
1,1,.006,-.030311,-.0175*
20,1,.006,-.030311,-.0175,-.032889,-.011971,0.0*
1,1,.006,-.032889,-.011971*
20,1,.006,-.032889,-.011971,-.034468,-.006078,0.0*
1,1,.006,-.034468,-.006078*
20,1,.006,-.034468,-.006078,-.035,0.0,0.0*
1,1,.006,-.035,0.0*
20,1,.006,-.035,0.0,-.034468,.006078,0.0*
1,1,.006,-.034468,.006078*
20,1,.006,-.034468,.006078,-.032889,.011971,0.0*
1,1,.006,-.032889,.011971*
20,1,.006,-.032889,.011971,-.030311,.0175,0.0*
1,1,.006,-.030311,.0175*
20,1,.006,-.030311,.0175,-.026812,.022498,0.0*
1,1,.006,-.026812,.022498*
20,1,.006,-.026812,.022498,-.022498,.026812,0.0*
1,1,.006,-.022498,.026812*
20,1,.006,-.022498,.026812,-.0175,.030311,0.0*
1,1,.006,-.0175,.030311*
20,1,.006,-.0175,.030311,-.011971,.032889,0.0*
1,1,.006,-.011971,.032889*
20,1,.006,-.011971,.032889,-.006078,.034468,0.0*
1,1,.006,-.006078,.034468*
20,1,.006,-.006078,.034468,0.0,.035,0.0*
1,1,.006,0.0,.035*
20,1,.006,0.0,.035,.006078,.034468,0.0*
1,1,.006,.006078,.034468*
20,1,.006,.006078,.034468,.011971,.032889,0.0*
1,1,.006,.011971,.032889*
20,1,.006,.011971,.032889,.0175,.030311,0.0*
1,1,.006,.0175,.030311*
20,1,.006,.0175,.030311,.022498,.026812,0.0*
1,1,.006,.022498,.026812*
20,1,.006,.022498,.026812,.026812,.022498,0.0*
1,1,.006,.026812,.022498*
20,1,.006,.026812,.022498,.030311,.0175,0.0*
1,1,.006,.030311,.0175*
20,1,.006,.030311,.0175,.032889,.011971,0.0*
1,1,.006,.032889,.011971*
20,1,.006,.032889,.011971,.034468,.006078,0.0*
1,1,.006,.034468,.006078*
20,1,.006,.034468,.006078,.035,0.0,0.0*
1,1,.006,.035,0.0*
1,1,.006,-.02707,.00347*
20,1,.006,-.02707,.00347,-.02082,-.01041,0.0*
1,1,.006,-.02082,-.01041*
20,1,.006,-.02082,-.01041,-.01457,.00347,0.0*
1,1,.006,-.01457,.00347*
1,1,.006,.00001,.01041*
20,1,.006,.00001,.01041,-.00277,.00972,0.0*
1,1,.006,-.00277,.00972*
20,1,.006,-.00277,.00972,-.00485,.00798,0.0*
1,1,.006,-.00485,.00798*
20,1,.006,-.00485,.00798,-.00624,.0059,0.0*
1,1,.006,-.00624,.0059*
20,1,.006,-.00624,.0059,-.00728,.00312,0.0*
1,1,.006,-.00728,.00312*
20,1,.006,-.00728,.00312,-.00762,0.0,0.0*
1,1,.006,-.00762,0.0*
20,1,.006,-.00762,0.0,-.00728,-.00312,0.0*
1,1,.006,-.00728,-.00312*
20,1,.006,-.00728,-.00312,-.00624,-.0059,0.0*
1,1,.006,-.00624,-.0059*
20,1,.006,-.00624,-.0059,-.00485,-.00798,0.0*
1,1,.006,-.00485,-.00798*
20,1,.006,-.00485,-.00798,-.00277,-.00972,0.0*
1,1,.006,-.00277,-.00972*
20,1,.006,-.00277,-.00972,.00001,-.01041,0.0*
1,1,.006,.00001,-.01041*
20,1,.006,.00001,-.01041,.00279,-.00972,0.0*
1,1,.006,.00279,-.00972*
20,1,.006,.00279,-.00972,.00487,-.00798,0.0*
1,1,.006,.00487,-.00798*
20,1,.006,.00487,-.00798,.00626,-.0059,0.0*
1,1,.006,.00626,-.0059*
20,1,.006,.00626,-.0059,.0073,-.00312,0.0*
1,1,.006,.0073,-.00312*
20,1,.006,.0073,-.00312,.00764,0.0,0.0*
1,1,.006,.00764,0.0*
20,1,.006,.00764,0.0,.0073,.00312,0.0*
1,1,.006,.0073,.00312*
20,1,.006,.0073,.00312,.00626,.0059,0.0*
1,1,.006,.00626,.0059*
20,1,.006,.00626,.0059,.00487,.00798,0.0*
1,1,.006,.00487,.00798*
20,1,.006,.00487,.00798,.00279,.00972,0.0*
1,1,.006,.00279,.00972*
20,1,.006,.00279,.00972,.00001,.01041,0.0*
1,1,.006,.00001,.01041*
1,1,.006,.02084,-.01041*
20,1,.006,.02084,-.01041,.02327,-.01006,0.0*
1,1,.006,.02327,-.01006*
20,1,.006,.02327,-.01006,.02604,-.00902,0.0*
1,1,.006,.02604,-.00902*
20,1,.006,.02604,-.00902,.02778,-.00729,0.0*
1,1,.006,.02778,-.00729*
20,1,.006,.02778,-.00729,.02847,-.00486,0.0*
1,1,.006,.02847,-.00486*
20,1,.006,.02847,-.00486,.02778,-.00243,0.0*
1,1,.006,.02778,-.00243*
20,1,.006,.02778,-.00243,.0257,-.00035,0.0*
1,1,.006,.0257,-.00035*
20,1,.006,.0257,-.00035,.02257,.00069,0.0*
1,1,.006,.02257,.00069*
20,1,.006,.02257,.00069,.01911,.00069,0.0*
1,1,.006,.01911,.00069*
20,1,.006,.01911,.00069,.01702,.00139,0.0*
1,1,.006,.01702,.00139*
20,1,.006,.01702,.00139,.01529,.00312,0.0*
1,1,.006,.01529,.00312*
20,1,.006,.01529,.00312,.01459,.00555,0.0*
1,1,.006,.01459,.00555*
20,1,.006,.01459,.00555,.01564,.00798,0.0*
1,1,.006,.01564,.00798*
20,1,.006,.01564,.00798,.01806,.00972,0.0*
1,1,.006,.01806,.00972*
20,1,.006,.01806,.00972,.02084,.01041,0.0*
1,1,.006,.02084,.01041*
20,1,.006,.02084,.01041,.02362,.00972,0.0*
1,1,.006,.02362,.00972*
20,1,.006,.02362,.00972,.02604,.00798,0.0*
1,1,.006,.02604,.00798*
20,1,.006,.02604,.00798,.02709,.00555,0.0*
1,1,.006,.02709,.00555*
20,1,.006,.02709,.00555,.02639,.00312,0.0*
1,1,.006,.02639,.00312*
20,1,.006,.02639,.00312,.02466,.00139,0.0*
1,1,.006,.02466,.00139*
20,1,.006,.02466,.00139,.02257,.00069,0.0*
1,1,.006,.02257,.00069*
20,1,.006,.02257,.00069,.01911,.00069,0.0*
1,1,.006,.01911,.00069*
20,1,.006,.01911,.00069,.01598,-.00035,0.0*
1,1,.006,.01598,-.00035*
20,1,.006,.01598,-.00035,.0139,-.00243,0.0*
1,1,.006,.0139,-.00243*
20,1,.006,.0139,-.00243,.01321,-.00486,0.0*
1,1,.006,.01321,-.00486*
20,1,.006,.01321,-.00486,.0139,-.00729,0.0*
1,1,.006,.0139,-.00729*
20,1,.006,.0139,-.00729,.01564,-.00902,0.0*
1,1,.006,.01564,-.00902*
20,1,.006,.01564,-.00902,.01841,-.01006,0.0*
1,1,.006,.01841,-.01006*
20,1,.006,.01841,-.01006,.02084,-.01041,0.0*
1,1,.006,.02084,-.01041*
%
%ADD22MACRO22*%
%ADD45C,.006*%
G75*
%LPD*%
G75*
G54D10*
X3001Y61178D03*
Y127178D03*
Y149178D03*
Y171178D03*
Y193178D03*
Y215178D03*
Y237178D03*
Y259178D03*
Y281178D03*
Y303178D03*
X21569Y49379D03*
X10875Y323721D03*
Y345721D03*
Y367721D03*
Y389721D03*
X21345Y387760D03*
X21309Y395712D03*
X10875Y411721D03*
Y433721D03*
Y455721D03*
Y477721D03*
Y499721D03*
Y521721D03*
X20587Y523970D03*
X16342Y516951D03*
X16512Y533155D03*
X10875Y543721D03*
Y565721D03*
Y587721D03*
Y609721D03*
Y653721D03*
Y675721D03*
Y697721D03*
Y719721D03*
Y741721D03*
Y763721D03*
Y785721D03*
Y807721D03*
Y829721D03*
Y851721D03*
Y873721D03*
Y895721D03*
Y917721D03*
Y939721D03*
Y961721D03*
Y983721D03*
Y1005721D03*
Y1027721D03*
Y1049721D03*
Y1071721D03*
Y1093721D03*
Y1115721D03*
Y1137721D03*
Y1159721D03*
Y1181721D03*
Y1203721D03*
Y1225721D03*
Y1247721D03*
Y1269721D03*
Y1291721D03*
Y1445721D03*
X19230Y1446459D03*
X10875Y1467721D03*
Y1489721D03*
Y1511721D03*
Y1533721D03*
Y1555721D03*
Y1577721D03*
X18960Y1598181D03*
X34281Y277798D03*
Y282916D03*
X35689Y298207D03*
X34281Y312916D03*
Y307798D03*
X36500Y323500D03*
X33686Y383944D03*
X27309Y383926D03*
X36524Y398013D03*
X26771Y398811D03*
X30680Y438142D03*
X33184Y523285D03*
X28562Y517025D03*
X36402Y528675D03*
X33257Y540370D03*
X26887Y541805D03*
X35952Y551605D03*
X35852Y670445D03*
D03*
Y667045D03*
D03*
Y673010D03*
Y664480D03*
Y670445D03*
Y667045D03*
Y681410D03*
D03*
Y678010D03*
D03*
Y688916D03*
D03*
Y686410D03*
Y683910D03*
Y675510D03*
Y681410D03*
Y678010D03*
Y692316D03*
D03*
Y703222D03*
D03*
Y699822D03*
D03*
Y697322D03*
Y694822D03*
Y692316D03*
Y703222D03*
Y688916D03*
Y699822D03*
Y705728D03*
X35010Y1289485D03*
X35040Y1292433D03*
X35080Y1298360D03*
X35040Y1295380D03*
X34584Y1307744D03*
Y1310244D03*
Y1312744D03*
Y1315244D03*
X33822Y1462075D03*
Y1459075D03*
Y1456075D03*
X36822D03*
Y1459075D03*
Y1462075D03*
X33822Y1465075D03*
X36822D03*
X33822Y1477075D03*
Y1486075D03*
Y1483075D03*
Y1480075D03*
X27205Y1501630D03*
Y1498230D03*
X37671Y1515214D03*
X34704Y1515235D03*
X38058Y1591405D03*
X35133Y1603396D03*
X35167Y1610521D03*
Y1598896D03*
X28592Y1617961D03*
X35233Y1623196D03*
X35167Y1626896D03*
X28592Y1639961D03*
X35167Y1629405D03*
X28592Y1661961D03*
X32927Y1668587D03*
X28592Y1683961D03*
X43569Y49379D03*
X44600Y280357D03*
X41492Y292892D03*
X50500Y311100D03*
X40000Y323500D03*
X46834Y360862D03*
X51114D03*
X39410Y384582D03*
X49400Y384392D03*
X43020Y382942D03*
X39226Y395346D03*
X49250Y396332D03*
X41933Y395652D03*
X47618Y412613D03*
X47619Y419084D03*
X47618Y415184D03*
X50138Y425810D03*
X45182D03*
X47619Y421655D03*
X49360Y428806D03*
X45960D03*
X49212Y451602D03*
X45812D03*
X45022Y449106D03*
X50002D03*
X49212Y451602D03*
X45812D03*
X49848Y524210D03*
X47812Y517635D03*
X49889Y531149D03*
X42810Y528070D03*
X48626Y552365D03*
X39952Y551605D03*
X51000Y1339200D03*
X50880Y1415563D03*
D03*
Y1418963D03*
D03*
Y1412563D03*
Y1415563D03*
Y1421963D03*
Y1418963D03*
X42822Y1462075D03*
Y1459075D03*
Y1456075D03*
Y1465075D03*
Y1477075D03*
Y1483075D03*
Y1486075D03*
Y1480075D03*
X49265Y1490950D03*
Y1493450D03*
X49188Y1499181D03*
X41360Y1498971D03*
X41309Y1496173D03*
X38650Y1499326D03*
X49177Y1496272D03*
X47138Y1513072D03*
X47089Y1510268D03*
X52405Y1514835D03*
X49405D03*
X52405Y1511986D03*
X49405D03*
X52330Y1509137D03*
X49330D03*
X52796Y1526469D03*
X52905Y1523335D03*
X47760Y1529506D03*
X48383Y1532395D03*
X48157Y1536296D03*
X49196Y1551294D03*
X48324Y1545961D03*
X50642Y1557451D03*
X48758Y1559295D03*
X48907Y1554972D03*
X45633Y1592481D03*
X50133D03*
X46833Y1612596D03*
X47602Y1622414D03*
X51333Y1640996D03*
X42491Y1638656D03*
X40167Y1632405D03*
X40922Y1654869D03*
Y1658269D03*
X51358Y1647717D03*
Y1650217D03*
X38426Y1654079D03*
X40922Y1654869D03*
X41679Y1673323D03*
X38426Y1659059D03*
X40922Y1658269D03*
X41679Y1676723D03*
X44583Y1672433D03*
Y1677613D03*
X45052Y1684283D03*
X41679Y1673323D03*
Y1676723D03*
X54584Y8335D03*
Y30335D03*
X65933Y28406D03*
Y48720D03*
X61157Y69340D03*
X64557D03*
X65347Y66847D03*
X60367D03*
X65347Y71839D03*
X60367D03*
X58457Y69340D03*
X67257D03*
X61157D03*
X64557D03*
X57271Y272357D03*
X59780Y282866D03*
X67575Y287500D03*
X62567Y295103D03*
X66289Y298207D03*
X56620Y303500D03*
X59780Y312866D03*
X59322Y360702D03*
X63429D03*
X67681D03*
X61340Y384362D03*
X61250Y396142D03*
X53406Y402862D03*
X62812Y412100D03*
X62813Y416000D03*
X62833Y409597D03*
X62808Y418675D03*
X62812Y412100D03*
X62813Y416000D03*
X65380Y427810D03*
X60393D03*
X64150Y434972D03*
X64821Y430806D03*
X60921D03*
X53800Y435451D03*
X54762Y444993D03*
X63540Y438802D03*
X56800Y524220D03*
X64442Y510667D03*
X55682Y517595D03*
X56719Y531120D03*
X56192Y537795D03*
X63633Y528229D03*
X58365Y552365D03*
X53299D03*
X56542Y589521D03*
X56627Y585818D03*
X59259Y737422D03*
X64823Y756832D03*
Y760178D03*
X58751Y777718D03*
X61251D03*
Y775218D03*
X58751D03*
X69323Y780257D03*
Y786950D03*
Y793643D03*
X58751Y790218D03*
Y792718D03*
Y780218D03*
X61251D03*
X56057Y792750D03*
X61251Y792718D03*
Y790218D03*
X56057Y790250D03*
Y787750D03*
X61251Y787718D03*
X56057Y785250D03*
X61251Y785218D03*
Y782718D03*
X56057Y782750D03*
X58751Y782718D03*
Y785218D03*
Y787718D03*
X69323Y803682D03*
Y796989D03*
X64923Y795316D03*
X69323Y817068D03*
Y810375D03*
Y823761D03*
X57752Y808020D03*
X69323Y830454D03*
Y833800D03*
X64923Y832127D03*
X69323Y840493D03*
Y847186D03*
Y853879D03*
Y860572D03*
Y867265D03*
Y877304D03*
Y870611D03*
Y883997D03*
X64923Y868938D03*
X69323Y890690D03*
Y897383D03*
Y904076D03*
Y907423D03*
X64923Y905750D03*
X69323Y914115D03*
Y920808D03*
Y927501D03*
Y934194D03*
Y940887D03*
Y950926D03*
Y944234D03*
Y957619D03*
X64923Y942561D03*
X69323Y964312D03*
Y971005D03*
Y977698D03*
Y984391D03*
Y1001123D03*
Y997777D03*
Y991084D03*
Y1031241D03*
Y1037934D03*
Y1044627D03*
Y1058013D03*
Y1051320D03*
Y1074745D03*
Y1081438D03*
Y1088131D03*
Y1091478D03*
X64923Y1089805D03*
X69323Y1098171D03*
Y1104863D03*
Y1111556D03*
Y1118249D03*
Y1134982D03*
Y1124942D03*
Y1128289D03*
X64923Y1126616D03*
X69323Y1148367D03*
Y1141675D03*
Y1155060D03*
Y1161753D03*
Y1165100D03*
X64923Y1163427D03*
X69323Y1171793D03*
Y1178486D03*
Y1185178D03*
Y1191871D03*
Y1208604D03*
Y1198564D03*
Y1201911D03*
X64923Y1200238D03*
X69323Y1215297D03*
Y1221989D03*
Y1228682D03*
Y1235375D03*
Y1238722D03*
X64923Y1237049D03*
X69323Y1245415D03*
Y1252108D03*
X60547Y1276036D03*
X57747Y1270470D03*
X55099Y1289676D03*
X55043Y1295676D03*
X53700Y1342300D03*
X58349Y1403331D03*
Y1406331D03*
D03*
Y1409731D03*
D03*
Y1412731D03*
Y1406331D03*
Y1409731D03*
X66822Y1462075D03*
Y1459075D03*
Y1456075D03*
X57822Y1462075D03*
Y1459075D03*
Y1456075D03*
X66822Y1465075D03*
X57822D03*
X67010Y1476292D03*
X57822Y1477075D03*
X57777Y1490580D03*
X66710Y1485324D03*
Y1482324D03*
X66785Y1479175D03*
X57822Y1482791D03*
Y1485294D03*
Y1480075D03*
X64030Y1491595D03*
X57770Y1488047D03*
X66696Y1488010D03*
X64030Y1499095D03*
Y1501595D03*
Y1494095D03*
Y1496595D03*
X55755Y1511885D03*
X55905Y1514835D03*
X57281Y1523287D03*
X66081D03*
X59881D03*
X63481D03*
X55789Y1509224D03*
X57281Y1526394D03*
X66081D03*
X65281Y1529501D03*
X59881Y1526394D03*
X63481D03*
X62681Y1529501D03*
X64235Y1533150D03*
X61755D03*
X59275D03*
X67196Y1552869D03*
X64235Y1538750D03*
X61755D03*
X59275D03*
X55370Y1551351D03*
X61605Y1546833D03*
X64275Y1546296D03*
X67725Y1538946D03*
X63990Y1562177D03*
Y1567627D03*
Y1564727D03*
X63915Y1558805D03*
Y1556254D03*
X63802Y1579997D03*
X63990Y1570427D03*
X58602Y1579997D03*
X61302D03*
X61225Y1570283D03*
X58564Y1570209D03*
X65767Y1609405D03*
X59767D03*
X53767D03*
X61110Y1598146D03*
X65767Y1615405D03*
X65943Y1621405D03*
X59767D03*
X53767Y1615405D03*
Y1621405D03*
X58633Y1641388D03*
X54449Y1641722D03*
X59427Y1644410D03*
X53648Y1653088D03*
X64427Y1643496D03*
X64462Y1655624D03*
X61927Y1643496D03*
X65257Y1652941D03*
X56815Y1643431D03*
X61415Y1661695D03*
X61374Y1669931D03*
X62202Y1684579D03*
X66127Y1687362D03*
X81970Y19541D03*
X75928Y3001D03*
X81159Y17045D03*
X78265Y26477D03*
X74865D03*
X78265D03*
X74865D03*
X81970Y19541D03*
X72087Y25977D03*
X74087Y23981D03*
X79043D03*
X73015Y28406D03*
X81043Y25977D03*
X80101Y28406D03*
X79192Y19541D03*
X81159Y22037D03*
X73025Y37106D03*
X80111D03*
X73015Y40020D03*
X80101D03*
X73025Y48720D03*
X80111D03*
X83157Y69340D03*
X72153Y75343D03*
X75553D03*
X69453D03*
X78253D03*
X82367Y71839D03*
X80457Y69340D03*
X82367Y66847D03*
X76347Y72850D03*
X71367D03*
X72153Y75343D03*
X75553D03*
X76347Y77842D03*
X71367D03*
X79726Y145191D03*
X71779Y157194D03*
Y165194D03*
X71775Y153194D03*
X72462Y268223D03*
X77680Y378395D03*
Y380895D03*
X68020Y395222D03*
X68365Y443677D03*
X77790Y520108D03*
X80318Y539413D03*
X77733Y526764D03*
X77790Y537808D03*
X80318Y543313D03*
D03*
Y539413D03*
X77733Y544464D03*
X80915Y756766D03*
X73873D03*
Y760266D03*
X69323Y776911D03*
X80915Y763766D03*
Y767400D03*
X80784Y771366D03*
X73933Y768706D03*
X73960Y766090D03*
X80015Y786950D03*
X69323Y783604D03*
X74773Y790297D03*
X81065Y791970D03*
X69323Y780257D03*
Y786950D03*
X80015Y796989D03*
X69323Y807029D03*
X74773Y800336D03*
X69323Y803682D03*
Y793643D03*
Y796989D03*
Y813722D03*
Y820415D03*
Y817068D03*
Y810375D03*
X80015Y823761D03*
Y833800D03*
X81065Y828781D03*
X74773Y827108D03*
Y837147D03*
X69323Y823761D03*
Y830454D03*
Y833800D03*
Y843840D03*
Y850533D03*
Y840493D03*
Y847186D03*
X80015Y860572D03*
X81065Y865592D03*
X69323Y857226D03*
X74773Y863919D03*
X69323Y853879D03*
Y860572D03*
X80015Y870611D03*
X69323Y880651D03*
X74773Y873958D03*
X69323Y877304D03*
Y867265D03*
Y870611D03*
Y887344D03*
Y894037D03*
Y883997D03*
Y890690D03*
X74773Y900730D03*
X80015Y907423D03*
X74773Y910769D03*
X80015Y897383D03*
X81065Y902403D03*
X69323Y897383D03*
Y904076D03*
Y907423D03*
Y924155D03*
Y917462D03*
Y914115D03*
Y920808D03*
X81065Y939214D03*
X80015Y934194D03*
X74773Y937541D03*
X69323Y930848D03*
Y927501D03*
Y934194D03*
Y940887D03*
X80015Y944234D03*
X69323Y954273D03*
X74773Y947580D03*
X69323Y950926D03*
Y944234D03*
Y960966D03*
Y967659D03*
Y964312D03*
Y957619D03*
Y971005D03*
Y974352D03*
Y981045D03*
Y977698D03*
Y984391D03*
Y987737D03*
Y994430D03*
Y1001123D03*
Y997777D03*
Y991084D03*
Y1004470D03*
Y1034588D03*
Y1041281D03*
Y1031241D03*
Y1037934D03*
Y1044627D03*
Y1047974D03*
Y1054667D03*
Y1058013D03*
Y1051320D03*
Y1071399D03*
Y1061360D03*
Y1074745D03*
Y1068052D03*
Y1064706D03*
X80015Y1081438D03*
X81065Y1086458D03*
X74773Y1084785D03*
X69323Y1078092D03*
Y1081438D03*
Y1088131D03*
X80015Y1091478D03*
X69323Y1101517D03*
X74773Y1094824D03*
X69323Y1098171D03*
Y1104863D03*
Y1091478D03*
X80015Y1118249D03*
X69323Y1114903D03*
Y1108210D03*
Y1111556D03*
Y1118249D03*
X80015Y1128289D03*
X81065Y1123269D03*
X74773Y1121596D03*
Y1131635D03*
X69323Y1134982D03*
Y1124942D03*
Y1128289D03*
Y1145021D03*
Y1138328D03*
Y1148367D03*
Y1141675D03*
X80015Y1165100D03*
X81065Y1160080D03*
X80015Y1155060D03*
X69323Y1151714D03*
X74773Y1158407D03*
X69323Y1155060D03*
Y1161753D03*
Y1165100D03*
Y1175139D03*
X74773Y1168446D03*
X69323Y1171793D03*
Y1178486D03*
Y1181832D03*
X80015Y1191871D03*
X69323Y1188525D03*
Y1185178D03*
Y1191871D03*
X81065Y1196891D03*
X80015Y1201911D03*
X74773Y1195218D03*
Y1205257D03*
X69323Y1208604D03*
Y1198564D03*
Y1201911D03*
Y1211950D03*
Y1218643D03*
Y1215297D03*
Y1221989D03*
X80015Y1238722D03*
Y1228682D03*
X81065Y1233702D03*
X69323Y1225336D03*
X74773Y1232029D03*
X69323Y1228682D03*
Y1235375D03*
Y1238722D03*
X74773Y1242068D03*
X69323Y1248761D03*
Y1245415D03*
Y1252108D03*
Y1255454D03*
X68354Y1314097D03*
X80378Y1406676D03*
X81052Y1427410D03*
X81132Y1424195D03*
X71511Y1444379D03*
X79055Y1434000D03*
X73820Y1442893D03*
X81401Y1436105D03*
X73820Y1445945D03*
X73757Y1448500D03*
X81822Y1462075D03*
Y1456075D03*
Y1465075D03*
Y1477075D03*
X77883Y1491440D03*
X80932D03*
X80852Y1488638D03*
X75245Y1491440D03*
X81822Y1480075D03*
Y1483075D03*
Y1486075D03*
X72396Y1491290D03*
X72390Y1499211D03*
X77883Y1499240D03*
X80833D03*
X77883Y1494040D03*
Y1496640D03*
X80932Y1494040D03*
Y1496640D03*
X75245Y1499240D03*
Y1494040D03*
Y1496640D03*
X72396Y1493890D03*
Y1496490D03*
X74325Y1523303D03*
X68870Y1523147D03*
X71359Y1523186D03*
X81868Y1511285D03*
X81405Y1516835D03*
X81905Y1513835D03*
X81405Y1519835D03*
Y1522835D03*
X78808Y1522839D03*
X81905Y1508698D03*
X74440Y1526385D03*
X74462Y1529665D03*
X82696Y1529095D03*
X74912Y1538946D03*
X72585D03*
X70155D03*
X77920Y1538245D03*
X75796Y1545669D03*
X75396Y1542369D03*
X78796Y1545669D03*
X78096Y1542444D03*
X78372Y1556416D03*
Y1558916D03*
X78522Y1562641D03*
Y1565141D03*
Y1567888D03*
X78403Y1580311D03*
X81103D03*
X78522Y1570388D03*
X81468Y1570285D03*
X76806Y1593265D03*
X68133Y1587896D03*
X81006Y1593265D03*
X72660Y1587365D03*
X80400Y1602225D03*
X75764Y1636993D03*
X68427Y1644410D03*
X73427D03*
X77427D03*
X69486Y1661828D03*
X69589Y1669878D03*
X74127Y1687362D03*
X82127D03*
X80000Y1702450D03*
X79500Y1720450D03*
X82500Y1720331D03*
X85370Y19541D03*
X96143D03*
X99543D03*
X86139Y17045D03*
X95333D03*
X92438Y26477D03*
X89038D03*
X85370Y19541D03*
X92438Y26477D03*
X89038D03*
X96143Y19541D03*
X88148D03*
X95216Y25977D03*
X86260D03*
X93216Y23981D03*
X94274Y28406D03*
X88260Y23981D03*
X87188Y28406D03*
X86139Y22037D03*
X95333D03*
X93365Y19541D03*
X94284Y37106D03*
X87198D03*
X87188Y40020D03*
X94274D03*
X87198Y48720D03*
X94284D03*
X97557Y75340D03*
X94157D03*
X86557Y69340D03*
X87347Y71839D03*
Y66847D03*
X89257Y69340D03*
X91457Y75340D03*
X93367Y72847D03*
X94157Y75340D03*
X83157Y69340D03*
X97557Y75340D03*
X86557Y69340D03*
X93367Y77839D03*
X89150Y154494D03*
X93717Y159053D03*
X87520Y382219D03*
Y391391D03*
Y395865D03*
X90225Y610351D03*
X84057Y599372D03*
X84038Y602233D03*
X90225Y614351D03*
Y618351D03*
Y622351D03*
X94524Y760178D03*
Y756832D03*
X89965D03*
X85465Y776911D03*
Y773564D03*
X90015Y766871D03*
X85465Y776911D03*
X89965Y763525D03*
X94474D03*
X90015Y770218D03*
X99024Y780257D03*
Y786950D03*
X85465Y783604D03*
Y790297D03*
Y793643D03*
X99024D03*
X85465Y780257D03*
Y783604D03*
Y790297D03*
Y800336D03*
Y807029D03*
X99024Y803682D03*
Y796989D03*
X85465Y803682D03*
X94624Y795316D03*
X85465Y800336D03*
Y807029D03*
Y793643D03*
X99024Y817068D03*
Y810375D03*
X85465Y813722D03*
Y820415D03*
X99024Y823761D03*
X85465Y810375D03*
Y817068D03*
Y813722D03*
Y820415D03*
Y837147D03*
Y830454D03*
Y827108D03*
X99024Y830454D03*
Y833800D03*
X94624Y832127D03*
X85465Y837147D03*
Y830454D03*
Y827108D03*
X99024Y840493D03*
Y847186D03*
X85465Y843840D03*
Y850533D03*
X99024Y853879D03*
X85465Y840493D03*
Y847186D03*
Y843840D03*
Y850533D03*
Y857226D03*
Y863919D03*
X99024Y860572D03*
Y867265D03*
X85465D03*
Y853879D03*
Y857226D03*
Y863919D03*
X99024Y877304D03*
Y870611D03*
X85465Y873958D03*
Y880651D03*
X99024Y883997D03*
X85465Y877304D03*
X94624Y868938D03*
X85465Y873958D03*
Y880651D03*
Y867265D03*
Y887344D03*
Y894037D03*
X99024Y890690D03*
Y897383D03*
X85465Y890690D03*
Y883997D03*
Y887344D03*
Y894037D03*
X99024Y904076D03*
Y907423D03*
X85465Y910769D03*
Y904076D03*
Y900730D03*
X94624Y905750D03*
X85465Y910769D03*
Y904076D03*
Y900730D03*
Y924155D03*
Y917462D03*
X99024Y914115D03*
Y920808D03*
Y927501D03*
X85465Y920808D03*
Y914115D03*
Y924155D03*
Y917462D03*
X99024Y934194D03*
Y940887D03*
X85465Y930848D03*
Y940887D03*
Y937541D03*
Y927501D03*
Y930848D03*
Y940887D03*
Y937541D03*
Y947580D03*
Y954273D03*
X99024Y950926D03*
Y944234D03*
Y957619D03*
X85465Y950926D03*
X94624Y942561D03*
X85465Y947580D03*
Y954273D03*
X99024Y964312D03*
Y971005D03*
X90965Y960966D03*
X85465Y967659D03*
Y957619D03*
Y971005D03*
Y964312D03*
Y960966D03*
X90965D03*
X85465Y967659D03*
Y974352D03*
Y981045D03*
X99024Y977698D03*
Y984391D03*
X85465Y987737D03*
Y984391D03*
Y977698D03*
Y974352D03*
Y981045D03*
X99024Y1001123D03*
Y997777D03*
Y991084D03*
X85465Y994430D03*
Y1001123D03*
Y991084D03*
Y997777D03*
Y987737D03*
Y994430D03*
Y1001123D03*
Y1004470D03*
Y1027895D03*
X99024Y1031241D03*
X85465Y1027895D03*
Y1034588D03*
Y1041281D03*
X99024Y1037934D03*
Y1044627D03*
X85465Y1047974D03*
Y1044627D03*
Y1031241D03*
Y1037934D03*
Y1034588D03*
Y1041281D03*
X99024Y1058013D03*
Y1051320D03*
X85465Y1054667D03*
Y1061360D03*
Y1051320D03*
Y1058013D03*
Y1047974D03*
Y1054667D03*
Y1071399D03*
Y1064706D03*
X99024Y1074745D03*
X85465Y1068052D03*
Y1074745D03*
Y1061360D03*
Y1071399D03*
Y1064706D03*
X99024Y1081438D03*
Y1088131D03*
X85465Y1078092D03*
Y1088131D03*
Y1084785D03*
X99024Y1091478D03*
X94624Y1089805D03*
X85465Y1078092D03*
Y1088131D03*
Y1084785D03*
Y1094824D03*
Y1101517D03*
X99024Y1098171D03*
Y1104863D03*
X85465Y1098171D03*
Y1104863D03*
Y1094824D03*
Y1101517D03*
X99024Y1111556D03*
Y1118249D03*
X85465Y1108210D03*
Y1114903D03*
Y1121596D03*
Y1111556D03*
Y1108210D03*
Y1114903D03*
Y1131635D03*
Y1124942D03*
X99024Y1134982D03*
Y1124942D03*
Y1128289D03*
X94624Y1126616D03*
X85465Y1134982D03*
Y1131635D03*
Y1124942D03*
Y1121596D03*
X99024Y1148367D03*
Y1141675D03*
X85465Y1138328D03*
Y1145021D03*
Y1151714D03*
Y1148367D03*
Y1141675D03*
Y1138328D03*
Y1145021D03*
Y1161753D03*
Y1158407D03*
X99024Y1155060D03*
Y1161753D03*
Y1165100D03*
X94624Y1163427D03*
X85465Y1151714D03*
Y1161753D03*
Y1158407D03*
X99024Y1171793D03*
Y1178486D03*
X85465Y1168446D03*
Y1175139D03*
Y1181832D03*
Y1178486D03*
Y1171793D03*
Y1168446D03*
Y1175139D03*
Y1188525D03*
X99024Y1185178D03*
Y1191871D03*
X85465Y1195218D03*
Y1185178D03*
Y1181832D03*
Y1188525D03*
X99024Y1208604D03*
Y1198564D03*
Y1201911D03*
X85465Y1205257D03*
Y1198564D03*
Y1211950D03*
Y1208604D03*
X94624Y1200238D03*
X85465Y1205257D03*
Y1198564D03*
Y1195218D03*
Y1218643D03*
X99024Y1215297D03*
Y1221989D03*
X85465Y1225336D03*
Y1215297D03*
Y1221989D03*
Y1211950D03*
Y1218643D03*
X99024Y1228682D03*
Y1235375D03*
Y1238722D03*
X85465Y1235375D03*
Y1232029D03*
X94624Y1237049D03*
X85465Y1225336D03*
Y1235375D03*
Y1232029D03*
Y1242068D03*
Y1248761D03*
X99024Y1245415D03*
Y1252108D03*
X85465D03*
Y1245415D03*
Y1242068D03*
Y1248761D03*
X95790Y1278014D03*
X82953Y1307607D03*
X83023Y1311607D03*
X90501Y1338952D03*
X92791Y1341302D03*
X96191Y1337721D03*
X92941Y1346172D03*
X91000Y1350300D03*
X88500D03*
X97546Y1385912D03*
X85736Y1391597D03*
X84000Y1408000D03*
Y1412500D03*
Y1417000D03*
X97530Y1410247D03*
X86827Y1404080D03*
X93000Y1417000D03*
Y1408000D03*
X93069Y1412500D03*
X85103Y1433051D03*
X93000Y1430500D03*
X84000Y1421500D03*
Y1426000D03*
X93000D03*
X97800Y1433000D03*
X93000Y1421500D03*
Y1435500D03*
Y1440000D03*
X84500D03*
X93000Y1448500D03*
X84500Y1444500D03*
Y1448500D03*
X88722Y1462075D03*
X85722D03*
X88722Y1456075D03*
X85722D03*
X88722Y1465075D03*
X85722D03*
X88722Y1476741D03*
X89092Y1491106D03*
X89042Y1488506D03*
X83991Y1491440D03*
X83892Y1488840D03*
X88722Y1479741D03*
Y1482741D03*
Y1485741D03*
X83892Y1499140D03*
X83991Y1494040D03*
Y1496540D03*
X84051Y1501690D03*
X95624Y1523287D03*
X85368Y1511285D03*
X85405Y1513835D03*
X88868Y1511285D03*
X88905Y1513835D03*
X93024Y1523287D03*
X85405Y1508698D03*
X88905D03*
X97498Y1533150D03*
X95624Y1526394D03*
X95018Y1533150D03*
X88696Y1526769D03*
X93024Y1526394D03*
X88696Y1523769D03*
X83796Y1533746D03*
X83811Y1537296D03*
X97498Y1538750D03*
X85621Y1551969D03*
X82974Y1552051D03*
X95018Y1538750D03*
X91511Y1552296D03*
X97018Y1546331D03*
X88511Y1552296D03*
X83121Y1542294D03*
X94786Y1574205D03*
Y1576705D03*
X97486Y1574205D03*
Y1576705D03*
X83603Y1580311D03*
X84093Y1570285D03*
X90675Y1590783D03*
X96124Y1593458D03*
Y1595958D03*
X93424Y1593458D03*
X90675Y1593283D03*
X93424Y1595958D03*
X90675Y1595783D03*
X93537Y1598506D03*
X96237D03*
X90649Y1598507D03*
X84833Y1611896D03*
X85133Y1616396D03*
Y1620896D03*
Y1625396D03*
X85167Y1629905D03*
X99443Y1658531D03*
X90892Y1654749D03*
X83340Y1654353D03*
X85836Y1655143D03*
X99443Y1661931D03*
X89466Y1663138D03*
Y1667127D03*
X83340Y1659333D03*
X85395Y1670331D03*
X85836Y1658543D03*
X87891Y1671121D03*
X85395Y1675311D03*
X87891Y1674521D03*
X86127Y1687362D03*
X90127D03*
X92192Y1713741D03*
X93029Y1705225D03*
X82945Y1702511D03*
X95342Y1713741D03*
X97683Y1722477D03*
X92596Y1737117D03*
X110316Y19541D03*
X113716D03*
X97928Y3001D03*
X100313Y17045D03*
X109506D03*
X106611Y26477D03*
X103211D03*
X99543Y19541D03*
X106611Y26477D03*
X103211D03*
X110316Y19541D03*
X109389Y25977D03*
X100433D03*
X107389Y23981D03*
X108448Y28406D03*
X102433Y23981D03*
X101361Y28406D03*
X100313Y22037D03*
X102321Y19541D03*
X109506Y22037D03*
X107538Y19541D03*
X108458Y37106D03*
X101371D03*
X101361Y40020D03*
X108448D03*
X101371Y48720D03*
X108458D03*
X105157Y69340D03*
X108557D03*
X98347Y72847D03*
X100257Y75340D03*
X104367Y71839D03*
X109347D03*
X102457Y69340D03*
X104367Y66847D03*
X109347D03*
X111257Y69340D03*
X105157D03*
X108557D03*
X98347Y77839D03*
X101679Y151191D03*
X99754Y155807D03*
X101675Y160694D03*
X110616Y756766D03*
X103574D03*
Y760266D03*
X99024Y776911D03*
X110616Y763766D03*
X103574Y767266D03*
X110616Y767400D03*
X110485Y771366D03*
X103574Y763766D03*
X104474Y790297D03*
X99024Y783604D03*
X109716Y786950D03*
X110766Y791970D03*
X99024Y780257D03*
Y786950D03*
Y807029D03*
X104474Y800336D03*
X109716Y796989D03*
X99024Y803682D03*
Y793643D03*
Y796989D03*
Y813722D03*
Y820415D03*
Y817068D03*
Y810375D03*
X104474Y827108D03*
Y837147D03*
X109716Y823761D03*
Y833800D03*
X110766Y828781D03*
X99024Y823761D03*
Y830454D03*
Y833800D03*
Y843840D03*
Y850533D03*
Y840493D03*
Y847186D03*
Y857226D03*
X104474Y863919D03*
X109716Y860572D03*
X110766Y865592D03*
X99024Y853879D03*
Y860572D03*
Y880651D03*
X104474Y873958D03*
X109716Y870611D03*
X99024Y877304D03*
Y867265D03*
Y870611D03*
Y887344D03*
Y894037D03*
Y883997D03*
Y890690D03*
X104474Y900730D03*
X109716Y897383D03*
X110766Y902403D03*
X104474Y910769D03*
X109716Y907423D03*
X99024Y897383D03*
Y904076D03*
Y907423D03*
Y924155D03*
Y917462D03*
Y914115D03*
Y920808D03*
X104474Y937541D03*
X99024Y930848D03*
X110766Y939214D03*
X109716Y934194D03*
X99024Y927501D03*
Y934194D03*
Y940887D03*
Y954273D03*
X104474Y947580D03*
X109716Y944234D03*
X99024Y950926D03*
Y944234D03*
Y960966D03*
Y967659D03*
Y964312D03*
Y957619D03*
Y971005D03*
Y974352D03*
Y981045D03*
Y977698D03*
Y984391D03*
Y987737D03*
Y994430D03*
Y1001123D03*
Y997777D03*
Y991084D03*
Y1004470D03*
Y1034588D03*
Y1041281D03*
Y1031241D03*
Y1037934D03*
Y1044627D03*
Y1047974D03*
Y1054667D03*
Y1058013D03*
Y1051320D03*
Y1071399D03*
Y1061360D03*
Y1074745D03*
Y1068052D03*
Y1064706D03*
Y1078092D03*
X109716Y1081438D03*
X110766Y1086458D03*
X104474Y1084785D03*
X99024Y1081438D03*
Y1088131D03*
Y1101517D03*
X104474Y1094824D03*
X109716Y1091478D03*
X99024Y1098171D03*
Y1104863D03*
Y1091478D03*
Y1114903D03*
Y1108210D03*
X109716Y1118249D03*
X99024Y1111556D03*
Y1118249D03*
X104474Y1121596D03*
X109716Y1128289D03*
X110766Y1123269D03*
X104474Y1131635D03*
X99024Y1134982D03*
Y1124942D03*
Y1128289D03*
Y1145021D03*
Y1138328D03*
Y1148367D03*
Y1141675D03*
X104474Y1158407D03*
X99024Y1151714D03*
X109716Y1165100D03*
X110766Y1160080D03*
X109716Y1155060D03*
X99024D03*
Y1161753D03*
Y1165100D03*
Y1175139D03*
X104474Y1168446D03*
X99024Y1171793D03*
Y1178486D03*
Y1181832D03*
Y1188525D03*
X109716Y1191871D03*
X99024Y1185178D03*
Y1191871D03*
X104474Y1195218D03*
Y1205257D03*
X110766Y1196891D03*
X109716Y1201911D03*
X99024Y1208604D03*
Y1198564D03*
Y1201911D03*
Y1211950D03*
Y1218643D03*
Y1215297D03*
Y1221989D03*
X104474Y1232029D03*
X99024Y1225336D03*
X109716Y1228682D03*
Y1238722D03*
X110766Y1233702D03*
X99024Y1228682D03*
Y1235375D03*
Y1238722D03*
X104474Y1242068D03*
X99024Y1248761D03*
Y1245415D03*
Y1252108D03*
Y1255454D03*
X105165Y1300380D03*
Y1302880D03*
X107665D03*
Y1300380D03*
X102665Y1302880D03*
Y1300380D03*
X105165Y1305380D03*
X107665D03*
X102665D03*
Y1307880D03*
Y1310380D03*
Y1312880D03*
X105165Y1307880D03*
Y1310380D03*
Y1312880D03*
X107665D03*
Y1310380D03*
Y1307880D03*
X105165Y1315380D03*
X107665D03*
X105165Y1317880D03*
X107665D03*
X102665D03*
Y1315380D03*
X99211Y1337771D03*
X112677Y1357409D03*
X110077D03*
X107477D03*
X104877D03*
X111581Y1372872D03*
X106721Y1367272D03*
Y1372872D03*
X109151D03*
X112677Y1363473D03*
X110077D03*
X112677Y1360516D03*
X110077D03*
X107477D03*
X104877D03*
X100347Y1361417D03*
X109151Y1367272D03*
X111581D03*
X98101Y1369018D03*
Y1371559D03*
X111630Y1385287D03*
X104863Y1382593D03*
X99594Y1379933D03*
X104863Y1380085D03*
X112305Y1382130D03*
X111555Y1379562D03*
X101874Y1376408D03*
X110000Y1407425D03*
X110075Y1410500D03*
X112355Y1426064D03*
Y1433564D03*
Y1441064D03*
X101955Y1448660D03*
X101500Y1436000D03*
X112481Y1452424D03*
X103571Y1476485D03*
X103555Y1485128D03*
Y1479128D03*
Y1482128D03*
X109733Y1491367D03*
X110605Y1487896D03*
X104184Y1491292D03*
X106784D03*
X105453Y1487893D03*
X108053D03*
X102931Y1488097D03*
X101584Y1491292D03*
X106396Y1485113D03*
X108996D03*
X106371Y1482181D03*
X108971D03*
X107197Y1501756D03*
X109712Y1499196D03*
X104616Y1501811D03*
X107112Y1499196D03*
X109733Y1493967D03*
Y1496567D03*
X106784Y1493892D03*
Y1496492D03*
X101634D03*
X104512Y1499196D03*
X104184Y1496492D03*
Y1493892D03*
X101534Y1499244D03*
X101634Y1493992D03*
X101835Y1501863D03*
X109878Y1501879D03*
X98492Y1523287D03*
X100922D03*
X109635Y1523158D03*
X106713Y1523098D03*
X103513D03*
X99978Y1533150D03*
X98492Y1526394D03*
X98424Y1529501D03*
X100922Y1526394D03*
X101024Y1529501D03*
X108861Y1528840D03*
Y1526410D03*
X101396Y1552769D03*
X99978Y1538750D03*
X102011Y1550242D03*
X99818Y1546296D03*
X103468Y1538946D03*
X105898D03*
X108328D03*
X110655D03*
X111196Y1542569D03*
X111901Y1545543D03*
X102096Y1555442D03*
X112418Y1555680D03*
X112339Y1565015D03*
Y1562515D03*
X112418Y1558180D03*
X99986Y1574205D03*
Y1576705D03*
X108555Y1574657D03*
Y1577462D03*
X110144Y1597831D03*
X110996Y1592018D03*
X98824Y1593558D03*
X101524D03*
X98824Y1596058D03*
X101524D03*
X101637Y1598606D03*
X98937D03*
X112353Y1646612D03*
X112473Y1660235D03*
X109073D03*
X106573D03*
X101939Y1657742D03*
Y1662728D03*
X112473Y1660235D03*
X109073D03*
X110378Y1670313D03*
X99443Y1661931D03*
Y1658531D03*
X110969Y1685763D03*
X107569D03*
X100443Y1684063D03*
Y1687463D03*
X105069Y1685763D03*
X102243Y1682263D03*
X107569Y1685763D03*
X110969D03*
X110378Y1674313D03*
X100443Y1684063D03*
X102243Y1689263D03*
X100443Y1687463D03*
X124490Y19541D03*
X127890D03*
X119928Y3001D03*
X114486Y17045D03*
X123683D03*
X120785Y26477D03*
X117385D03*
X113716Y19541D03*
X120785Y26477D03*
X117385D03*
X124490Y19541D03*
X123563Y25977D03*
X114607D03*
X122621Y28406D03*
X116607Y23981D03*
X121563D03*
X115534Y28406D03*
X114486Y22037D03*
X116494Y19541D03*
X121712D03*
X123683Y22037D03*
X122631Y37106D03*
X115544D03*
X115534Y40020D03*
X122621D03*
X115544Y48720D03*
X122631D03*
X127153Y69343D03*
X116157Y75340D03*
X119557D03*
X113457D03*
X115367Y72847D03*
X120347D03*
X122257Y75340D03*
X126367Y71842D03*
X124457Y69343D03*
X126367Y66850D03*
X116157Y75340D03*
X127153Y69343D03*
X119557Y75340D03*
X115367Y77839D03*
X120347D03*
X115016Y300281D03*
Y320715D03*
X120891Y521216D03*
X118407Y526766D03*
X113042Y686285D03*
X113980Y717480D03*
X116480D03*
X118980D03*
X121480D03*
X123980D03*
X113980Y714980D03*
X116480D03*
X118980D03*
X121480D03*
X123980D03*
X116480Y722480D03*
X118980D03*
X121480D03*
X123980D03*
X113980Y719980D03*
X116480D03*
X118980D03*
X121480D03*
X123980D03*
X113980Y722480D03*
X124224Y760178D03*
Y756832D03*
X119666D03*
X115166Y776911D03*
Y773564D03*
X119616Y767166D03*
X115166Y776911D03*
X119666Y763525D03*
X124174D03*
X119716Y770218D03*
X128724Y780257D03*
Y786950D03*
X115166Y783604D03*
Y790297D03*
Y793643D03*
X128724D03*
X115166Y780257D03*
Y783604D03*
Y790297D03*
Y800336D03*
Y807029D03*
X128724Y803682D03*
Y796989D03*
X124324Y795316D03*
X115166Y803682D03*
Y800336D03*
Y807029D03*
Y793643D03*
X128724Y817068D03*
Y810375D03*
X115166Y813722D03*
Y820415D03*
X128724Y823761D03*
X115166Y810375D03*
Y817068D03*
Y813722D03*
Y820415D03*
Y837147D03*
Y830454D03*
Y827108D03*
X128724Y830454D03*
Y833800D03*
X124324Y832127D03*
X115166Y837147D03*
Y830454D03*
Y827108D03*
X128724Y840493D03*
Y847186D03*
X115166Y843840D03*
Y850533D03*
X128724Y853879D03*
X115166Y840493D03*
Y847186D03*
Y843840D03*
Y850533D03*
Y857226D03*
Y863919D03*
X128724Y860572D03*
Y867265D03*
X115166D03*
Y853879D03*
Y857226D03*
Y863919D03*
X128724Y877304D03*
Y870611D03*
X115166Y873958D03*
Y880651D03*
X128724Y883997D03*
X115166Y877304D03*
X124324Y868938D03*
X115166Y873958D03*
Y880651D03*
Y867265D03*
Y887344D03*
Y894037D03*
X128724Y890690D03*
Y897383D03*
X115166Y890690D03*
Y883997D03*
Y887344D03*
Y894037D03*
X128724Y904076D03*
Y907423D03*
X115166Y910769D03*
Y904076D03*
Y900730D03*
X124324Y905750D03*
X115166Y910769D03*
Y904076D03*
Y900730D03*
Y924155D03*
Y917462D03*
X128724Y914115D03*
Y920808D03*
Y927501D03*
X115166Y920808D03*
Y914115D03*
Y924155D03*
Y917462D03*
X128724Y934194D03*
Y940887D03*
X115166Y930848D03*
Y940887D03*
Y937541D03*
Y927501D03*
Y930848D03*
Y940887D03*
Y937541D03*
Y947580D03*
Y954273D03*
X128724Y950926D03*
Y944234D03*
Y957619D03*
X115166Y950926D03*
X124324Y942561D03*
X115166Y947580D03*
Y954273D03*
X128724Y964312D03*
Y971005D03*
X120666Y960966D03*
X115166Y967659D03*
Y957619D03*
Y971005D03*
Y964312D03*
Y960966D03*
X120666D03*
X115166Y967659D03*
Y974352D03*
Y981045D03*
X128724Y977698D03*
Y984391D03*
X115166Y987737D03*
Y984391D03*
Y977698D03*
Y974352D03*
Y981045D03*
X128724Y1001123D03*
Y997777D03*
Y991084D03*
X115166Y994430D03*
Y1001123D03*
Y991084D03*
Y997777D03*
Y987737D03*
Y994430D03*
Y1001123D03*
Y1004470D03*
Y1027895D03*
X128724Y1031241D03*
X115166Y1027895D03*
Y1034588D03*
Y1041281D03*
X128724Y1037934D03*
Y1044627D03*
X115166Y1047974D03*
Y1031241D03*
Y1037934D03*
Y1044627D03*
Y1034588D03*
Y1041281D03*
X128724Y1058013D03*
Y1051320D03*
X115166Y1054667D03*
Y1061360D03*
Y1051320D03*
Y1058013D03*
Y1047974D03*
Y1054667D03*
Y1071399D03*
Y1064706D03*
X128724Y1074745D03*
X115166Y1068052D03*
Y1074745D03*
Y1061360D03*
Y1071399D03*
Y1064706D03*
X128724Y1081438D03*
Y1088131D03*
X115166Y1078092D03*
Y1088131D03*
Y1084785D03*
X128724Y1091478D03*
X124324Y1089805D03*
X115166Y1078092D03*
Y1088131D03*
Y1084785D03*
Y1094824D03*
Y1101517D03*
X128724Y1098171D03*
Y1104863D03*
X115166Y1098171D03*
Y1104863D03*
Y1094824D03*
Y1101517D03*
X128724Y1111556D03*
Y1118249D03*
X115166Y1108210D03*
Y1114903D03*
Y1121596D03*
Y1111556D03*
Y1108210D03*
Y1114903D03*
Y1131635D03*
Y1124942D03*
X128724Y1134982D03*
Y1124942D03*
Y1128289D03*
X124324Y1126616D03*
X115166Y1134982D03*
Y1131635D03*
Y1124942D03*
Y1121596D03*
X128724Y1148367D03*
Y1141675D03*
X115166Y1138328D03*
Y1145021D03*
Y1151714D03*
Y1148367D03*
Y1141675D03*
Y1138328D03*
Y1145021D03*
Y1161753D03*
Y1158407D03*
X128724Y1155060D03*
Y1161753D03*
Y1165100D03*
X124324Y1163427D03*
X115166Y1151714D03*
Y1161753D03*
Y1158407D03*
X128724Y1171793D03*
Y1178486D03*
X115166Y1168446D03*
Y1175139D03*
Y1181832D03*
Y1178486D03*
Y1171793D03*
Y1168446D03*
Y1175139D03*
Y1188525D03*
X128724Y1185178D03*
Y1191871D03*
X115166Y1195218D03*
Y1185178D03*
Y1181832D03*
Y1188525D03*
X128724Y1208604D03*
Y1198564D03*
Y1201911D03*
X115166Y1205257D03*
Y1198564D03*
Y1211950D03*
Y1208604D03*
X124324Y1200238D03*
X115166Y1205257D03*
Y1198564D03*
Y1195218D03*
Y1218643D03*
X128724Y1215297D03*
Y1221989D03*
X115166Y1225336D03*
Y1215297D03*
Y1221989D03*
Y1211950D03*
Y1218643D03*
X128724Y1228682D03*
Y1235375D03*
Y1238722D03*
X115166Y1235375D03*
Y1232029D03*
X124324Y1237049D03*
X115166Y1225336D03*
Y1235375D03*
Y1232029D03*
Y1242068D03*
Y1248761D03*
X128724Y1245415D03*
Y1252108D03*
X115166D03*
Y1245415D03*
Y1242068D03*
Y1248761D03*
X120965Y1307880D03*
Y1310380D03*
Y1312880D03*
X118465D03*
Y1310380D03*
Y1307880D03*
Y1300380D03*
X123465Y1302880D03*
Y1300380D03*
X120965Y1305380D03*
X118465D03*
X123465D03*
Y1307880D03*
Y1310380D03*
Y1312880D03*
X120965Y1300380D03*
Y1302880D03*
X118465D03*
X120965Y1315380D03*
X118465D03*
X120965Y1317880D03*
X118465D03*
X123465D03*
Y1315380D03*
X124071Y1337843D03*
X126671D03*
X115277Y1357409D03*
X126491Y1354871D03*
X125241Y1357371D03*
X126491Y1352271D03*
X123891Y1354871D03*
Y1352271D03*
X120221Y1357425D03*
X126491Y1349671D03*
X123891D03*
X117777Y1357409D03*
X121207Y1363643D03*
Y1360686D03*
X115321Y1372872D03*
X120181D03*
X117751D03*
X121241Y1367047D03*
Y1369947D03*
X127211Y1373177D03*
Y1378977D03*
X125111Y1377577D03*
X122945Y1379207D03*
X127211Y1376077D03*
X125011Y1374577D03*
X122945Y1376307D03*
X126000Y1418000D03*
X119855Y1426064D03*
X127355Y1433564D03*
Y1426064D03*
X119855Y1441064D03*
X127355D03*
X113600Y1449100D03*
X116122Y1458000D03*
X124600Y1465100D03*
X114405Y1509335D03*
Y1516335D03*
Y1512835D03*
Y1519835D03*
Y1522835D03*
X116905D03*
Y1519835D03*
Y1512835D03*
Y1516335D03*
Y1509335D03*
Y1526335D03*
X113100Y1537346D03*
X114030Y1542419D03*
X114610Y1545543D03*
X127374Y1572749D03*
X127392Y1575524D03*
X125768Y1568744D03*
X127246Y1585801D03*
X127264Y1588576D03*
X113496Y1592018D03*
X121705Y1619460D03*
X114618Y1624541D03*
X117655Y1621766D03*
X118956Y1635244D03*
X126717Y1635893D03*
X116353Y1646612D03*
X120353D03*
X124353D03*
X123278Y1658587D03*
X114973Y1660235D03*
X126428Y1658587D03*
X113469Y1685763D03*
X126760Y1682383D03*
X119353Y1695941D03*
X123353D03*
X127353Y1696062D03*
X125107Y1702666D03*
X124461Y1726116D03*
X114596Y1737117D03*
X141928Y3001D03*
X128663Y17045D03*
X127890Y19541D03*
X129708Y28406D03*
X130668Y19541D03*
X128663Y22037D03*
X129718Y37106D03*
X129708Y40020D03*
X129718Y48720D03*
X141557Y75340D03*
X138157D03*
X130553Y69343D03*
X135457Y75340D03*
X137367Y72847D03*
X142347D03*
X133257Y69343D03*
X131347Y71842D03*
Y66850D03*
X138157Y75340D03*
X141557D03*
X130553Y69343D03*
X137367Y77839D03*
X142347D03*
X128367Y202241D03*
Y207241D03*
Y197241D03*
Y212241D03*
X140360Y430160D03*
X139440Y439000D03*
X138090Y441900D03*
X140800Y441920D03*
X141642Y491434D03*
Y488684D03*
Y494147D03*
X139980Y507420D03*
X139890Y503440D03*
X131861Y664958D03*
X131752Y668506D03*
X139869Y686582D03*
X131752Y686074D03*
X131960Y679290D03*
X140316Y756766D03*
X133124D03*
Y760266D03*
X128724Y776911D03*
X140316Y763766D03*
X133124Y767266D03*
X140317Y767400D03*
Y771200D03*
X133124Y763766D03*
X134174Y790297D03*
X139416Y786950D03*
X128724Y783604D03*
X140466Y791970D03*
X128724Y780257D03*
Y786950D03*
Y807029D03*
X134174Y800336D03*
X139416Y796989D03*
X128724Y803682D03*
Y793643D03*
Y796989D03*
Y813722D03*
Y820415D03*
Y817068D03*
Y810375D03*
X134174Y837147D03*
X139416Y823761D03*
Y833800D03*
X140466Y828781D03*
X134174Y827108D03*
X128724Y823761D03*
Y830454D03*
Y833800D03*
Y843840D03*
Y850533D03*
Y840493D03*
Y847186D03*
Y857226D03*
X134174Y863919D03*
X139416Y860572D03*
X140466Y865592D03*
X128724Y853879D03*
Y860572D03*
X134174Y873958D03*
X128724Y880651D03*
X139416Y870611D03*
X128724Y877304D03*
Y867265D03*
Y870611D03*
Y887344D03*
Y894037D03*
Y883997D03*
Y890690D03*
X134174Y900730D03*
X139416Y897383D03*
X140466Y902403D03*
X134174Y910769D03*
X139416Y907423D03*
X128724Y897383D03*
Y904076D03*
Y907423D03*
Y924155D03*
Y917462D03*
Y914115D03*
Y920808D03*
X134174Y937541D03*
X140466Y939214D03*
X139416Y934194D03*
X128724Y930848D03*
Y927501D03*
Y934194D03*
Y940887D03*
Y954273D03*
X134174Y947580D03*
X139416Y944234D03*
X128724Y950926D03*
Y944234D03*
Y960966D03*
Y967659D03*
Y964312D03*
Y957619D03*
Y971005D03*
Y974352D03*
Y981045D03*
Y977698D03*
Y984391D03*
Y987737D03*
Y994430D03*
Y1001123D03*
Y997777D03*
Y991084D03*
Y1004470D03*
Y1034588D03*
Y1041281D03*
Y1031241D03*
Y1037934D03*
Y1044627D03*
Y1047974D03*
Y1054667D03*
Y1058013D03*
Y1051320D03*
Y1071399D03*
Y1061360D03*
Y1074745D03*
Y1068052D03*
Y1064706D03*
X139416Y1081438D03*
X134174Y1084785D03*
X140466Y1086458D03*
X128724Y1078092D03*
Y1081438D03*
Y1088131D03*
Y1101517D03*
X139416Y1091478D03*
X134174Y1094824D03*
X128724Y1098171D03*
Y1104863D03*
Y1091478D03*
Y1114903D03*
X139416Y1118249D03*
X128724Y1108210D03*
Y1111556D03*
Y1118249D03*
X139416Y1128289D03*
X134174Y1121596D03*
X140466Y1123269D03*
X134174Y1131635D03*
X128724Y1134982D03*
Y1124942D03*
Y1128289D03*
Y1145021D03*
Y1138328D03*
Y1148367D03*
Y1141675D03*
X139416Y1165100D03*
X140466Y1160080D03*
X134174Y1158407D03*
X139416Y1155060D03*
X128724Y1151714D03*
Y1155060D03*
Y1161753D03*
Y1165100D03*
Y1175139D03*
X134174Y1168446D03*
X128724Y1171793D03*
Y1178486D03*
Y1181832D03*
X139416Y1191871D03*
X128724Y1188525D03*
Y1185178D03*
Y1191871D03*
X134174Y1195218D03*
X140466Y1196891D03*
X134174Y1205257D03*
X139416Y1201911D03*
X128724Y1208604D03*
Y1198564D03*
Y1201911D03*
Y1211950D03*
Y1218643D03*
Y1215297D03*
Y1221989D03*
Y1225336D03*
X134174Y1232029D03*
X139416Y1228682D03*
X140466Y1233702D03*
X139416Y1238722D03*
X128724Y1228682D03*
Y1235375D03*
Y1238722D03*
X134174Y1242068D03*
X128724Y1248761D03*
Y1245415D03*
Y1252108D03*
Y1255454D03*
X140265Y1307880D03*
Y1310380D03*
Y1312880D03*
X137765D03*
Y1310380D03*
Y1307880D03*
X135265Y1312880D03*
Y1310380D03*
Y1307880D03*
Y1305380D03*
X140265D03*
X137765D03*
X135265Y1300380D03*
Y1302880D03*
X140265Y1300380D03*
Y1302880D03*
X137765D03*
Y1300380D03*
X140265Y1315380D03*
X137765D03*
X135265D03*
Y1317880D03*
X140265D03*
X137765D03*
X137551Y1337771D03*
X131791Y1337811D03*
X140077Y1357409D03*
X137477D03*
X139321Y1367272D03*
Y1372872D03*
X141751D03*
X140077Y1360516D03*
X137477D03*
X132947Y1361417D03*
X141751Y1367272D03*
X130701Y1369018D03*
Y1371559D03*
X130492Y1384789D03*
X132150Y1386740D03*
X137463Y1382593D03*
X132194Y1379933D03*
X137463Y1380085D03*
X141417Y1380530D03*
X134474Y1376408D03*
X142000Y1414500D03*
X136000Y1432000D03*
X141500Y1429500D03*
X137120Y1454751D03*
X128661Y1464000D03*
X128617Y1561022D03*
X139802Y1556133D03*
X129892Y1575524D03*
X129874Y1572749D03*
X128268Y1568744D03*
X129764Y1588576D03*
X129746Y1585801D03*
X129070Y1608338D03*
X142576Y1640163D03*
Y1643563D03*
X140775Y1638035D03*
X135543Y1637055D03*
X128353Y1646612D03*
X140353D03*
X132353D03*
X136353D03*
X136048Y1666851D03*
X142465Y1662493D03*
X133548Y1677351D03*
X135353Y1696062D03*
X132643Y1711846D03*
X142293Y1705166D03*
X129493Y1711846D03*
X135722Y1715672D03*
X130000Y1719450D03*
X136596Y1737117D03*
X156651Y26477D03*
X153251D03*
X156651D03*
X153251D03*
X150473Y25977D03*
X157429Y23981D03*
X152473D03*
X151400Y28406D03*
X147920Y28261D03*
X151410Y37106D03*
X151400Y40020D03*
X151410Y48720D03*
X148780D03*
X149153Y69343D03*
X152553D03*
X144257Y75340D03*
X153347Y71842D03*
X148367D03*
X153347Y66850D03*
X148367D03*
X155253Y69343D03*
X146453D03*
X149153D03*
X152553D03*
X150318Y233536D03*
X144610Y429560D03*
X142660Y438930D03*
X143720Y441960D03*
X145960Y438800D03*
X146930Y441870D03*
X149210Y438640D03*
X149830Y441920D03*
X146982Y521997D03*
Y530997D03*
X149672Y665500D03*
X152822D03*
X153925Y760178D03*
Y756832D03*
X149366D03*
X144866Y776911D03*
Y773564D03*
X149416Y766871D03*
X144866Y776911D03*
X149366Y763525D03*
X153875D03*
X149416Y770218D03*
X158425Y780257D03*
Y786950D03*
X144866Y783604D03*
Y790297D03*
Y793643D03*
X158425D03*
X144866Y780257D03*
Y783604D03*
Y790297D03*
Y800336D03*
Y807029D03*
X158425Y803682D03*
Y796989D03*
X154025Y795316D03*
X144866Y803682D03*
Y800336D03*
Y807029D03*
Y793643D03*
X158425Y817068D03*
Y810375D03*
X144866Y813722D03*
Y820415D03*
X158425Y823761D03*
X144866Y810375D03*
Y817068D03*
Y813722D03*
Y820415D03*
Y837147D03*
Y830454D03*
Y827108D03*
X158425Y830454D03*
Y833800D03*
X154025Y832127D03*
X144866Y837147D03*
Y830454D03*
Y827108D03*
X158425Y840493D03*
Y847186D03*
X144866Y843840D03*
Y850533D03*
X158425Y853879D03*
X144866Y840493D03*
Y847186D03*
Y843840D03*
Y850533D03*
Y857226D03*
Y863919D03*
X158425Y860572D03*
Y867265D03*
X144866D03*
Y853879D03*
Y857226D03*
Y863919D03*
X158425Y877304D03*
Y870611D03*
X144866Y873958D03*
Y880651D03*
X158425Y883997D03*
X144866Y877304D03*
X154025Y868938D03*
X144866Y873958D03*
Y880651D03*
Y867265D03*
Y887344D03*
Y894037D03*
X158425Y890690D03*
Y897383D03*
X144866Y890690D03*
Y883997D03*
Y887344D03*
Y894037D03*
X158425Y904076D03*
Y907423D03*
X144866Y910769D03*
Y904076D03*
Y900730D03*
X154025Y905750D03*
X144866Y910769D03*
Y904076D03*
Y900730D03*
Y924155D03*
Y917462D03*
X158425Y914115D03*
Y920808D03*
Y927501D03*
X144866Y920808D03*
Y914115D03*
Y924155D03*
Y917462D03*
X158425Y934194D03*
Y940887D03*
X144866Y930848D03*
Y940887D03*
Y937541D03*
Y927501D03*
Y930848D03*
Y940887D03*
Y937541D03*
Y947580D03*
Y954273D03*
X158425Y950926D03*
Y944234D03*
Y957619D03*
X154025Y942561D03*
X144866Y950926D03*
Y947580D03*
Y954273D03*
X158425Y964312D03*
Y971005D03*
X150366Y960966D03*
X144866Y967659D03*
Y957619D03*
Y971005D03*
Y964312D03*
Y960966D03*
X150366D03*
X144866Y967659D03*
Y974352D03*
Y981045D03*
X158425Y977698D03*
Y984391D03*
X144866Y987737D03*
Y984391D03*
Y977698D03*
Y974352D03*
Y981045D03*
X158425Y1001123D03*
Y997777D03*
Y991084D03*
X144866Y994430D03*
Y1001123D03*
Y991084D03*
Y997777D03*
Y987737D03*
Y994430D03*
Y1001123D03*
Y1004470D03*
Y1027895D03*
X158425Y1031241D03*
X144866Y1027895D03*
Y1034588D03*
Y1041281D03*
X158425Y1037934D03*
Y1044627D03*
X144866Y1047974D03*
Y1031241D03*
Y1037934D03*
Y1044627D03*
Y1034588D03*
Y1041281D03*
X158425Y1058013D03*
Y1051320D03*
X144866Y1054667D03*
Y1061360D03*
Y1051320D03*
Y1058013D03*
Y1047974D03*
Y1054667D03*
Y1071399D03*
Y1064706D03*
X158425Y1074745D03*
X144866Y1068052D03*
Y1074745D03*
Y1061360D03*
Y1071399D03*
Y1064706D03*
X158425Y1081438D03*
Y1088131D03*
X144866Y1078092D03*
Y1088131D03*
Y1084785D03*
X158425Y1091478D03*
X154025Y1089805D03*
X144866Y1078092D03*
Y1088131D03*
Y1084785D03*
Y1094824D03*
Y1101517D03*
X158425Y1098171D03*
Y1104863D03*
X144866Y1098171D03*
Y1104863D03*
Y1094824D03*
Y1101517D03*
X158425Y1111556D03*
Y1118249D03*
X144866Y1108210D03*
Y1114903D03*
Y1121596D03*
Y1111556D03*
Y1108210D03*
Y1114903D03*
Y1131635D03*
Y1124942D03*
X158425Y1134982D03*
Y1124942D03*
Y1128289D03*
X154025Y1126616D03*
X144866Y1134982D03*
Y1131635D03*
Y1124942D03*
Y1121596D03*
X158425Y1148367D03*
Y1141675D03*
X144866Y1138328D03*
Y1145021D03*
Y1151714D03*
Y1148367D03*
Y1141675D03*
Y1138328D03*
Y1145021D03*
Y1161753D03*
Y1158407D03*
X158425Y1155060D03*
Y1161753D03*
Y1165100D03*
X154025Y1163427D03*
X144866Y1151714D03*
Y1161753D03*
Y1158407D03*
X158425Y1171793D03*
Y1178486D03*
X144866Y1168446D03*
Y1175139D03*
Y1181832D03*
Y1178486D03*
Y1171793D03*
Y1168446D03*
Y1175139D03*
Y1188525D03*
X158425Y1185178D03*
Y1191871D03*
X144866Y1195218D03*
Y1185178D03*
Y1181832D03*
Y1188525D03*
X158425Y1208604D03*
Y1198564D03*
Y1201911D03*
X144866Y1205257D03*
Y1198564D03*
Y1211950D03*
Y1208604D03*
X154025Y1200238D03*
X144866Y1205257D03*
Y1198564D03*
Y1195218D03*
Y1218643D03*
X158425Y1215297D03*
Y1221989D03*
X144866Y1225336D03*
Y1215297D03*
Y1221989D03*
Y1211950D03*
Y1218643D03*
X158425Y1228682D03*
Y1235375D03*
Y1238722D03*
X144866Y1235375D03*
Y1232029D03*
X154025Y1237049D03*
X144866Y1225336D03*
Y1235375D03*
Y1232029D03*
Y1242068D03*
Y1248761D03*
X158425Y1245415D03*
Y1252108D03*
X144866D03*
Y1245415D03*
Y1242068D03*
Y1248761D03*
X151065Y1307880D03*
Y1310380D03*
Y1312880D03*
X153565D03*
Y1310380D03*
Y1307880D03*
X156065Y1312880D03*
Y1310380D03*
Y1307880D03*
Y1305380D03*
X151065D03*
X153565D03*
X156065Y1300380D03*
Y1302880D03*
X151065Y1300380D03*
Y1302880D03*
X153565D03*
Y1300380D03*
X151065Y1315380D03*
X153565D03*
X156065D03*
Y1317880D03*
X151065D03*
X153565D03*
X156491Y1354871D03*
Y1352271D03*
X152821Y1357425D03*
X156491Y1349671D03*
X145277Y1357409D03*
X147877D03*
X142677D03*
X150377D03*
X144181Y1367272D03*
X153767Y1360456D03*
Y1363413D03*
X144181Y1372872D03*
X142677Y1360516D03*
X145277Y1363473D03*
X142677D03*
X145277Y1360516D03*
X152781Y1372872D03*
X150351D03*
X147921D03*
X153741Y1369977D03*
Y1367077D03*
X144230Y1385287D03*
X144905Y1382130D03*
X144155Y1379562D03*
X155545Y1379207D03*
Y1376307D03*
X145000Y1414425D03*
X150900Y1433500D03*
Y1429500D03*
Y1425500D03*
X143478Y1440000D03*
X151082Y1436653D03*
X146978Y1440000D03*
X154443Y1441195D03*
X156174Y1435396D03*
X154083Y1456007D03*
X145028Y1454705D03*
X148340Y1454674D03*
X154671Y1450019D03*
X155618Y1549331D03*
X155071Y1543604D03*
X152843Y1559146D03*
Y1562666D03*
X154945Y1624350D03*
Y1627750D03*
X152449Y1623572D03*
X154945Y1624350D03*
X146453Y1614879D03*
X152449Y1628528D03*
X154945Y1627750D03*
X142576Y1640163D03*
X148353Y1646612D03*
X144353D03*
X152353D03*
X142576Y1643563D03*
X154111Y1663933D03*
X157511D03*
X155328Y1670087D03*
X151611Y1663933D03*
X154111D03*
X157410Y1676811D03*
X154010D03*
X146928Y1685087D03*
X151510Y1676811D03*
X154010D03*
X157410D03*
X143778Y1685087D03*
X143353Y1696062D03*
X147253Y1696343D03*
X155353Y1687843D03*
X147277Y1712791D03*
X152815Y1705500D03*
X156825Y1705510D03*
X146086Y1705603D03*
X145267Y1722241D03*
X152496Y1722941D03*
X155260Y1723682D03*
X163756Y19541D03*
X160356D03*
X163928Y3001D03*
X164525Y17045D03*
X159545D03*
X170824Y26477D03*
X167424D03*
X170824D03*
X163756Y19541D03*
X167424Y26477D03*
X160356Y19541D03*
X159429Y25977D03*
X158487Y28406D03*
X164646Y25977D03*
X171602Y23981D03*
X166646D03*
X165574Y28406D03*
X157578Y19541D03*
X166534D03*
X171751D03*
X164525Y22037D03*
X159545D03*
X158497Y37106D03*
X165584D03*
X158487Y40020D03*
X165574D03*
X158497Y48720D03*
X165584D03*
X172361Y69340D03*
X161361Y75340D03*
X164761D03*
X158661D03*
X160571Y72847D03*
X165551D03*
X167461Y75340D03*
X171571Y71839D03*
X169661Y69340D03*
X171571Y66847D03*
X161361Y75340D03*
X164761D03*
X160571Y77839D03*
X165551D03*
X172120Y416600D03*
X168950Y412950D03*
X168910Y415930D03*
X172120Y412350D03*
X170500Y441420D03*
X167580Y441380D03*
X164870Y441360D03*
X169440Y438390D03*
X166220Y438460D03*
X166760Y506880D03*
X166670Y502900D03*
X162975Y760266D03*
Y756766D03*
X170017D03*
X158425Y776911D03*
X170017Y763766D03*
X162975Y767266D03*
X169987Y767666D03*
Y771266D03*
X162975Y763766D03*
X163875Y790297D03*
X158425Y783604D03*
X169117Y786950D03*
X170167Y791970D03*
X158425Y780257D03*
Y786950D03*
X163875Y800336D03*
X158425Y807029D03*
X169117Y796989D03*
X158425Y803682D03*
Y793643D03*
Y796989D03*
Y813722D03*
Y820415D03*
Y817068D03*
Y810375D03*
X163875Y837147D03*
X169117Y823761D03*
Y833800D03*
X170167Y828781D03*
X163875Y827108D03*
X158425Y823761D03*
Y830454D03*
Y833800D03*
Y843840D03*
Y850533D03*
Y840493D03*
Y847186D03*
X163875Y863919D03*
X158425Y857226D03*
X169117Y860572D03*
X170167Y865592D03*
X158425Y853879D03*
Y860572D03*
X163875Y873958D03*
X158425Y880651D03*
X169117Y870611D03*
X158425Y877304D03*
Y867265D03*
Y870611D03*
Y887344D03*
Y894037D03*
Y883997D03*
Y890690D03*
X163875Y900730D03*
X169117Y897383D03*
X170167Y902403D03*
X163875Y910769D03*
X169117Y907423D03*
X158425Y897383D03*
Y904076D03*
Y907423D03*
Y924155D03*
Y917462D03*
Y914115D03*
Y920808D03*
X163875Y937541D03*
X158425Y930848D03*
X170167Y939214D03*
X169117Y934194D03*
X158425Y927501D03*
Y934194D03*
Y940887D03*
X163875Y947580D03*
X158425Y954273D03*
X169117Y944234D03*
X158425Y950926D03*
Y944234D03*
Y960966D03*
Y967659D03*
Y964312D03*
Y957619D03*
Y971005D03*
Y974352D03*
Y981045D03*
Y977698D03*
Y984391D03*
Y987737D03*
Y994430D03*
Y1001123D03*
Y997777D03*
Y991084D03*
Y1004470D03*
Y1034588D03*
Y1041281D03*
Y1031241D03*
Y1037934D03*
Y1044627D03*
Y1047974D03*
Y1054667D03*
Y1058013D03*
Y1051320D03*
Y1071399D03*
Y1061360D03*
Y1074745D03*
Y1068052D03*
Y1064706D03*
X163875Y1084785D03*
X158425Y1078092D03*
X169117Y1081438D03*
X170167Y1086458D03*
X158425Y1081438D03*
Y1088131D03*
X163875Y1094824D03*
X158425Y1101517D03*
X169117Y1091478D03*
X158425Y1098171D03*
Y1104863D03*
Y1091478D03*
Y1114903D03*
Y1108210D03*
X169117Y1118249D03*
X158425Y1111556D03*
Y1118249D03*
X163875Y1121596D03*
X169117Y1128289D03*
X170167Y1123269D03*
X163875Y1131635D03*
X158425Y1134982D03*
Y1124942D03*
Y1128289D03*
Y1145021D03*
Y1138328D03*
Y1148367D03*
Y1141675D03*
X169117Y1165100D03*
X170167Y1160080D03*
X169117Y1155060D03*
X163875Y1158407D03*
X158425Y1151714D03*
Y1155060D03*
Y1161753D03*
Y1165100D03*
X163875Y1168446D03*
X158425Y1175139D03*
Y1171793D03*
Y1178486D03*
Y1181832D03*
Y1188525D03*
X169117Y1191871D03*
X158425Y1185178D03*
Y1191871D03*
X163875Y1195218D03*
Y1205257D03*
X170167Y1196891D03*
X169117Y1201911D03*
X158425Y1208604D03*
Y1198564D03*
Y1201911D03*
Y1211950D03*
Y1218643D03*
Y1215297D03*
Y1221989D03*
X163875Y1232029D03*
X158425Y1225336D03*
X169117Y1238722D03*
Y1228682D03*
X170167Y1233702D03*
X158425Y1228682D03*
Y1235375D03*
Y1238722D03*
X163875Y1242068D03*
X158425Y1248761D03*
Y1245415D03*
Y1252108D03*
Y1255454D03*
X170265Y1312880D03*
Y1310380D03*
Y1307880D03*
X167765Y1312880D03*
Y1310380D03*
Y1307880D03*
Y1305380D03*
X170265D03*
X167765Y1300380D03*
Y1302880D03*
X170265D03*
Y1300380D03*
Y1315380D03*
X167765D03*
Y1317880D03*
X170265D03*
X171481Y1337853D03*
X164481Y1337813D03*
X161881D03*
X170177Y1357409D03*
X159091Y1354871D03*
X157841Y1357371D03*
X159091Y1352271D03*
Y1349671D03*
X172021Y1367272D03*
Y1372872D03*
X170177Y1360516D03*
X165647Y1361417D03*
X163401Y1369018D03*
Y1371559D03*
X159811Y1373177D03*
X163192Y1384789D03*
X164850Y1386740D03*
X170163Y1382593D03*
X164894Y1379933D03*
X170163Y1380085D03*
X167174Y1376408D03*
X159811Y1378977D03*
Y1376077D03*
X157711Y1377577D03*
X157611Y1374577D03*
X163099Y1414400D03*
X162873Y1411611D03*
X163061Y1409048D03*
Y1406548D03*
X163421Y1425171D03*
Y1427671D03*
Y1430171D03*
Y1432671D03*
X160684Y1441046D03*
X158704Y1439411D03*
X161210Y1443542D03*
X163271Y1441588D03*
X169351Y1462595D03*
X172751D03*
X168661Y1459995D03*
X166751Y1462595D03*
X169351D03*
X163113Y1480190D03*
X168661Y1465195D03*
X163113Y1477590D03*
Y1483590D03*
Y1486190D03*
X160513Y1479500D03*
Y1484280D03*
X165713Y1479500D03*
Y1484280D03*
X163113Y1483590D03*
Y1480190D03*
X163460Y1491010D03*
X163113Y1501990D03*
Y1505390D03*
Y1499490D03*
X160513Y1501300D03*
Y1506080D03*
X165713D03*
X163113Y1507982D03*
X165713Y1501300D03*
X163113Y1501990D03*
Y1505390D03*
X163320Y1494340D03*
X164730Y1521561D03*
X161188Y1510800D03*
X162188Y1518040D03*
X164650Y1529350D03*
X162531Y1523331D03*
Y1526731D03*
X164650Y1540250D03*
X167666Y1550751D03*
X165166D03*
X162666D03*
X170166D03*
X170230Y1542960D03*
X160150Y1553251D03*
Y1555751D03*
X162666D03*
X165166D03*
X167666D03*
X170166D03*
Y1553251D03*
X167666D03*
X165166D03*
X162666D03*
X170166Y1567621D03*
X167666D03*
X165166D03*
X162666D03*
X170166Y1565121D03*
X167666D03*
X165166D03*
X162666D03*
Y1562621D03*
X165166D03*
X167666D03*
X170166D03*
X162466Y1570121D03*
X164966D03*
X167466D03*
X169966D03*
X163735Y1635369D03*
Y1631969D03*
X161239Y1636147D03*
Y1631191D03*
X163735Y1635369D03*
Y1631969D03*
X162995Y1661377D03*
X160011Y1663933D03*
X163003Y1666462D03*
X157511Y1663933D03*
X165491Y1665582D03*
Y1662182D03*
X159910Y1676811D03*
X162848Y1679357D03*
X162840Y1674272D03*
X165336Y1675077D03*
Y1678477D03*
X162740Y1704885D03*
X167500Y1712864D03*
X171925Y1727581D03*
X157860Y1718500D03*
X166467Y1720973D03*
X171925Y1717984D03*
X158596Y1737117D03*
X177929Y19541D03*
X174529D03*
X185928Y3001D03*
X173719Y17045D03*
X178699D03*
X177929Y19541D03*
X174529D03*
X173602Y25977D03*
X172660Y28406D03*
X179747D03*
X173719Y22037D03*
X178699D03*
X180707Y19541D03*
X172670Y37106D03*
X179757D03*
X172660Y40020D03*
X179747D03*
X172670Y48720D03*
X179757D03*
X186757Y75343D03*
X183357D03*
X175761Y69340D03*
X176551Y71839D03*
Y66847D03*
X178461Y69340D03*
X180657Y75343D03*
X182571Y72850D03*
X183357Y75343D03*
X172361Y69340D03*
X186757Y75343D03*
X175761Y69340D03*
X182571Y77842D03*
X184930Y125502D03*
X182548Y147260D03*
X181025Y159123D03*
X183890Y388180D03*
X173960Y400560D03*
X174320Y395040D03*
X176610Y441380D03*
X175990Y438100D03*
X173710Y441330D03*
X172740Y438260D03*
X173299Y664958D03*
X182500Y672500D03*
X172802Y682036D03*
X172500Y684799D03*
X183626Y760178D03*
Y756832D03*
X179067D03*
X174567Y776911D03*
Y773564D03*
X179117Y766871D03*
X174567Y776911D03*
X179067Y763525D03*
X183576D03*
X179117Y770218D03*
X188126Y780257D03*
Y786950D03*
X174567Y783604D03*
Y790297D03*
Y793643D03*
X188126D03*
X174567Y780257D03*
Y783604D03*
Y790297D03*
Y800336D03*
Y807029D03*
X188126Y803682D03*
Y796989D03*
X174567Y803682D03*
X183726Y795316D03*
X174567Y800336D03*
Y807029D03*
Y793643D03*
X188126Y817068D03*
Y810375D03*
X174567Y813722D03*
Y820415D03*
X188126Y823761D03*
X174567Y810375D03*
Y817068D03*
Y813722D03*
Y820415D03*
Y837147D03*
Y830454D03*
Y827108D03*
X188126Y830454D03*
Y833800D03*
X183726Y832127D03*
X174567Y837147D03*
Y830454D03*
Y827108D03*
X188126Y840493D03*
Y847186D03*
X174567Y843840D03*
Y850533D03*
X188126Y853879D03*
X174567Y840493D03*
Y847186D03*
Y843840D03*
Y850533D03*
Y857226D03*
Y863919D03*
X188126Y860572D03*
Y867265D03*
X174567D03*
Y853879D03*
Y857226D03*
Y863919D03*
X188126Y877304D03*
Y870611D03*
X174567Y873958D03*
Y880651D03*
X188126Y883997D03*
X174567Y877304D03*
X183726Y868938D03*
X174567Y873958D03*
Y880651D03*
Y867265D03*
Y887344D03*
Y894037D03*
X188126Y890690D03*
Y897383D03*
X174567Y890690D03*
Y883997D03*
Y887344D03*
Y894037D03*
X188126Y904076D03*
Y907423D03*
X174567Y910769D03*
Y904076D03*
Y900730D03*
X183726Y905750D03*
X174567Y910769D03*
Y904076D03*
Y900730D03*
Y924155D03*
Y917462D03*
X188126Y914115D03*
Y920808D03*
Y927501D03*
X174567Y920808D03*
Y914115D03*
Y924155D03*
Y917462D03*
X188126Y934194D03*
Y940887D03*
X174567Y930848D03*
Y940887D03*
Y937541D03*
Y927501D03*
Y930848D03*
Y940887D03*
Y937541D03*
Y947580D03*
Y954273D03*
X188126Y950926D03*
Y944234D03*
Y957619D03*
X174567Y950926D03*
X183726Y942561D03*
X174567Y947580D03*
Y954273D03*
X188126Y964312D03*
Y971005D03*
X180067Y960966D03*
X174567Y967659D03*
Y957619D03*
Y971005D03*
Y964312D03*
Y960966D03*
X180067D03*
X174567Y967659D03*
Y974352D03*
Y981045D03*
X188126Y977698D03*
Y984391D03*
X174567Y987737D03*
Y984391D03*
Y977698D03*
Y974352D03*
Y981045D03*
X188126Y1001123D03*
Y997777D03*
Y991084D03*
X174567Y994430D03*
Y1001123D03*
Y991084D03*
Y997777D03*
Y987737D03*
Y994430D03*
Y1001123D03*
Y1004470D03*
Y1027895D03*
X188126Y1031241D03*
X174567Y1027895D03*
Y1034588D03*
Y1041281D03*
X188126Y1037934D03*
Y1044627D03*
X174567Y1047974D03*
Y1031241D03*
Y1037934D03*
Y1044627D03*
Y1034588D03*
Y1041281D03*
X188126Y1058013D03*
Y1051320D03*
X174567Y1054667D03*
Y1061360D03*
Y1051320D03*
Y1058013D03*
Y1047974D03*
Y1054667D03*
Y1071399D03*
Y1064706D03*
X188126Y1074745D03*
X174567Y1068052D03*
Y1074745D03*
Y1061360D03*
Y1071399D03*
Y1064706D03*
X188126Y1081438D03*
Y1088131D03*
X174567Y1078092D03*
Y1088131D03*
Y1084785D03*
X188126Y1091478D03*
X183726Y1089805D03*
X174567Y1078092D03*
Y1088131D03*
Y1084785D03*
Y1094824D03*
Y1101517D03*
X188126Y1098171D03*
Y1104863D03*
X174567Y1098171D03*
Y1104863D03*
Y1094824D03*
Y1101517D03*
X188126Y1111556D03*
Y1118249D03*
X174567Y1108210D03*
Y1114903D03*
Y1121596D03*
Y1111556D03*
Y1108210D03*
Y1114903D03*
Y1131635D03*
Y1124942D03*
X188126Y1134982D03*
Y1124942D03*
Y1128289D03*
X174567Y1134982D03*
X183726Y1126616D03*
X174567Y1131635D03*
Y1124942D03*
Y1121596D03*
X188126Y1148367D03*
Y1141675D03*
X174567Y1138328D03*
Y1145021D03*
Y1151714D03*
Y1148367D03*
Y1141675D03*
Y1138328D03*
Y1145021D03*
Y1161753D03*
Y1158407D03*
X188126Y1155060D03*
Y1161753D03*
Y1165100D03*
X183726Y1163427D03*
X174567Y1151714D03*
Y1161753D03*
Y1158407D03*
X188126Y1171793D03*
Y1178486D03*
X174567Y1168446D03*
Y1175139D03*
Y1181832D03*
Y1178486D03*
Y1171793D03*
Y1168446D03*
Y1175139D03*
Y1188525D03*
X188126Y1185178D03*
Y1191871D03*
X174567Y1195218D03*
Y1185178D03*
Y1181832D03*
Y1188525D03*
X188126Y1208604D03*
Y1198564D03*
Y1201911D03*
X174567Y1205257D03*
Y1198564D03*
Y1211950D03*
Y1208604D03*
X183726Y1200238D03*
X174567Y1205257D03*
Y1198564D03*
Y1195218D03*
Y1218643D03*
X188126Y1215297D03*
Y1221989D03*
X174567Y1225336D03*
Y1215297D03*
Y1221989D03*
Y1211950D03*
Y1218643D03*
X188126Y1228682D03*
Y1235375D03*
Y1238722D03*
X174567Y1235375D03*
Y1232029D03*
X183726Y1237049D03*
X174567Y1225336D03*
Y1235375D03*
Y1232029D03*
Y1242068D03*
Y1248761D03*
X188126Y1245415D03*
Y1252108D03*
X174567D03*
Y1245415D03*
Y1242068D03*
Y1248761D03*
X183565Y1310380D03*
Y1312880D03*
X186065D03*
Y1310380D03*
Y1307880D03*
X172765D03*
Y1310380D03*
Y1312880D03*
X183565Y1307880D03*
Y1305380D03*
X186065D03*
X183565Y1300380D03*
Y1302880D03*
X186065D03*
Y1300380D03*
X172765Y1305380D03*
Y1300380D03*
Y1302880D03*
Y1315380D03*
X183565D03*
X186065D03*
X183565Y1317880D03*
X186065D03*
X172765D03*
X185701Y1337853D03*
X183101D03*
X174081D03*
X172777Y1357409D03*
X183077D03*
X185521Y1357425D03*
X175377Y1357409D03*
X177977D03*
X180577D03*
X176881Y1367272D03*
X174451D03*
X186467Y1360456D03*
Y1363413D03*
X172777Y1360516D03*
X176881Y1372872D03*
X174451D03*
X177977Y1363473D03*
X175377D03*
Y1360516D03*
X177977D03*
X185481Y1372872D03*
X183051D03*
X180621D03*
X186481Y1370147D03*
Y1367247D03*
X176930Y1385287D03*
X177605Y1382130D03*
X174117Y1380530D03*
X176855Y1379562D03*
X185558Y1418560D03*
Y1416060D03*
X183058Y1418560D03*
Y1416060D03*
X173164Y1406397D03*
Y1408897D03*
X172976Y1411460D03*
X173202Y1414249D03*
X172721Y1425171D03*
Y1430171D03*
Y1427671D03*
Y1432671D03*
X185558Y1421060D03*
Y1423560D03*
Y1426060D03*
X183058Y1421060D03*
Y1426060D03*
Y1423560D03*
Y1428560D03*
X185558D03*
X179451Y1452895D03*
X176051D03*
X173441Y1459995D03*
X175351Y1462595D03*
X182051Y1452895D03*
X173451D03*
X180141Y1450295D03*
X175361D03*
X180141Y1455495D03*
X175361D03*
X172751Y1462595D03*
X179451Y1452895D03*
X176051D03*
X173441Y1465195D03*
X186851Y1472295D03*
X177322Y1498320D03*
X173488Y1510800D03*
Y1514420D03*
Y1518040D03*
X173980Y1528731D03*
X188254Y1544997D03*
Y1548397D03*
X173490Y1542540D03*
X173050Y1555751D03*
Y1553251D03*
X178582Y1575390D03*
X181087Y1576135D03*
X178582Y1572490D03*
Y1569590D03*
X180292Y1582589D03*
X177792D03*
X188166Y1592380D03*
Y1624292D03*
X177509Y1653825D03*
X177666Y1649223D03*
X183974Y1656804D03*
X183920Y1653973D03*
X180103Y1668921D03*
X177672Y1657538D03*
X183986Y1659548D03*
X185254Y1686870D03*
X179999Y1699156D03*
X185173Y1695138D03*
X179444Y1708810D03*
X183813Y1705404D03*
X181760Y1731351D03*
X185760Y1731666D03*
X180596Y1737117D03*
X200785Y26477D03*
X197385D03*
X200785D03*
X197385D03*
X194607Y25977D03*
X196607Y23981D03*
X201563D03*
X195534Y28406D03*
X201712Y19541D03*
X195544Y37106D03*
X195534Y40020D03*
X195544Y48720D03*
X194361Y69340D03*
X197761D03*
X189457Y75343D03*
X193571Y71839D03*
X198551D03*
X191661Y69340D03*
X193571Y66847D03*
X198551D03*
X200461Y69340D03*
X187656Y72850D03*
X194361Y69340D03*
X197761D03*
X187656Y77842D03*
X200577Y125502D03*
X190000Y143000D03*
X191264Y147768D03*
X193610Y153951D03*
X192592Y353072D03*
X189410Y388180D03*
X195690Y415390D03*
X195730Y412410D03*
X200754Y603274D03*
X200405Y622385D03*
X188055Y731734D03*
X192676Y760266D03*
Y756766D03*
X199718D03*
X192676Y767266D03*
X199718Y763766D03*
X188126Y776911D03*
X199718Y767400D03*
X197651Y769241D03*
X192676Y763766D03*
X199868Y791970D03*
X198818Y786950D03*
X193576Y790297D03*
X188126Y783604D03*
Y780257D03*
Y786950D03*
X198818Y796989D03*
X193576Y800336D03*
X188126Y807029D03*
Y803682D03*
Y793643D03*
Y796989D03*
Y813722D03*
Y820415D03*
Y817068D03*
Y810375D03*
X199868Y828781D03*
X198818Y823761D03*
Y833800D03*
X193576Y827108D03*
Y837147D03*
X188126Y823761D03*
Y830454D03*
Y833800D03*
Y843840D03*
Y850533D03*
Y840493D03*
Y847186D03*
X199868Y865592D03*
X198818Y860572D03*
X193576Y863919D03*
X188126Y857226D03*
Y853879D03*
Y860572D03*
X198818Y870611D03*
X193576Y873958D03*
X188126Y880651D03*
Y877304D03*
Y867265D03*
Y870611D03*
Y887344D03*
Y894037D03*
Y883997D03*
Y890690D03*
X199868Y902403D03*
X198818Y897383D03*
X193576Y900730D03*
X198818Y907423D03*
X193576Y910769D03*
X188126Y897383D03*
Y904076D03*
Y907423D03*
Y917462D03*
Y924155D03*
Y914115D03*
Y920808D03*
X199868Y939214D03*
X198818Y934194D03*
X193576Y937541D03*
X188126Y930848D03*
Y927501D03*
Y934194D03*
Y940887D03*
X198818Y944234D03*
X193576Y947580D03*
X188126Y954273D03*
Y950926D03*
Y944234D03*
Y960966D03*
Y967659D03*
Y964312D03*
Y957619D03*
Y971005D03*
Y974352D03*
Y981045D03*
Y977698D03*
Y984391D03*
Y987737D03*
Y994430D03*
Y1001123D03*
Y997777D03*
Y991084D03*
Y1004470D03*
Y1034588D03*
Y1041281D03*
Y1031241D03*
Y1037934D03*
Y1044627D03*
Y1047974D03*
Y1054667D03*
Y1058013D03*
Y1051320D03*
Y1061360D03*
Y1071399D03*
Y1074745D03*
Y1068052D03*
Y1064706D03*
X199868Y1086458D03*
X193576Y1084785D03*
X198818Y1081438D03*
X188126Y1078092D03*
Y1081438D03*
Y1088131D03*
X198818Y1091478D03*
X193576Y1094824D03*
X188126Y1101517D03*
Y1098171D03*
Y1104863D03*
Y1091478D03*
X198818Y1118249D03*
X188126Y1108210D03*
Y1114903D03*
Y1111556D03*
Y1118249D03*
X199868Y1123269D03*
X193576Y1121596D03*
X198818Y1128289D03*
X193576Y1131635D03*
X188126Y1134982D03*
Y1124942D03*
Y1128289D03*
Y1138328D03*
Y1145021D03*
Y1148367D03*
Y1141675D03*
X199868Y1160080D03*
X198818Y1155060D03*
X193576Y1158407D03*
X198818Y1165100D03*
X188126Y1151714D03*
Y1155060D03*
Y1161753D03*
Y1165100D03*
X193576Y1168446D03*
X188126Y1175139D03*
Y1171793D03*
Y1178486D03*
X198818Y1191871D03*
X188126Y1181832D03*
Y1188525D03*
Y1185178D03*
Y1191871D03*
X199868Y1196891D03*
X198818Y1201911D03*
X193576Y1205257D03*
Y1195218D03*
X188126Y1208604D03*
Y1198564D03*
Y1201911D03*
Y1211950D03*
Y1218643D03*
Y1215297D03*
Y1221989D03*
X199868Y1233702D03*
X198818Y1228682D03*
X193576Y1232029D03*
X198818Y1238722D03*
X188126Y1225336D03*
Y1228682D03*
Y1235375D03*
Y1238722D03*
X193576Y1242068D03*
X188126Y1248761D03*
Y1245415D03*
Y1252108D03*
Y1255454D03*
X200365Y1312880D03*
Y1310380D03*
Y1307880D03*
Y1305380D03*
Y1300380D03*
Y1302880D03*
X188565Y1312880D03*
Y1310380D03*
Y1307880D03*
Y1305380D03*
Y1300380D03*
Y1302880D03*
X200365Y1315380D03*
Y1317880D03*
X188565Y1315380D03*
Y1317880D03*
X195771Y1337903D03*
X193171D03*
X190541Y1357371D03*
X189191Y1354871D03*
Y1352271D03*
X191791Y1354871D03*
Y1352271D03*
X189191Y1349671D03*
X191791D03*
X198547Y1361417D03*
X196301Y1369018D03*
Y1371559D03*
X192511Y1373177D03*
X196092Y1384789D03*
X197750Y1386740D03*
X197794Y1379933D03*
X200074Y1376408D03*
X188245Y1379207D03*
X190411Y1377577D03*
X192511Y1378977D03*
X190311Y1374577D03*
X188245Y1376307D03*
X192511Y1376077D03*
X200408Y1416249D03*
Y1418749D03*
X192983Y1417568D03*
X188058Y1416060D03*
Y1418560D03*
X190483Y1417568D03*
X197983D03*
X195483D03*
X188695Y1404813D03*
Y1407313D03*
X191995Y1404813D03*
Y1407313D03*
X194495Y1404813D03*
Y1407313D03*
X196995Y1404813D03*
Y1407313D03*
X199495Y1404813D03*
Y1407313D03*
X188507Y1409876D03*
X191807D03*
X194307D03*
X196807D03*
X199307D03*
X200558Y1421551D03*
X195483Y1420068D03*
X192983D03*
X195483Y1422568D03*
X197983D03*
X192983D03*
X188058Y1421060D03*
Y1423560D03*
X190483Y1420068D03*
Y1422568D03*
X197983Y1420068D03*
X188058Y1426060D03*
X199551Y1462595D03*
X196151D03*
X202851Y1452895D03*
X202151Y1462595D03*
X193551D03*
X200241Y1459995D03*
X195461D03*
X202161Y1450295D03*
X200251Y1452895D03*
X202161Y1455495D03*
X199551Y1462595D03*
X196151D03*
X192851Y1472295D03*
X189451D03*
X195451D03*
X193541Y1469695D03*
X188761D03*
X193541Y1474895D03*
X188761D03*
X200241Y1465195D03*
X195461D03*
X192851Y1472295D03*
X189451D03*
X192978Y1544997D03*
X197703D03*
X192978Y1548397D03*
X197703D03*
X202427Y1544997D03*
Y1548397D03*
X197703Y1550897D03*
X192978Y1550797D03*
X188254D03*
Y1544997D03*
X192978D03*
X197703D03*
X188254Y1548397D03*
X192978D03*
X197703D03*
X192951Y1560498D03*
X200226Y1592380D03*
X203626D03*
X191566D03*
X187388Y1594876D03*
X192344D03*
X199448D03*
X187388Y1589884D03*
X199448D03*
X192344D03*
X188166Y1592380D03*
X200226D03*
X191566D03*
X194196Y1602380D03*
X197596D03*
X194196Y1614292D03*
X197596D03*
X193418Y1604876D03*
Y1599884D03*
X198374D03*
Y1604876D03*
Y1611796D03*
X193418D03*
X194196Y1602380D03*
X197596D03*
X200226Y1624292D03*
X203626D03*
X191566D03*
X198374Y1616788D03*
X193418D03*
X192344Y1626788D03*
X199448D03*
X192344Y1621796D03*
X199448D03*
X187388D03*
Y1626788D03*
X188166Y1624292D03*
X200226D03*
X191566D03*
X194196Y1614292D03*
X197596D03*
X193679Y1640052D03*
D03*
Y1643452D03*
D03*
Y1640052D03*
X196081Y1639349D03*
X193679Y1643452D03*
X200848Y1655656D03*
X190242Y1656635D03*
X195504Y1645359D03*
X201120Y1668603D03*
X199040Y1666925D03*
X196366Y1664821D03*
X190271Y1671753D03*
X195153Y1679774D03*
X200424Y1686870D03*
X190391Y1701988D03*
X195300Y1694898D03*
X194000Y1712362D03*
X201531Y1715000D03*
X192745Y1707106D03*
X199547Y1704605D03*
X193274Y1709769D03*
X199843Y1709837D03*
X196763Y1710444D03*
X189760Y1731564D03*
X195150Y1723000D03*
X194000Y1720551D03*
X198760Y1719991D03*
X207890Y19541D03*
X204490D03*
X218663D03*
X207928Y3001D03*
X208659Y17045D03*
X203679D03*
X214958Y26477D03*
X211558D03*
X207890Y19541D03*
X214958Y26477D03*
X204490Y19541D03*
X211558Y26477D03*
X208780Y25977D03*
X203563D03*
X202621Y28406D03*
X210780Y23981D03*
X215736D03*
X216794Y28406D03*
X209708D03*
X210668Y19541D03*
X215885D03*
X208659Y22037D03*
X203679D03*
X202631Y37106D03*
X216804D03*
X209718D03*
X202621Y40020D03*
X209708D03*
X216794D03*
X202631Y48720D03*
X209718D03*
X216804D03*
X216491Y69343D03*
X205495Y75340D03*
X208895D03*
X202795D03*
X204705Y72847D03*
X209685D03*
X211595Y75340D03*
X213791Y69343D03*
X215705Y66850D03*
Y71842D03*
X216491Y69343D03*
X205495Y75340D03*
X208895D03*
X204705Y77839D03*
X209685D03*
X206760Y148760D03*
X203754Y595174D03*
X214999Y585668D03*
X211254Y595145D03*
X208254D03*
X203754Y603274D03*
X211009Y610001D03*
X208009D03*
X214202Y606943D03*
X208254Y603245D03*
X211254D03*
X214202Y609681D03*
X208326Y606918D03*
X211326D03*
X206805Y622385D03*
X203605D03*
X206805Y632385D03*
X203605D03*
X210199Y714074D03*
X206199D03*
X206254Y732537D03*
X206933Y737277D03*
X213327Y760178D03*
Y756832D03*
X208768D03*
X204268Y776911D03*
Y773564D03*
Y776911D03*
X208768Y763525D03*
X212772Y766871D03*
X213277Y763525D03*
X208818Y770218D03*
X204268Y783604D03*
Y790297D03*
Y793643D03*
Y780257D03*
Y783604D03*
Y790297D03*
Y800336D03*
Y807029D03*
X213427Y795316D03*
X204268Y803682D03*
Y800336D03*
Y807029D03*
Y793643D03*
Y813722D03*
Y820415D03*
Y810375D03*
Y817068D03*
Y813722D03*
Y820415D03*
Y837147D03*
Y830454D03*
Y827108D03*
X213427Y832127D03*
X204268Y837147D03*
Y830454D03*
Y827108D03*
Y843840D03*
Y850533D03*
Y840493D03*
Y847186D03*
Y843840D03*
Y850533D03*
Y857226D03*
Y863919D03*
Y867265D03*
Y853879D03*
Y857226D03*
Y863919D03*
Y873958D03*
Y880651D03*
X213427Y868938D03*
X204268Y877304D03*
Y873958D03*
Y880651D03*
Y867265D03*
Y887344D03*
Y894037D03*
Y883997D03*
Y890690D03*
Y887344D03*
Y894037D03*
Y910769D03*
Y904076D03*
Y900730D03*
X213427Y905750D03*
X204268Y910769D03*
Y904076D03*
Y900730D03*
Y924155D03*
Y917462D03*
Y914115D03*
Y920808D03*
Y924155D03*
Y917462D03*
Y930848D03*
Y940887D03*
Y937541D03*
Y927501D03*
Y930848D03*
Y940887D03*
Y937541D03*
Y947580D03*
Y954273D03*
X213427Y942561D03*
X204268Y950926D03*
Y947580D03*
Y954273D03*
X209768Y960966D03*
X204268Y967659D03*
Y957619D03*
Y964312D03*
Y971005D03*
Y960966D03*
X209768D03*
X204268Y967659D03*
Y974352D03*
Y981045D03*
Y987737D03*
Y977698D03*
Y984391D03*
Y974352D03*
Y981045D03*
Y994430D03*
Y1001123D03*
Y991084D03*
Y997777D03*
Y987737D03*
Y994430D03*
Y1001123D03*
Y1004470D03*
Y1027895D03*
D03*
Y1034588D03*
Y1041281D03*
Y1047974D03*
Y1031241D03*
Y1037934D03*
Y1044627D03*
Y1034588D03*
Y1041281D03*
Y1054667D03*
Y1061360D03*
Y1051320D03*
Y1058013D03*
Y1047974D03*
Y1054667D03*
Y1071399D03*
Y1064706D03*
Y1068052D03*
Y1074745D03*
Y1061360D03*
Y1071399D03*
Y1064706D03*
Y1078092D03*
Y1088131D03*
Y1084785D03*
X213427Y1089805D03*
X204268Y1078092D03*
Y1088131D03*
Y1084785D03*
Y1094824D03*
Y1101517D03*
Y1098171D03*
Y1104863D03*
Y1094824D03*
Y1101517D03*
Y1108210D03*
Y1114903D03*
Y1121596D03*
Y1111556D03*
Y1108210D03*
Y1114903D03*
Y1131635D03*
Y1124942D03*
X213427Y1126616D03*
X204268Y1134982D03*
Y1131635D03*
Y1124942D03*
Y1121596D03*
Y1138328D03*
Y1145021D03*
Y1151714D03*
Y1141675D03*
Y1148367D03*
Y1138328D03*
Y1145021D03*
Y1161753D03*
Y1158407D03*
X213427Y1163427D03*
X204268Y1151714D03*
Y1161753D03*
Y1158407D03*
Y1168446D03*
Y1175139D03*
Y1181832D03*
Y1171793D03*
Y1178486D03*
Y1168446D03*
Y1175139D03*
Y1188525D03*
Y1195218D03*
Y1185178D03*
Y1181832D03*
Y1188525D03*
Y1205257D03*
Y1198564D03*
Y1211950D03*
X213427Y1200238D03*
X204268Y1208604D03*
Y1205257D03*
Y1198564D03*
Y1195218D03*
Y1218643D03*
Y1225336D03*
Y1215297D03*
Y1221989D03*
Y1211950D03*
Y1218643D03*
Y1235375D03*
Y1232029D03*
X213427Y1237049D03*
X204268Y1225336D03*
Y1235375D03*
Y1232029D03*
Y1242068D03*
Y1248761D03*
Y1245415D03*
Y1252108D03*
Y1242068D03*
Y1248761D03*
X205365Y1307880D03*
Y1310380D03*
Y1312880D03*
X202865D03*
Y1310380D03*
Y1307880D03*
X216165D03*
Y1310380D03*
Y1312880D03*
Y1305380D03*
Y1300380D03*
Y1302880D03*
X205365Y1305380D03*
X202865D03*
X205365Y1300380D03*
Y1302880D03*
X202865D03*
Y1300380D03*
X205365Y1315380D03*
X202865D03*
X216165D03*
Y1317880D03*
X205365D03*
X202865D03*
X215977Y1357409D03*
X210877D03*
X208277D03*
X213477D03*
X205677D03*
X203077D03*
X207351Y1367272D03*
X209781Y1372872D03*
X204921Y1367272D03*
Y1372872D03*
X207351D03*
X210877Y1363473D03*
X208277D03*
Y1360516D03*
X210877D03*
X205677D03*
X203077D03*
X209781Y1367272D03*
X213521Y1372872D03*
X215951D03*
X209830Y1385287D03*
X203063Y1382593D03*
Y1380085D03*
X210505Y1382130D03*
X207017Y1380530D03*
X209755Y1379562D03*
X213648Y1416262D03*
X205558Y1418560D03*
Y1416060D03*
X202945Y1415910D03*
Y1418410D03*
X208058Y1416060D03*
X208061Y1418605D03*
X206251Y1452895D03*
X206941Y1450295D03*
X208851Y1452895D03*
X206941Y1455495D03*
X206251Y1452895D03*
X202851D03*
X216251Y1472295D03*
X213651D03*
X215561Y1469695D03*
Y1474895D03*
X216251Y1472295D03*
X207152Y1544997D03*
X211876D03*
X216601D03*
X207152Y1548397D03*
X211876D03*
X216601D03*
Y1550697D03*
X202427D03*
X211876Y1550897D03*
X207152D03*
X202427Y1544997D03*
X207152D03*
X211876D03*
X216601D03*
X202427Y1548397D03*
X207152D03*
X211876D03*
X216601D03*
X215686Y1592380D03*
X212286D03*
X211508Y1594876D03*
X204404D03*
X216464D03*
X211508Y1589884D03*
X204404D03*
X216464D03*
X212286Y1592380D03*
X203626D03*
X215686D03*
X206256Y1602380D03*
X209656D03*
X218316D03*
Y1614292D03*
X206256D03*
X209656D03*
X210434Y1604876D03*
X205478D03*
X210434Y1599884D03*
X205478D03*
Y1611796D03*
X210434D03*
X206256Y1602380D03*
X209656D03*
X215686Y1624292D03*
X212286D03*
X210434Y1616788D03*
X205478D03*
X211508Y1626788D03*
X216464D03*
X211508Y1621796D03*
X216464D03*
X204404Y1626788D03*
Y1621796D03*
X212286Y1624292D03*
X203626D03*
X215686D03*
X206256Y1614292D03*
X209656D03*
X205479Y1652130D03*
Y1648730D03*
X207968Y1653130D03*
X203800Y1646832D03*
X205479Y1652130D03*
Y1648730D03*
X206788Y1660960D03*
X210833Y1660867D03*
X210217Y1668603D03*
X203807Y1681173D03*
X207807Y1681302D03*
X203807Y1696366D03*
X207807Y1696409D03*
X211103Y1708988D03*
X211000Y1717675D03*
X202596Y1737117D03*
X222063Y19541D03*
X229928Y3001D03*
X217853Y17045D03*
X222833D03*
X222063Y19541D03*
X218663D03*
X217736Y25977D03*
X223881Y28406D03*
X230967D03*
X217853Y22037D03*
X222833D03*
X224841Y19541D03*
X229131Y26477D03*
X225731D03*
X223891Y37106D03*
X230977D03*
X223881Y40020D03*
X230967D03*
X223891Y48720D03*
X230977D03*
X229127Y50649D03*
X225727D03*
X230895Y75340D03*
X227495D03*
X219891Y69343D03*
X222591D03*
X224795Y75340D03*
X226705Y72847D03*
X231685D03*
X220685Y66850D03*
Y71842D03*
X227495Y75340D03*
X230895D03*
X219891Y69343D03*
X231685Y77839D03*
X226705D03*
X222000Y160000D03*
X221051Y153167D03*
X220687Y522453D03*
X226687D03*
X226599Y570970D03*
X217999Y585668D03*
X223999D03*
X220999D03*
X217202Y606943D03*
X220202D03*
X223202D03*
X223111Y603782D03*
X225895Y609691D03*
X228895D03*
X220111Y603782D03*
X217202Y609681D03*
X220202D03*
X223202D03*
X218024Y622385D03*
X221024D03*
X224024D03*
X227024D03*
X221024Y632385D03*
X218024D03*
X224024D03*
X227024D03*
X227493Y676906D03*
X224493D03*
X230493D03*
X221493D03*
X224157Y715915D03*
Y712915D03*
X222377Y760266D03*
Y756766D03*
X229419D03*
X222377Y767266D03*
X229419Y763119D03*
X217827Y776911D03*
X229263Y765863D03*
X229275Y769292D03*
X222377Y763766D03*
X229569Y791970D03*
X228519Y786950D03*
X223277Y790297D03*
X217827Y783604D03*
X228519Y796989D03*
X223277Y800336D03*
X217827Y807029D03*
Y813722D03*
Y820415D03*
X229569Y828781D03*
X223277Y837147D03*
X228519Y823761D03*
Y833800D03*
X223277Y827108D03*
X217827Y843840D03*
Y850533D03*
X229569Y865592D03*
X228519Y860572D03*
X223277Y863919D03*
X217827Y857226D03*
X228519Y870611D03*
X223277Y873958D03*
X217827Y880651D03*
Y887344D03*
Y894037D03*
X229569Y902403D03*
X228519Y897383D03*
X223277Y900730D03*
X228519Y907423D03*
X223277Y910769D03*
X217827Y917462D03*
Y924155D03*
X229569Y939214D03*
X228519Y934194D03*
X223277Y937541D03*
X217827Y930848D03*
X228519Y944234D03*
X223277Y947580D03*
X217827Y954273D03*
Y960966D03*
Y967659D03*
X227540Y960966D03*
X217827Y974352D03*
Y981045D03*
Y987737D03*
Y994430D03*
Y1004470D03*
Y1034588D03*
Y1041281D03*
Y1047974D03*
Y1054667D03*
Y1061360D03*
Y1071399D03*
X229569Y1086458D03*
X223277Y1084785D03*
X228519Y1081438D03*
X217827Y1078092D03*
Y1101517D03*
X228519Y1091478D03*
X223277Y1094824D03*
X228519Y1118249D03*
X217827Y1108210D03*
Y1114903D03*
X229569Y1123269D03*
X223277Y1121596D03*
X228519Y1128289D03*
X223277Y1131635D03*
X217827Y1138328D03*
Y1145021D03*
X229569Y1160080D03*
X228519Y1155060D03*
X223277Y1158407D03*
X228519Y1165100D03*
X217827Y1151714D03*
X223277Y1168446D03*
X217827Y1175139D03*
X228519Y1191871D03*
X217827Y1181832D03*
Y1188525D03*
X229569Y1196891D03*
X228519Y1201911D03*
X223277Y1205257D03*
Y1195218D03*
X217827Y1211950D03*
Y1218643D03*
X229569Y1233702D03*
X228519Y1228682D03*
X223277Y1232029D03*
X228519Y1238722D03*
X217827Y1225336D03*
X223277Y1242068D03*
X217827Y1248761D03*
Y1255454D03*
X218665Y1312880D03*
Y1310380D03*
Y1307880D03*
X221165Y1312880D03*
Y1310380D03*
Y1307880D03*
Y1305380D03*
X218665D03*
X221165Y1300380D03*
Y1302880D03*
X218665D03*
Y1300380D03*
X224481Y1326418D03*
X221881D03*
X224481Y1323918D03*
X221881Y1321418D03*
X224481D03*
X221881Y1323918D03*
X230171Y1323904D03*
Y1321404D03*
X218665Y1315380D03*
X221165D03*
Y1317880D03*
X218665D03*
X227871Y1338124D03*
X223941Y1338068D03*
X221341D03*
X230661Y1338124D03*
X224691Y1354871D03*
Y1352271D03*
X223441Y1357371D03*
X222091Y1354871D03*
Y1352271D03*
X218421Y1357425D03*
X224691Y1349671D03*
X222091D03*
X219367Y1360456D03*
Y1363413D03*
X231347Y1361417D03*
X229101Y1369018D03*
Y1371559D03*
X218381Y1372872D03*
X219401Y1370067D03*
Y1367167D03*
X225411Y1373177D03*
X228892Y1384789D03*
X230550Y1386740D03*
X230594Y1379933D03*
X225411Y1378977D03*
Y1376077D03*
X221145Y1379207D03*
X223311Y1377577D03*
X223211Y1374577D03*
X221145Y1376307D03*
X228693Y1408885D03*
X224881Y1410685D03*
X220803Y1412115D03*
X217097Y1413863D03*
X226351Y1462595D03*
X222951D03*
X229651Y1452895D03*
X233051D03*
X227051D03*
X228951Y1462595D03*
X220351D03*
X228961Y1450295D03*
Y1455495D03*
X227041Y1459995D03*
X222261D03*
X226351Y1462595D03*
X222951D03*
X229651Y1452895D03*
X219651Y1472295D03*
X222251D03*
X220341Y1469695D03*
Y1474895D03*
X227041Y1465195D03*
X222261D03*
X219651Y1472295D03*
X221325Y1544997D03*
X226050D03*
X230774D03*
X221325Y1548397D03*
X226050D03*
X230774D03*
X226050Y1550897D03*
X221325Y1550797D03*
X230774Y1550897D03*
X221325Y1544997D03*
X226050D03*
X230774D03*
X221325Y1548397D03*
X226050D03*
X230774D03*
X224346Y1592380D03*
X227746D03*
X228524Y1594876D03*
X223568D03*
Y1589884D03*
X228524D03*
X224346Y1592380D03*
X227746D03*
X230376Y1602380D03*
X221716D03*
X233776D03*
X230376Y1614292D03*
X233776D03*
X221716D03*
X222494Y1604876D03*
X217538D03*
X222494Y1599884D03*
X217538D03*
X229598Y1604876D03*
Y1599884D03*
Y1611796D03*
X217538D03*
X222494D03*
X218316Y1602380D03*
X230376D03*
X221716D03*
X224346Y1624292D03*
X227746D03*
X229598Y1616788D03*
X217538D03*
X222494D03*
X223568Y1626788D03*
X228524D03*
X223568Y1621796D03*
X228524D03*
X224346Y1624292D03*
X227746D03*
X218316Y1614292D03*
X230376D03*
X221716D03*
X224596Y1737117D03*
X243486Y23005D03*
X233335Y17665D03*
X246506Y20365D03*
X242216Y39365D03*
X246216D03*
X238059Y37165D03*
X235697Y39755D03*
X244296Y59765D03*
X233595Y75340D03*
X234331Y103286D03*
X232529Y114830D03*
X238297Y121555D03*
X244818Y111546D03*
Y115546D03*
X235460Y115790D03*
X235186Y112022D03*
X238600Y130400D03*
X235147Y124435D03*
X241271Y130719D03*
X234000Y148000D03*
X239988Y141986D03*
X242251Y162515D03*
X234628Y166735D03*
X246250Y204360D03*
X233413Y360867D03*
X235913D03*
X234727Y584030D03*
Y571211D03*
X233438Y593556D03*
X236638D03*
X233456Y601598D03*
X236656D03*
X236674Y609640D03*
X233474D03*
X243845Y656940D03*
X246045Y655540D03*
X243845Y651140D03*
Y654040D03*
X245945Y652540D03*
X245815Y672746D03*
X244565Y677846D03*
Y680446D03*
Y675246D03*
X242543Y691115D03*
X239443Y691015D03*
X239843Y709715D03*
X232981Y743983D03*
X238469Y756832D03*
X233969Y773564D03*
X238469Y763525D03*
X246371Y772388D03*
X238519Y770218D03*
X233969Y780257D03*
Y803682D03*
Y810375D03*
Y817068D03*
Y840493D03*
Y847186D03*
Y853879D03*
Y877304D03*
Y883997D03*
Y890690D03*
Y914115D03*
Y920808D03*
Y927501D03*
Y950926D03*
Y957619D03*
Y964312D03*
Y971005D03*
Y960966D03*
Y977698D03*
Y984391D03*
Y991084D03*
Y997777D03*
Y1004470D03*
Y1031241D03*
Y1037934D03*
Y1044627D03*
Y1051320D03*
Y1058013D03*
Y1068052D03*
Y1074745D03*
Y1098171D03*
Y1104863D03*
Y1111556D03*
Y1134982D03*
Y1141675D03*
Y1148367D03*
Y1171793D03*
Y1178486D03*
Y1185178D03*
Y1208604D03*
Y1215297D03*
Y1221989D03*
Y1245415D03*
Y1252108D03*
X232965Y1297880D03*
X237965D03*
X235465D03*
Y1300380D03*
Y1302880D03*
X237965D03*
Y1300380D03*
X235465Y1305380D03*
X237965D03*
X232965Y1302880D03*
Y1300380D03*
Y1305380D03*
Y1307880D03*
Y1310380D03*
Y1312880D03*
X237965Y1307880D03*
Y1310380D03*
Y1312880D03*
X235465D03*
Y1310380D03*
Y1307880D03*
X232961Y1323904D03*
Y1321404D03*
X237965Y1315380D03*
X235465D03*
X232965D03*
X239561Y1338124D03*
X243677Y1357409D03*
X241077D03*
X238477D03*
X235877D03*
X246277D03*
X242581Y1367272D03*
X240151D03*
X243677Y1363473D03*
X241077D03*
Y1360516D03*
X243677D03*
X242581Y1372872D03*
X240151D03*
X237721D03*
Y1367272D03*
X238477Y1360516D03*
X235877D03*
X246321Y1372872D03*
X242630Y1385287D03*
X235863Y1380085D03*
X243305Y1382130D03*
X239817Y1380530D03*
X242555Y1379562D03*
X235863Y1382593D03*
X232874Y1376408D03*
X233194Y1407349D03*
X235651Y1452895D03*
X233741Y1450295D03*
Y1455495D03*
X233051Y1452895D03*
X246451Y1472295D03*
X243051D03*
X240451D03*
X242361Y1469695D03*
Y1474895D03*
X246451Y1472295D03*
X243051D03*
X235499Y1544997D03*
X240223D03*
X244947D03*
X235499Y1548397D03*
X240223D03*
X244947D03*
X235499Y1550897D03*
X240223D03*
X244947Y1550697D03*
X235499Y1544997D03*
X240223D03*
X244947D03*
X235499Y1548397D03*
X240223D03*
X244947D03*
X248466Y1592380D03*
X236406D03*
X239806D03*
X240584Y1594876D03*
X235628D03*
Y1589884D03*
X240584D03*
X236406Y1592380D03*
X239806D03*
X242436Y1602380D03*
X245836D03*
Y1614292D03*
X242436D03*
X246614Y1604876D03*
Y1599884D03*
X234554Y1604876D03*
Y1599884D03*
X241658Y1604876D03*
Y1599884D03*
X246614Y1611796D03*
X241658D03*
X234554D03*
X242436Y1602380D03*
X233776D03*
X245836D03*
X248466Y1624292D03*
X236406D03*
X239806D03*
X246614Y1616788D03*
X241658D03*
X234554D03*
X235628Y1626788D03*
X240584D03*
X235628Y1621796D03*
X240584D03*
X236406Y1624292D03*
X239806D03*
X242436Y1614292D03*
X233776D03*
X245836D03*
X251928Y3001D03*
X255106Y16615D03*
X252996Y28365D03*
X256496D03*
X249496D03*
X259996D03*
X250216Y39365D03*
X254046Y39425D03*
X259316Y48965D03*
X261016Y51565D03*
X252316Y48965D03*
X255816D03*
X254016Y51565D03*
X250516D03*
X247716Y75865D03*
Y71865D03*
X247893Y100546D03*
X248093Y92146D03*
X261416Y100665D03*
X253874Y111774D03*
X261383Y133786D03*
X258253D03*
X256586Y138373D03*
X260596Y151065D03*
X248350Y165700D03*
X257252Y156730D03*
X254095Y209235D03*
X258439Y214000D03*
X247859Y375389D03*
X250359D03*
X254859D03*
X247694Y378523D03*
X250194D03*
X254694D03*
X254671Y642138D03*
X259475Y657245D03*
X259426Y644830D03*
X258751Y647987D03*
X259501Y650555D03*
X255735Y657245D03*
X253305D03*
X250875D03*
X248111Y653810D03*
Y650910D03*
X259475Y662845D03*
X250312Y670080D03*
Y667180D03*
X250835Y672692D03*
X253279Y672708D03*
X258379Y666644D03*
Y669601D03*
Y672708D03*
X255779D03*
X260979Y666644D03*
Y669601D03*
Y672708D03*
X250312Y663080D03*
Y660180D03*
X247165Y677846D03*
Y680446D03*
Y675246D03*
X254448Y692050D03*
X247587Y714760D03*
Y717260D03*
X252591Y714737D03*
Y717237D03*
X250091D03*
Y714737D03*
X247587Y712237D03*
X250087D03*
X252587D03*
X247587Y719760D03*
X252591Y719737D03*
X250091D03*
X247587Y724760D03*
X252587D03*
X250087D03*
X247587Y722260D03*
Y727260D03*
X250087Y729760D03*
X247587D03*
X250087Y727260D03*
X252587D03*
Y729760D03*
X252591Y722237D03*
X250091D03*
X254671Y776388D03*
X258470Y775410D03*
X260971Y777988D03*
X248765Y1297880D03*
X251265D03*
X248765Y1292880D03*
Y1295380D03*
X251265D03*
Y1292880D03*
X248765Y1307880D03*
Y1310380D03*
Y1312880D03*
X251265D03*
Y1310380D03*
Y1307880D03*
X248765Y1305380D03*
X251265D03*
X248765Y1300380D03*
Y1302880D03*
X251265D03*
Y1300380D03*
X248765Y1315380D03*
X251265D03*
Y1317880D03*
X248765D03*
X260671Y1338124D03*
X258071D03*
X247725Y1338141D03*
X257491Y1352271D03*
X256241Y1357371D03*
X257491Y1354871D03*
X254891Y1352271D03*
Y1354871D03*
X251221Y1357425D03*
X248777Y1357409D03*
X257491Y1349671D03*
X254891D03*
X252167Y1363413D03*
Y1360456D03*
X248751Y1372872D03*
X251181D03*
X252211Y1370232D03*
Y1367332D03*
X258211Y1373177D03*
X256111Y1377577D03*
X258211Y1378977D03*
X256011Y1374577D03*
X258211Y1376077D03*
X253945Y1379207D03*
Y1376307D03*
X253151Y1462595D03*
X259851Y1452895D03*
X249751Y1462595D03*
X256451Y1452895D03*
X253851D03*
X255751Y1462595D03*
X247151D03*
X260541Y1450295D03*
X255761D03*
X260541Y1455495D03*
X255761D03*
X253841Y1459995D03*
X249061D03*
X253151Y1462595D03*
X259851Y1452895D03*
X249751Y1462595D03*
X256451Y1452895D03*
X249051Y1472295D03*
X253841Y1465195D03*
X249061D03*
X247141Y1469695D03*
Y1474895D03*
X249671Y1544997D03*
X254396D03*
X259120D03*
X249671Y1548397D03*
X254396D03*
X259120D03*
Y1550797D03*
X254396Y1550897D03*
X249671D03*
Y1544997D03*
X254396D03*
X259120D03*
X249671Y1548397D03*
X254396D03*
X259120D03*
X261530Y1550300D03*
X260526Y1592380D03*
X251866D03*
X259748Y1594876D03*
X247688D03*
X252644D03*
X247688Y1589884D03*
X259748D03*
X252644D03*
X248466Y1592380D03*
X260526D03*
X251866D03*
X254496Y1602380D03*
X257896D03*
X254496Y1614292D03*
X257896D03*
X253718Y1604876D03*
X258674D03*
X253718Y1599884D03*
X258674D03*
Y1611796D03*
X253718D03*
X254496Y1602380D03*
X257896D03*
X260526Y1624292D03*
X251866D03*
X258674Y1616788D03*
X253718D03*
X252644Y1626788D03*
X259748D03*
X252644Y1621796D03*
X259748D03*
X247688Y1626788D03*
Y1621796D03*
X248466Y1624292D03*
X260526D03*
X251866D03*
X254496Y1614292D03*
X257896D03*
X273928Y3001D03*
X272596Y27185D03*
X263276Y34625D03*
X271596Y40165D03*
X263516Y51565D03*
X261816Y48965D03*
X263182Y73396D03*
X269860Y72741D03*
X262893Y77529D03*
Y80029D03*
X263316Y87665D03*
X275238Y83024D03*
X264916Y100665D03*
X268416D03*
X262916Y97965D03*
X266416D03*
X269916D03*
X270364Y118415D03*
X272361Y120243D03*
X272525Y108556D03*
X268981D03*
Y111056D03*
X265438Y108556D03*
X261895D03*
Y111056D03*
X265438D03*
X272525D03*
X275793Y129595D03*
X266971Y140110D03*
X264574Y151206D03*
X270178Y140322D03*
X264574Y155206D03*
X262500Y161100D03*
X273500Y207500D03*
X266360Y203070D03*
X267500Y220441D03*
X272242Y523076D03*
X269568Y522366D03*
X266327Y522456D03*
X274201Y579478D03*
X274096Y574698D03*
X266601Y586578D03*
X270905Y608485D03*
X273905D03*
Y611485D03*
X264335Y657245D03*
X261905D03*
X271462Y650184D03*
X266193Y650032D03*
X272955Y658558D03*
X266193Y647524D03*
X269182Y653709D03*
X261905Y662845D03*
X264335D03*
X263579Y669601D03*
X266179D03*
Y672708D03*
X263579D03*
X272955Y661099D03*
X276575Y685381D03*
Y688281D03*
X263839Y692049D03*
X272603Y692910D03*
Y695510D03*
X276575Y691181D03*
X265891Y714737D03*
Y717237D03*
X263391D03*
Y714737D03*
X263387Y712237D03*
X265887D03*
X265891Y719737D03*
X263391D03*
X265787Y724760D03*
X263287D03*
X265787Y727260D03*
X263287D03*
X265787Y729760D03*
X263287D03*
X265787Y732260D03*
X263287D03*
X265891Y722237D03*
X263391D03*
X265787Y737260D03*
X263287D03*
X265787Y734760D03*
X263287D03*
X268991Y783248D03*
X271245Y785474D03*
X272054Y801112D03*
X270850Y797605D03*
X272165Y1256716D03*
X269665Y1259216D03*
X272165D03*
X269765Y1269234D03*
X272265D03*
X269765Y1261734D03*
Y1264234D03*
Y1266734D03*
X272265D03*
Y1264234D03*
Y1261734D03*
X267179Y1269273D03*
Y1266773D03*
Y1264273D03*
Y1261773D03*
Y1271773D03*
X269679D03*
X272179D03*
X271491Y1291740D03*
X274091D03*
X272077Y1314370D03*
X269477D03*
X274677D03*
X272077Y1311263D03*
X269477D03*
X274677D03*
X271321Y1326726D03*
Y1321126D03*
X276181Y1326726D03*
X273751D03*
X274677Y1317327D03*
X264947Y1315271D03*
X276181Y1321126D03*
X273751D03*
X262701Y1322872D03*
Y1325413D03*
X276230Y1339141D03*
X264194Y1333787D03*
X269463Y1333939D03*
X273417Y1334384D03*
X276155Y1333416D03*
X269463Y1336447D03*
X266474Y1330262D03*
X269851Y1452895D03*
X273251D03*
X275851D03*
X267251D03*
X262451D03*
X273941Y1450295D03*
X269161D03*
X273941Y1455495D03*
X269161D03*
X269851Y1452895D03*
X273251D03*
X276085Y1509654D03*
X269829Y1521436D03*
X273597Y1519845D03*
X269144Y1511953D03*
X273474Y1516120D03*
Y1512220D03*
X269144Y1514453D03*
Y1516953D03*
X267322Y1519250D03*
X276624Y1516120D03*
Y1512220D03*
X276637Y1521436D03*
Y1523953D03*
X270720Y1531073D03*
X273220D03*
X275720D03*
X270139Y1548563D03*
X274546Y1549295D03*
Y1546795D03*
X267297Y1546119D03*
X275986Y1592380D03*
X272586D03*
X263926D03*
X271808Y1594876D03*
X264704D03*
X271808Y1589884D03*
X264704D03*
X272586Y1592380D03*
X263926D03*
X275986D03*
X266556Y1602380D03*
X269956D03*
X278616D03*
Y1614292D03*
X266556D03*
X269956D03*
X265778Y1604876D03*
X270734D03*
X265778Y1599790D03*
X270734D03*
Y1611796D03*
X265778D03*
X266556Y1602380D03*
X269956D03*
X275986Y1624292D03*
X272586D03*
X263926D03*
X270734Y1616788D03*
X265778D03*
X271808Y1626788D03*
Y1621796D03*
X264704Y1626788D03*
Y1621796D03*
X272586Y1624292D03*
X263926D03*
X275986D03*
X266556Y1614292D03*
X269956D03*
X266596Y1737117D03*
X291000Y14820D03*
X285896Y23965D03*
X278979Y28406D03*
X286066D03*
X291156Y21395D03*
X284228Y25935D03*
X280828D03*
X286716Y40020D03*
X282716D03*
X290716D03*
X285499Y53191D03*
X278989Y48720D03*
X286076D03*
X291379Y55746D03*
X284226Y50649D03*
X280826D03*
X278638Y83024D03*
X279273Y99186D03*
X288553Y105006D03*
X285353D03*
X289553Y121806D03*
X280853Y109906D03*
X282853Y115606D03*
X285853D03*
X280853Y107306D03*
X283049Y139731D03*
X283949Y152506D03*
X288516Y157065D03*
X288000Y209000D03*
X290000Y222575D03*
X289163Y212503D03*
X285260Y234000D03*
X279500Y234075D03*
X278425Y230925D03*
X289393Y498960D03*
X278547Y523041D03*
X281147Y521803D03*
X284018Y522300D03*
X287723Y548499D03*
X289421Y575098D03*
X277105Y608485D03*
X280305D03*
X277105Y611485D03*
X280305D03*
X286665Y609470D03*
X283705Y608485D03*
X284705Y605485D03*
X283705Y611485D03*
X287832Y674150D03*
X291481Y682228D03*
X280841Y688051D03*
X278675Y686781D03*
X280841Y685151D03*
X291109Y700885D03*
X283062Y700979D03*
X288465Y691493D03*
X283605D03*
X286035D03*
X278775Y689781D03*
X283042Y697280D03*
Y694380D03*
X279895Y709487D03*
X283565Y706933D03*
X286009Y706949D03*
X278545Y706987D03*
X279895Y712087D03*
Y714687D03*
X291109Y703842D03*
Y706949D03*
X288509D03*
X277295Y709487D03*
Y712087D03*
Y714687D03*
X283062Y703936D03*
X277055Y722649D03*
X279171Y724988D03*
X285317Y746478D03*
X282817D03*
X280317D03*
Y759110D03*
X285317D03*
X282817D03*
X285317Y761610D03*
X285321Y748978D03*
Y751478D03*
Y753978D03*
X282821D03*
Y751478D03*
Y748978D03*
X285321Y756478D03*
X282821D03*
X280317Y756610D03*
Y751610D03*
Y754110D03*
Y749110D03*
Y761610D03*
X282817D03*
X284035Y796850D03*
X285258Y799314D03*
X282323Y794867D03*
X281449Y809609D03*
X283987Y811342D03*
X285565Y1246716D03*
X288065D03*
X283065D03*
X288065Y1251716D03*
X285565D03*
X283065D03*
X288065Y1249216D03*
X285565D03*
X283065D03*
Y1254216D03*
X288065D03*
X285565D03*
X283065Y1269234D03*
X285565D03*
X283065Y1261734D03*
Y1264234D03*
Y1266734D03*
X285565D03*
Y1264234D03*
Y1261734D03*
X283065Y1256716D03*
X285565D03*
X288065D03*
X283065Y1259216D03*
X285565D03*
X288065D03*
Y1266716D03*
Y1264216D03*
Y1261716D03*
Y1269216D03*
X285479Y1271773D03*
X282979D03*
X287979D03*
X283921Y1291740D03*
X281321D03*
X284821Y1311279D03*
X282377Y1311263D03*
X279877D03*
X277277Y1314370D03*
Y1311263D03*
X288491Y1306125D03*
Y1308725D03*
X291091Y1306125D03*
Y1308725D03*
X288491Y1303525D03*
X291091D03*
X289841Y1311225D03*
X285767Y1314310D03*
Y1317267D03*
X277277Y1317327D03*
X284781Y1326726D03*
X282351D03*
X279921D03*
X285891Y1320942D03*
Y1323842D03*
X289611Y1328431D03*
X281992Y1342705D03*
X276905Y1335984D03*
X289711Y1331431D03*
X287545Y1330161D03*
Y1333061D03*
X291175Y1480190D03*
X280621Y1478082D03*
X291175Y1477590D03*
X280621Y1484082D03*
Y1480682D03*
X291175Y1483590D03*
X280621Y1494082D03*
Y1486682D03*
X283221Y1484772D03*
Y1479992D03*
X278021Y1484772D03*
Y1479992D03*
X291175Y1486190D03*
X288575Y1484280D03*
Y1479500D03*
X283221Y1493392D03*
X280621Y1491482D03*
X278021Y1493392D03*
X280621Y1484082D03*
Y1480682D03*
X291175Y1483590D03*
Y1480190D03*
Y1501990D03*
Y1505390D03*
X280621Y1497482D03*
Y1500082D03*
X291175Y1499490D03*
X288575Y1506080D03*
Y1501300D03*
X291175Y1507990D03*
X283221Y1498172D03*
X278021D03*
X280621Y1497482D03*
Y1494082D03*
X291175Y1501990D03*
Y1505390D03*
X280088Y1509469D03*
X282588D03*
X279774Y1512220D03*
Y1516120D03*
X284024Y1514576D03*
X279499Y1519845D03*
X284024Y1512076D03*
X283946Y1530595D03*
X286446D03*
X291619Y1536606D03*
X291593Y1529402D03*
Y1531902D03*
X284800Y1526750D03*
X277572Y1536763D03*
X280072D03*
X290593Y1523331D03*
Y1526731D03*
X291619Y1539106D03*
X291416Y1541795D03*
Y1549295D03*
Y1546795D03*
Y1544295D03*
X285586Y1551844D03*
X288004Y1551099D03*
X290509Y1551844D03*
X288004Y1548199D03*
X284014Y1538682D03*
X286514D03*
X284546Y1549295D03*
Y1546795D03*
Y1541795D03*
Y1544295D03*
X287046D03*
Y1541795D03*
X277046Y1546795D03*
Y1549295D03*
X282046D03*
Y1546795D03*
Y1544295D03*
X279546Y1549295D03*
Y1546795D03*
X282046Y1541795D03*
X284646Y1592380D03*
X288046D03*
X288824Y1594876D03*
X276764D03*
X283868D03*
Y1589884D03*
X276764D03*
X288824D03*
X284646Y1592380D03*
X288046D03*
X290676Y1602380D03*
X282016D03*
X290676Y1614292D03*
X282016D03*
X277838Y1604876D03*
X282794D03*
X277838Y1599884D03*
X282794D03*
X289898Y1604876D03*
Y1599884D03*
Y1611796D03*
X282794D03*
X277838D03*
X278616Y1602380D03*
X290676D03*
X282016D03*
X284646Y1624292D03*
X288046D03*
X289898Y1616788D03*
X282794D03*
X277838D03*
X283868Y1626788D03*
X288824D03*
X283868Y1621796D03*
X288824D03*
X276764Y1626788D03*
Y1621796D03*
X284646Y1624292D03*
X288046D03*
X278616Y1614292D03*
X290676D03*
X282016D03*
X295928Y3001D03*
X300230Y14820D03*
X302606Y26365D03*
X292056Y24475D03*
X304923Y24657D03*
X304968Y28365D03*
X298716Y40020D03*
X301306Y52485D03*
X296272Y69128D03*
X295755Y72800D03*
X303852Y65042D03*
X306470Y65160D03*
X293443Y78576D03*
X293448Y82486D03*
Y85986D03*
X303043Y79376D03*
X299943Y79276D03*
X299653Y92506D03*
X301747Y121469D03*
X301179Y112806D03*
Y110006D03*
Y107106D03*
X301747Y127469D03*
Y124469D03*
X296478Y149203D03*
X294553Y153819D03*
X296474Y158706D03*
X293000Y216500D03*
X292811Y213242D03*
X296283Y242391D03*
X292705Y580275D03*
X297815Y580384D03*
X294165Y609570D03*
X297838Y609585D03*
X300965Y609570D03*
X292156Y679071D03*
X304192Y684425D03*
X298923Y684273D03*
X294969Y683828D03*
X292231Y684796D03*
X298923Y681765D03*
X301912Y687950D03*
X292205Y691486D03*
X297065D03*
X294635D03*
X293709Y700885D03*
X297065Y697086D03*
X303657Y702815D03*
X292205Y697086D03*
X294635D03*
X305685Y695340D03*
Y692799D03*
X293709Y703842D03*
Y706949D03*
X298909Y703842D03*
Y706949D03*
X296309Y703842D03*
Y706949D03*
X305121Y726348D03*
X298991D03*
X298617Y746478D03*
X296117D03*
X301117D03*
X298621Y753978D03*
X296121D03*
Y751478D03*
Y748978D03*
X298621Y756478D03*
X296121D03*
X301121Y748996D03*
Y751496D03*
Y753996D03*
Y756496D03*
X296117Y759110D03*
Y761610D03*
X301117Y759110D03*
X298617D03*
X301117Y761610D03*
X298617D03*
X298621Y748978D03*
Y751478D03*
X301117Y766610D03*
X296117D03*
Y764110D03*
X301117Y771610D03*
X298617D03*
Y769110D03*
X301117D03*
X296117Y771610D03*
Y769110D03*
X298617Y766610D03*
Y764110D03*
X301117D03*
X305061Y1254131D03*
X300061D03*
X302561D03*
X305061Y1249131D03*
Y1251631D03*
X300061D03*
X302561D03*
X300061Y1249131D03*
X302561D03*
X305061Y1246631D03*
X300061D03*
X302561D03*
X302661Y1269149D03*
X305161D03*
X302661Y1261649D03*
Y1264149D03*
Y1266649D03*
X305161D03*
Y1264149D03*
Y1261649D03*
X300061Y1269131D03*
Y1266631D03*
X305061Y1259131D03*
Y1256631D03*
X300061D03*
Y1259131D03*
Y1261631D03*
Y1264131D03*
X302561Y1256631D03*
Y1259131D03*
X305075Y1271688D03*
X302575D03*
X300075D03*
X294541Y1291378D03*
X291941D03*
X302373Y1314342D03*
X304973D03*
X302373Y1311235D03*
X304973D03*
X304217Y1326698D03*
Y1321098D03*
X297843Y1315243D03*
X295597Y1322844D03*
Y1325385D03*
X291811Y1327031D03*
X295388Y1338615D03*
X297046Y1340566D03*
X297090Y1333759D03*
X302359Y1333911D03*
X306313Y1334356D03*
X302359Y1336419D03*
X299370Y1330234D03*
X291811Y1332831D03*
Y1329931D03*
X294725Y1381612D03*
X294533Y1384401D03*
X305204Y1381461D03*
X305012Y1384250D03*
X294684Y1387040D03*
X305163Y1386889D03*
X305199Y1398269D03*
Y1400769D03*
X295116Y1398132D03*
Y1400632D03*
X292516D03*
Y1398132D03*
X294683Y1390281D03*
X305163Y1389678D03*
X300813Y1462595D03*
X297413D03*
X304113Y1452895D03*
X307513D03*
X303413Y1462595D03*
X301513Y1452895D03*
X294813Y1462595D03*
X303423Y1450295D03*
Y1455495D03*
X301503Y1459995D03*
X296723D03*
X300813Y1462595D03*
X297413D03*
X304113Y1452895D03*
X301503Y1465195D03*
X296723D03*
X293775Y1484280D03*
Y1479500D03*
Y1506080D03*
Y1501300D03*
X299950Y1499500D03*
X301550Y1518040D03*
Y1514420D03*
Y1510800D03*
X292792Y1521561D03*
X302042Y1528731D03*
X295042Y1530596D03*
X304606Y1546333D03*
X296416Y1549295D03*
X293916D03*
Y1546795D03*
X296416D03*
Y1544295D03*
X293916D03*
X296416Y1541795D03*
X293916D03*
X298916D03*
Y1549295D03*
Y1546795D03*
Y1544295D03*
X303041Y1544299D03*
X296706Y1592380D03*
X300106D03*
X300884Y1594876D03*
X295928D03*
Y1589884D03*
X300884D03*
X296706Y1592380D03*
X300106D03*
X302736Y1602380D03*
X294076D03*
X306136D03*
Y1614292D03*
X302736D03*
X294076D03*
X294854Y1604876D03*
Y1599884D03*
X301958Y1604876D03*
Y1599884D03*
Y1611796D03*
X294854D03*
X302736Y1602380D03*
X294076D03*
X306136D03*
X296706Y1624292D03*
X300106D03*
X301958Y1616788D03*
X294854D03*
X295928Y1626788D03*
X300884D03*
X295928Y1621796D03*
X300884D03*
X296706Y1624292D03*
X300106D03*
X302736Y1614292D03*
X294076D03*
X306136D03*
X307255Y1643750D03*
Y1647150D03*
X297323Y1657172D03*
Y1653772D03*
Y1651172D03*
Y1657172D03*
Y1653772D03*
Y1659772D03*
X317928Y3001D03*
X318660Y24989D03*
X306716Y39985D03*
X310396Y50365D03*
X306566Y50225D03*
X314653Y71806D03*
Y68906D03*
X320053Y85806D03*
Y88806D03*
X312410Y89060D03*
X311754Y121472D03*
X311053Y112806D03*
Y110006D03*
Y107106D03*
X311754Y124472D03*
Y127472D03*
X308240Y148100D03*
X317472Y222262D03*
Y225217D03*
X319970Y228167D03*
X320095Y231810D03*
X310425Y243925D03*
X317240Y252970D03*
X308925Y260075D03*
X319075D03*
X311749Y440921D03*
X307865Y609570D03*
X313961Y607088D03*
Y604588D03*
X319657Y696415D03*
X310445Y700931D03*
X312611Y702301D03*
X321235Y711636D03*
X316375D03*
X318805D03*
X311545Y709931D03*
X310445Y703931D03*
X311445Y706931D03*
X313611Y708201D03*
Y705301D03*
X315912Y717400D03*
Y714500D03*
Y721039D03*
Y723996D03*
X321279Y727099D03*
X312665Y729637D03*
Y732237D03*
X310065Y729637D03*
Y732237D03*
X316335Y727083D03*
X311315Y727137D03*
X318779Y727099D03*
X313255Y746279D03*
X312665Y734837D03*
X310065D03*
X313087Y769160D03*
Y771660D03*
Y774160D03*
Y776660D03*
X318091Y769128D03*
Y771628D03*
Y774128D03*
X315591D03*
Y771628D03*
Y769128D03*
X318091Y776628D03*
X315591D03*
X313087Y766628D03*
X315587D03*
X318087D03*
Y791660D03*
X313087D03*
X315587D03*
X318087Y789160D03*
X313087D03*
X315587D03*
Y779160D03*
X313087Y784160D03*
X315587D03*
X313087Y786660D03*
X315587D03*
X313087Y781660D03*
X315587D03*
X313087Y779160D03*
X318087Y786660D03*
Y784160D03*
Y779160D03*
Y781660D03*
X313284Y1218522D03*
D03*
Y1215122D03*
D03*
Y1218522D03*
Y1215122D03*
X318461Y1254131D03*
X320961D03*
X315961D03*
Y1249131D03*
X318461D03*
X320961D03*
X315961Y1251631D03*
X318461D03*
X320961D03*
X315961Y1246631D03*
X318461D03*
X320961D03*
X315961Y1269149D03*
X318461D03*
X315961Y1261649D03*
Y1264149D03*
Y1266649D03*
X318461D03*
Y1264149D03*
Y1261649D03*
X320961Y1269131D03*
Y1256631D03*
Y1259131D03*
Y1261631D03*
X318461Y1256631D03*
Y1259131D03*
X320961Y1264131D03*
Y1266631D03*
X315961Y1256631D03*
Y1259131D03*
X320875Y1271688D03*
X315875D03*
X318375D03*
X319621Y1291740D03*
X321387Y1306097D03*
Y1308697D03*
Y1303497D03*
X317717Y1311251D03*
X315273Y1311235D03*
X312773D03*
X307573Y1314342D03*
Y1311235D03*
X310173Y1314342D03*
Y1311235D03*
X318663Y1314282D03*
X309077Y1321098D03*
X306647D03*
X318663Y1317239D03*
X309077Y1326698D03*
X306647D03*
X307573Y1317299D03*
X310173D03*
X312817Y1326698D03*
X315247D03*
X317677D03*
X318811Y1320902D03*
Y1323802D03*
X309126Y1339113D03*
X309801Y1335956D03*
X309051Y1333388D03*
X320441Y1330133D03*
Y1333033D03*
X307799Y1400769D03*
Y1398269D03*
X318199Y1400549D03*
X314199D03*
X310399D03*
X310113Y1452895D03*
X308203Y1450295D03*
Y1455495D03*
X307513Y1452895D03*
X320913Y1472295D03*
X317513D03*
X314913D03*
X316823Y1469695D03*
Y1474895D03*
X320913Y1472295D03*
X317513D03*
X316316Y1544997D03*
X321040D03*
X316316Y1548397D03*
X321040D03*
Y1550797D03*
X316316D03*
X311476Y1552567D03*
X316316Y1544997D03*
X321040D03*
X316316Y1548397D03*
X321040D03*
X320826Y1592380D03*
X308766D03*
X312166D03*
X320048Y1594876D03*
X307988D03*
X312944D03*
X307988Y1589884D03*
X320048D03*
X312944D03*
X308766Y1592380D03*
X320826D03*
X312166D03*
X314796Y1602380D03*
X318196D03*
X314796Y1614292D03*
X318196D03*
X306914Y1604876D03*
Y1599884D03*
X314018Y1604876D03*
X318974D03*
X314018Y1599884D03*
X318974D03*
Y1611796D03*
X314018D03*
X306914D03*
X314796Y1602380D03*
X318196D03*
X320826Y1624292D03*
X308766D03*
X312166D03*
X318974Y1616788D03*
X314018D03*
X306914D03*
X320048Y1626788D03*
X312944D03*
X320048Y1621796D03*
X312944D03*
X307988Y1626788D03*
Y1621796D03*
X308766Y1624292D03*
X320826D03*
X312166D03*
X314796Y1614292D03*
X318196D03*
X307255Y1641150D03*
Y1649750D03*
Y1643750D03*
Y1647150D03*
X312596Y1737117D03*
X329535Y49379D03*
X323113Y76941D03*
X334339Y162580D03*
X323646Y160120D03*
Y156120D03*
X331000Y270260D03*
X336000Y284000D03*
X328966Y543012D03*
Y548030D03*
X325816Y543012D03*
X324647Y566086D03*
X333500Y582500D03*
Y578500D03*
X333988Y590633D03*
X334031Y613498D03*
Y610498D03*
X331391D03*
Y613498D03*
X333502Y600019D03*
Y603019D03*
X330109Y602883D03*
Y605883D03*
X334031Y619398D03*
Y616498D03*
X331391D03*
Y619398D03*
X324926Y699221D03*
X324251Y702378D03*
X331693Y701915D03*
X329835Y711636D03*
X324975D03*
X329835Y717236D03*
X327405Y711636D03*
X324975Y717236D03*
X327405D03*
X331693Y704423D03*
X327739Y703978D03*
X325001Y704946D03*
X334682Y708100D03*
X326479Y721035D03*
X323879D03*
Y727099D03*
X326479D03*
X329079D03*
X331679D03*
X323879Y723992D03*
X326479D03*
X329079D03*
X331679D03*
X331391Y769128D03*
Y771628D03*
Y774128D03*
X328891D03*
Y771628D03*
Y769128D03*
X331391Y776628D03*
X328891D03*
X333887Y766628D03*
X328887D03*
X331387D03*
X333891Y776646D03*
Y774146D03*
Y771646D03*
Y769146D03*
X333887Y791660D03*
X328887D03*
X331387D03*
X333887Y789160D03*
X328887D03*
X331387D03*
X333887Y779160D03*
Y781660D03*
X331387Y779160D03*
X328887D03*
Y781660D03*
X331387D03*
X333887Y786660D03*
X328887D03*
X331387D03*
X333887Y784160D03*
X328887D03*
X331387D03*
X335465Y1246631D03*
X332965D03*
X335465Y1249131D03*
X332965D03*
X335465Y1251631D03*
X332965D03*
X335465Y1254131D03*
X332965D03*
X335465Y1259131D03*
Y1256631D03*
X332965Y1259131D03*
Y1256631D03*
X335565Y1269149D03*
Y1261649D03*
Y1264149D03*
Y1266649D03*
X332961Y1269188D03*
Y1266688D03*
Y1261688D03*
Y1264188D03*
Y1271688D03*
X335461D03*
X329471Y1291778D03*
X322221Y1291740D03*
X326761Y1291778D03*
X335277Y1314285D03*
Y1311178D03*
X323987Y1303497D03*
Y1306097D03*
Y1308697D03*
X322737Y1311197D03*
X330747Y1315186D03*
X328501Y1322787D03*
Y1325328D03*
X324707Y1327003D03*
X322507Y1328403D03*
X328292Y1338558D03*
X329950Y1340509D03*
X329994Y1333702D03*
X335263Y1333854D03*
Y1336362D03*
X332274Y1330177D03*
X324707Y1332803D03*
X322607Y1331403D03*
X324707Y1329903D03*
X334038Y1373469D03*
X334230Y1370680D03*
X323559Y1373620D03*
X323751Y1370831D03*
X334189Y1376108D03*
X323710Y1376259D03*
X334189Y1378897D03*
X323709Y1379500D03*
X333830Y1396299D03*
Y1398899D03*
Y1401499D03*
Y1393799D03*
X324309Y1396599D03*
Y1399199D03*
Y1401799D03*
Y1394099D03*
X321999Y1400549D03*
X327613Y1462595D03*
X334313Y1452895D03*
X324213Y1462595D03*
X330913Y1452895D03*
X330213Y1462595D03*
X321613D03*
X323523Y1459995D03*
X328303D03*
X328313Y1452895D03*
X335003Y1450295D03*
X330223D03*
X335003Y1455495D03*
X330223D03*
X327613Y1462595D03*
X334313Y1452895D03*
X324213Y1462595D03*
X330913Y1452895D03*
X323513Y1472295D03*
X328313D03*
X323523Y1465195D03*
X328303D03*
X321603Y1469695D03*
Y1474895D03*
X325765Y1544997D03*
X330489D03*
X335214D03*
X325765Y1548397D03*
X330489D03*
X335214D03*
X325765Y1550897D03*
X330489Y1550697D03*
X335214Y1550897D03*
X325765Y1544997D03*
X330489D03*
X335214D03*
X325765Y1548397D03*
X330489D03*
X335214D03*
X336286Y1592380D03*
X332886D03*
X324226D03*
X332108Y1594876D03*
X325004D03*
X332108Y1589884D03*
X325004D03*
X332886Y1592380D03*
X324226D03*
X326856Y1602380D03*
X330256D03*
X326856Y1614292D03*
X330256D03*
X326078Y1604876D03*
X331034D03*
X326078Y1599884D03*
X331034D03*
Y1611796D03*
X326078D03*
X326856Y1602380D03*
X330256D03*
X336286Y1624292D03*
X332886D03*
X324226D03*
X331034Y1616788D03*
X326078D03*
X332108Y1626788D03*
X325004D03*
X332108Y1621796D03*
X325004D03*
X332886Y1624292D03*
X324226D03*
X326856Y1614292D03*
X330256D03*
X334596Y1737117D03*
X341082Y56308D03*
X340436Y120555D03*
X338244Y192264D03*
X344106Y222659D03*
X348107Y220420D03*
X348645Y229180D03*
X349676Y276708D03*
X344034Y282609D03*
X349695Y286712D03*
X342075Y287925D03*
X348890Y409120D03*
Y411620D03*
X340337Y496462D03*
X346751Y515376D03*
X350566Y541882D03*
X350817Y558248D03*
X351157Y562415D03*
X351018Y554896D03*
X351157Y566936D03*
X345521Y564388D03*
X349397Y564459D03*
X345500Y574415D03*
X351157D03*
Y570415D03*
X341500Y574500D03*
X342500Y582500D03*
Y578500D03*
X338420Y574500D03*
X343182Y586415D03*
Y591335D03*
X351157Y586415D03*
X337031Y607498D03*
Y613498D03*
Y610498D03*
X346031Y607498D03*
X343031D03*
X349031D03*
X346031Y610498D03*
X343031D03*
X349031D03*
X340031Y607498D03*
Y610498D03*
Y613498D03*
X346031Y604498D03*
X343031D03*
X349031D03*
X340031D03*
X343691Y614018D03*
X346191D03*
X348691D03*
X343721Y618348D03*
X346221D03*
X348721D03*
X351191Y614018D03*
X351221Y618348D03*
X340031Y619398D03*
Y616498D03*
X337031Y619398D03*
Y616498D03*
X342675Y640994D03*
X345175D03*
X347675D03*
X350175D03*
X342675Y643494D03*
X345175D03*
X347675D03*
X350175D03*
X342595Y646054D03*
X345095D03*
X347595D03*
X350095D03*
X338664Y699660D03*
X337030Y697750D03*
X336962Y704575D03*
X338455Y715490D03*
Y712949D03*
X349435Y711368D03*
X346671Y705033D03*
X344505Y706663D03*
X346671Y707933D03*
X344605Y709663D03*
X342405Y705263D03*
Y708163D03*
Y711063D03*
X348395Y717060D03*
Y714160D03*
X348449Y720827D03*
Y723784D03*
X345725Y729369D03*
X343125D03*
X345725Y731969D03*
X343125D03*
X344375Y726869D03*
X349395Y726815D03*
X336457Y722815D03*
X339825Y746269D03*
X342425D03*
X349625D03*
X345725Y734569D03*
X343125D03*
X346051Y769058D03*
Y771558D03*
Y774058D03*
Y776558D03*
X351151Y769040D03*
Y771540D03*
Y774040D03*
X348651D03*
Y771540D03*
Y769040D03*
X351151Y776540D03*
X348651D03*
X351147Y766540D03*
X348647D03*
X346147D03*
X346051Y791558D03*
X348551D03*
X351051D03*
X346051Y789058D03*
X348551D03*
X346051Y784058D03*
X348551D03*
X346051Y786558D03*
X348551D03*
X346051Y779058D03*
X348551D03*
X346051Y781558D03*
X348551D03*
X351051Y789058D03*
Y784058D03*
Y786558D03*
Y779058D03*
Y781558D03*
X347107Y1174343D03*
X339278Y1192112D03*
X336778D03*
X347885Y1206426D03*
X339532Y1218605D03*
X349938Y1214563D03*
X337965Y1251631D03*
Y1249131D03*
Y1254131D03*
X348865Y1246631D03*
Y1251631D03*
Y1249131D03*
Y1254131D03*
X337965Y1246631D03*
X348865Y1269149D03*
Y1261649D03*
Y1264149D03*
Y1266649D03*
X338065Y1269149D03*
Y1266649D03*
Y1264149D03*
Y1261649D03*
X337965Y1256631D03*
Y1259131D03*
X348865D03*
Y1256631D03*
X337961Y1271688D03*
X348861D03*
X340477Y1314285D03*
X337877D03*
Y1311178D03*
X340477D03*
X350621Y1311194D03*
X348177Y1311178D03*
X343077Y1314285D03*
X345677Y1311178D03*
X343077D03*
X341981Y1321041D03*
X339551D03*
X341981Y1326641D03*
X337121Y1321041D03*
X339551Y1326641D03*
X337121D03*
X340477Y1317242D03*
X343077D03*
X348151Y1326641D03*
X350581D03*
X345721D03*
X342030Y1339056D03*
X342705Y1335899D03*
X339217Y1334299D03*
X341955Y1333331D03*
X346464Y1380102D03*
X343964D03*
X348964D03*
Y1387602D03*
Y1385102D03*
Y1382602D03*
X343964Y1385102D03*
Y1387602D03*
X346464Y1385102D03*
Y1387602D03*
X343964Y1382602D03*
X346464D03*
X347110Y1398312D03*
X351110D03*
X341760Y1401449D03*
X337760D03*
X349760D03*
X345760D03*
X348964Y1390102D03*
X343964D03*
Y1392602D03*
X346464D03*
Y1390102D03*
X343777Y1395166D03*
X346302Y1395242D03*
X348828Y1395392D03*
X349032Y1392675D03*
X351013Y1462595D03*
X348413D03*
X350323Y1459995D03*
X336913Y1452895D03*
X351013Y1462595D03*
X347713Y1472295D03*
X344313D03*
X350313D03*
X341713D03*
X350323Y1465195D03*
X348403Y1469695D03*
X343623D03*
X348403Y1474895D03*
X343623D03*
X347713Y1472295D03*
X344313D03*
X339938Y1544997D03*
X344663D03*
X349387D03*
X339938Y1548397D03*
X344663D03*
X349387D03*
X339938Y1550897D03*
X349387Y1550797D03*
X344663Y1550697D03*
X339938Y1544997D03*
X344663D03*
X349387D03*
X339938Y1548397D03*
X344663D03*
X349387D03*
X344946Y1592380D03*
X348346D03*
X349124Y1594876D03*
X337064D03*
X344168D03*
Y1589884D03*
X337064D03*
X349124D03*
X344946Y1592380D03*
X336286D03*
X348346D03*
X338916Y1602380D03*
X350976D03*
X342316D03*
X350976Y1614292D03*
X338916D03*
X342316D03*
X338138Y1604876D03*
X343094D03*
X338138Y1599884D03*
X343094D03*
X350198Y1604876D03*
Y1599884D03*
Y1611796D03*
X343094D03*
X338138D03*
X338916Y1602380D03*
X350976D03*
X342316D03*
X344946Y1624292D03*
X348346D03*
X350198Y1616788D03*
X343094D03*
X338138D03*
X344168Y1626788D03*
X349124D03*
X344168Y1621796D03*
X349124D03*
X337064Y1626788D03*
Y1621796D03*
X344946Y1624292D03*
X336286D03*
X348346D03*
X338916Y1614292D03*
X350976D03*
X342316D03*
X351535Y49379D03*
X361744Y120713D03*
X363621Y127665D03*
X352418Y225329D03*
Y222329D03*
X361171Y223114D03*
X358618Y223129D03*
X361171Y220614D03*
X358671D03*
X355733Y275059D03*
X359734Y288768D03*
X360433Y294030D03*
X355832Y297855D03*
X357925Y304082D03*
X351390Y409120D03*
X353890D03*
Y411620D03*
X351390D03*
X365852Y516466D03*
X353700Y547893D03*
X356850D03*
X355100Y544390D03*
X359200Y566990D03*
X359657Y570702D03*
X359157Y574415D03*
X365158Y597546D03*
Y593580D03*
X352031Y607498D03*
Y610498D03*
X355031Y607498D03*
Y613498D03*
Y610498D03*
X352031Y604498D03*
X355031D03*
X361031Y607498D03*
Y613498D03*
Y610498D03*
X358031Y607498D03*
Y613498D03*
Y610498D03*
Y604498D03*
X365593Y621622D03*
X358031Y619398D03*
Y616498D03*
X355031Y619398D03*
Y616498D03*
X361031Y619398D03*
Y616498D03*
X352675Y640994D03*
Y643494D03*
X355275Y641034D03*
Y643534D03*
X355195Y646094D03*
X352595Y646054D03*
X357986Y698953D03*
X357311Y702110D03*
X364753Y701647D03*
X362895Y716968D03*
X360465Y711368D03*
X362895D03*
X358035D03*
Y716968D03*
X360465D03*
X364753Y704155D03*
X360799Y703710D03*
X358061Y704678D03*
X351865Y711368D03*
X354295D03*
X359539Y720767D03*
X356939D03*
X351839Y726831D03*
X354339D03*
X356939D03*
X362139D03*
X359539D03*
X364739D03*
X356939Y723724D03*
X362139D03*
X359539D03*
X364739D03*
X352225Y746269D03*
X360025D03*
X362625D03*
X364451Y769040D03*
Y771540D03*
Y774040D03*
X361951D03*
Y771540D03*
Y769040D03*
X364451Y776540D03*
X361951D03*
X364447Y766540D03*
X361947D03*
X364451Y791558D03*
X361951D03*
X364451Y786558D03*
Y789058D03*
X361951D03*
Y786558D03*
X364451Y784058D03*
X361951Y781558D03*
X364451Y779058D03*
Y781558D03*
X361951Y779058D03*
Y784058D03*
X361671Y803588D03*
X356671D03*
X351671D03*
X363313Y812088D03*
X359813Y812188D03*
X356313D03*
X352813D03*
X356535Y849708D03*
X364897Y852564D03*
X364821Y861852D03*
X357400Y855982D03*
X356895Y859791D03*
X353281Y859620D03*
X364788Y1193918D03*
X364457Y1188109D03*
X363236Y1199632D03*
X351413Y1210052D03*
X352943Y1214510D03*
X365461Y1254188D03*
Y1251688D03*
Y1249188D03*
Y1246688D03*
X351365Y1246631D03*
X353865D03*
Y1251631D03*
X351365D03*
X353865Y1249131D03*
X351365D03*
X353865Y1254131D03*
X351365D03*
Y1269149D03*
Y1266649D03*
Y1264149D03*
Y1261649D03*
X365461Y1256688D03*
Y1259188D03*
X353865Y1266631D03*
Y1264131D03*
Y1261631D03*
Y1269131D03*
X351365Y1259131D03*
Y1256631D03*
X353865Y1259131D03*
Y1256631D03*
X365561Y1269288D03*
Y1264288D03*
Y1266788D03*
Y1261788D03*
Y1271788D03*
X351361Y1271688D03*
X353861D03*
X359541Y1291918D03*
X362311Y1291968D03*
X356551Y1291880D03*
X353951D03*
X356891Y1306040D03*
Y1308640D03*
Y1303440D03*
X354291Y1306040D03*
Y1308640D03*
Y1303440D03*
X355641Y1311140D03*
X351567Y1314225D03*
Y1317182D03*
X363547Y1315386D03*
X361301Y1322987D03*
Y1325528D03*
X351651Y1320942D03*
Y1323842D03*
X357611Y1326946D03*
X355411Y1328346D03*
X361092Y1338758D03*
X362750Y1340709D03*
X362794Y1333902D03*
X365074Y1330377D03*
X353345Y1332976D03*
X357611Y1329846D03*
X353345Y1330076D03*
X355511Y1331346D03*
X357611Y1332746D03*
X356764Y1359296D03*
X354264D03*
X364764D03*
X362264D03*
X359764D03*
X351632Y1359203D03*
X351923Y1364724D03*
X354423D03*
X356923D03*
X359423D03*
X362223D03*
X364723D03*
X351772Y1362085D03*
X354272D03*
X356772D03*
X359272D03*
X362072D03*
X364572D03*
X363964Y1385102D03*
X356464Y1380102D03*
X358964D03*
X361464D03*
X353964D03*
X351464D03*
X363964D03*
Y1382602D03*
X351464Y1385102D03*
X353964D03*
X361464D03*
X356464D03*
X358964D03*
X351464Y1382602D03*
X361464D03*
X358964D03*
X356464D03*
X353964D03*
X352067Y1387665D03*
X354567D03*
X357067D03*
X359567D03*
X363190Y1387527D03*
X365979Y1387641D03*
X355110Y1398312D03*
X359110D03*
X363110D03*
X357760Y1401449D03*
X353760D03*
X352332Y1391886D03*
X354832D03*
X357332D03*
X359832D03*
X363191Y1390292D03*
Y1392792D03*
X365980Y1392906D03*
Y1390406D03*
X363003Y1395393D03*
X365792Y1395507D03*
X352313Y1395223D03*
X359859D03*
X357208D03*
X354413Y1462595D03*
X361113Y1452895D03*
X357713D03*
X363713D03*
X355113D03*
X357013Y1462595D03*
X361803Y1450295D03*
X357023D03*
X361803Y1455495D03*
X357023D03*
X355103Y1459995D03*
X354413Y1462595D03*
X361113Y1452895D03*
X357713D03*
X355103Y1465195D03*
X363561Y1544997D03*
X354112D03*
X358836D03*
X363561Y1548397D03*
X354112D03*
X358836D03*
X354112Y1550897D03*
X358836D03*
X363561D03*
Y1544997D03*
X354112D03*
X358836D03*
X363561Y1548397D03*
X354112D03*
X358836D03*
X357006Y1592380D03*
X360406D03*
X361184Y1594876D03*
X356228D03*
Y1589884D03*
X361184D03*
X357006Y1592380D03*
X360406D03*
X363036Y1602380D03*
X354376D03*
X366436D03*
Y1614292D03*
X363036D03*
X354376D03*
X355154Y1604876D03*
Y1599884D03*
X362258Y1604876D03*
Y1599790D03*
Y1611796D03*
X355154D03*
X363036Y1602380D03*
X354376D03*
X357006Y1624292D03*
X360406D03*
X362258Y1616788D03*
X355154D03*
X356228Y1626788D03*
X361184D03*
X356228Y1621796D03*
X361184D03*
X357006Y1624292D03*
X360406D03*
X363036Y1614292D03*
X354376D03*
X365493Y1655107D03*
X356596Y1737117D03*
X373535Y49379D03*
X370888Y155250D03*
X379023Y225149D03*
X371318Y218629D03*
X379023Y228649D03*
X379028Y232559D03*
X369428Y231759D03*
X372528Y231859D03*
X380181Y236674D03*
X380012Y239615D03*
Y243615D03*
X379200Y298772D03*
X366671Y297114D03*
X369171D03*
X369671Y292114D03*
Y294614D03*
X367902Y303760D03*
X380935Y443386D03*
X375935D03*
X378435D03*
X379633Y493942D03*
X380771Y524903D03*
X375943D03*
X368371Y553038D03*
X371971Y553138D03*
X377502Y554193D03*
X380157Y553090D03*
X379114Y544866D03*
X368647Y550422D03*
X369171Y562380D03*
X376671D03*
X370271Y555038D03*
X369100Y577400D03*
X369171Y569880D03*
X376600Y577400D03*
X378577Y593026D03*
X377577Y590126D03*
X371724Y699450D03*
X370090Y697482D03*
X370022Y704307D03*
X371515Y715222D03*
Y712681D03*
X367742Y707832D03*
X379711Y708001D03*
Y705101D03*
X375445Y708231D03*
X377545Y706731D03*
X375445Y705331D03*
X377645Y709731D03*
X375445Y711131D03*
X376165Y729437D03*
X378765D03*
X376165Y732037D03*
X378765D03*
X377415Y726937D03*
X369557Y722615D03*
X373425Y746169D03*
X370825D03*
X376165Y734637D03*
X378765D03*
X366951Y769058D03*
Y771558D03*
Y774058D03*
Y776558D03*
X379187Y766428D03*
Y768960D03*
Y771460D03*
Y773960D03*
Y776460D03*
X366947Y766540D03*
X366951Y781558D03*
Y786558D03*
Y789058D03*
Y784058D03*
X379187Y786460D03*
Y783960D03*
Y788960D03*
Y778960D03*
Y781460D03*
X366951Y791558D03*
X379187Y791460D03*
X366951Y779058D03*
X376671Y803588D03*
X371671D03*
X366671D03*
X371999Y819527D03*
Y822927D03*
X372000Y816862D03*
X371999Y819527D03*
X372000Y831797D03*
Y835197D03*
Y826362D03*
Y828862D03*
Y831797D03*
Y835197D03*
X371999Y822927D03*
X372000Y846427D03*
Y843027D03*
Y837862D03*
Y840362D03*
Y849362D03*
Y846427D03*
Y843027D03*
X366864Y857274D03*
X369626Y860717D03*
X378083Y1184949D03*
X367782Y1199648D03*
X367836Y1209506D03*
X370316Y1204673D03*
X367931Y1196981D03*
X376271Y1207488D03*
X372126Y1214455D03*
D03*
X368726D03*
D03*
X380718Y1221906D03*
X379223Y1219527D03*
X372126Y1214455D03*
X368726D03*
X367961Y1254188D03*
Y1251688D03*
Y1249188D03*
Y1246688D03*
X370461Y1254188D03*
Y1249188D03*
Y1251688D03*
Y1246688D03*
X367961Y1256688D03*
Y1259188D03*
X370461D03*
Y1256688D03*
X368061Y1269206D03*
X370561D03*
X368061Y1261706D03*
Y1264206D03*
Y1266706D03*
X370561D03*
Y1264206D03*
Y1261706D03*
Y1271788D03*
X368061D03*
X380977Y1311378D03*
X375877Y1314485D03*
X378477Y1311378D03*
X375877D03*
X370677Y1314485D03*
X368077D03*
X373277D03*
X368077Y1311378D03*
X370677D03*
X373277D03*
X375877Y1317442D03*
X372351Y1326841D03*
X369921D03*
Y1321241D03*
X374781Y1326841D03*
X373277Y1317442D03*
X374781Y1321241D03*
X372351D03*
X380951Y1326841D03*
X378521D03*
X374830Y1339256D03*
X368063Y1334054D03*
X375505Y1336099D03*
X372017Y1334499D03*
X374755Y1333531D03*
X368063Y1336562D03*
X377190Y1387697D03*
X368964Y1382602D03*
Y1385102D03*
X366464D03*
X368964Y1380102D03*
X366464D03*
Y1382602D03*
X368542Y1387639D03*
X379610Y1391781D03*
X375056Y1393741D03*
X368543Y1390404D03*
Y1392904D03*
X368355Y1395505D03*
X377813Y1462595D03*
X381213D03*
X375213D03*
X377123Y1459995D03*
X377813Y1462595D03*
X374513Y1472295D03*
X371113D03*
X377113D03*
X368513D03*
X377123Y1465195D03*
X375203Y1469695D03*
X370423D03*
X375203Y1474895D03*
X370423D03*
X374513Y1472295D03*
X371113D03*
X368285Y1544997D03*
X373009D03*
X377733D03*
X368285Y1548397D03*
X373009D03*
X377733D03*
X382458Y1544997D03*
Y1548397D03*
X368285Y1550897D03*
X373009Y1550697D03*
X377733Y1550897D03*
X368285Y1544997D03*
X373009D03*
X377733D03*
X368285Y1548397D03*
X373009D03*
X377733D03*
X374432Y1582600D03*
X369066Y1592380D03*
X372466D03*
X368288Y1594876D03*
X373244D03*
X368288Y1589884D03*
X373244D03*
X369066Y1592380D03*
X372466D03*
X375096Y1602380D03*
X378496D03*
Y1614292D03*
X375096D03*
X367214Y1604876D03*
Y1599790D03*
X374318Y1604876D03*
X379274D03*
X374318Y1599884D03*
X379274D03*
Y1611796D03*
X374318D03*
X367214D03*
X375096Y1602380D03*
X366436D03*
X378496D03*
X369066Y1624292D03*
X372466D03*
X379274Y1616788D03*
X374318D03*
X367214D03*
X373244Y1626788D03*
Y1621796D03*
X368288Y1626788D03*
Y1621796D03*
X369066Y1624292D03*
X372466D03*
X375096Y1614292D03*
X366436D03*
X378496D03*
X372313Y1641759D03*
X379895Y1670046D03*
X370369Y1661817D03*
X372350Y1683284D03*
X372449Y1680520D03*
X372395Y1677449D03*
X390841Y-25571D03*
X381770Y-30570D03*
X385023Y-30584D03*
X388048Y-29264D03*
X381755Y-28055D03*
X385008Y-28069D03*
X393287Y-28508D03*
X390841Y-22171D03*
Y-15571D03*
Y-12171D03*
Y-25571D03*
Y-22171D03*
Y-15571D03*
X381740Y-25540D03*
X381725Y-23025D03*
X385024Y-17575D03*
X381771Y-17589D03*
X388049Y-18895D03*
X381756Y-20104D03*
X385009Y-20090D03*
X381725Y-14717D03*
X393287Y-18508D03*
X390841Y-12171D03*
X385008Y-9673D03*
X385023Y-7158D03*
X381755Y-9687D03*
X388048Y-8478D03*
X381770Y-7172D03*
X381740Y-12202D03*
X393287Y-9234D03*
X395535Y49379D03*
X395048Y121178D03*
X384375Y147365D03*
X386350Y138980D03*
X384600Y221800D03*
X391310Y227871D03*
X390461Y270694D03*
Y267694D03*
Y275194D03*
X386563Y280370D03*
X389912Y280345D03*
X390881Y284156D03*
X395053Y318125D03*
X383525Y443386D03*
X384668Y471926D03*
X387184Y470495D03*
X389784Y476070D03*
X387184Y494382D03*
X384827Y507057D03*
X382184Y507101D03*
X395657Y546894D03*
X391657Y546816D03*
X387657Y546876D03*
X383071Y553738D03*
X382705Y546433D03*
X384259Y562426D03*
X395669Y563328D03*
X385318Y555238D03*
X384301Y577446D03*
X393481Y571239D03*
X385443Y597279D03*
X392471Y596988D03*
X391021Y588788D03*
X391026Y699021D03*
X390351Y702178D03*
X395935Y717036D03*
Y711436D03*
X393505D03*
X391075D03*
Y717036D03*
X393505D03*
X393839Y703778D03*
X391101Y704746D03*
X382475Y711436D03*
X387335D03*
X384905D03*
X381812Y717060D03*
Y714160D03*
X392579Y720835D03*
X389979D03*
X381802Y720789D03*
Y723746D03*
X387379Y726899D03*
X384879D03*
X389979D03*
Y723792D03*
X382435Y726883D03*
X392579Y726899D03*
X395179D03*
X392579Y723792D03*
X395179D03*
X394987Y766428D03*
X381687D03*
X384187D03*
X394991Y773928D03*
Y771428D03*
Y768928D03*
Y776428D03*
X384191Y768928D03*
Y771428D03*
Y773928D03*
X381691D03*
Y771428D03*
Y768928D03*
X384191Y776428D03*
X381691D03*
X381687Y791460D03*
X384187D03*
X394987Y784060D03*
Y779060D03*
Y781560D03*
Y789060D03*
Y786560D03*
X381687Y778960D03*
Y786460D03*
Y783960D03*
Y788960D03*
Y781460D03*
X384187Y788960D03*
Y786460D03*
Y783960D03*
Y778960D03*
Y781460D03*
X385001Y816927D03*
Y813527D03*
X384500Y810862D03*
X384499Y819862D03*
X385001Y816927D03*
Y813527D03*
X389981Y1015474D03*
X386381D03*
X393861D03*
X389981Y1022560D03*
Y1019017D03*
X386381Y1022560D03*
Y1019017D03*
X393861Y1022560D03*
Y1019017D03*
X390974Y1222849D03*
D03*
Y1219449D03*
D03*
Y1222849D03*
Y1219449D03*
X388630Y1236747D03*
D03*
Y1240147D03*
D03*
Y1236747D03*
X381361Y1254188D03*
Y1249188D03*
Y1251688D03*
Y1246688D03*
X383861Y1254188D03*
X386361D03*
X383861Y1249188D03*
X386361D03*
X383861Y1251688D03*
X386361D03*
X383861Y1246688D03*
X386361D03*
X388630Y1240147D03*
X381361Y1269206D03*
X383861D03*
X381361Y1261706D03*
Y1264206D03*
Y1266706D03*
X383861D03*
Y1264206D03*
Y1261706D03*
X381361Y1256688D03*
Y1259188D03*
X386361Y1256688D03*
Y1259188D03*
X383861Y1256688D03*
Y1259188D03*
X386361Y1269288D03*
Y1261788D03*
Y1266788D03*
Y1264288D03*
X381361Y1271788D03*
X386361D03*
X383861D03*
X388361Y1293713D03*
X385701Y1291828D03*
X392176Y1309859D03*
X394951Y1311259D03*
X389691Y1306240D03*
Y1308840D03*
X387091Y1306240D03*
Y1308840D03*
X389691Y1303640D03*
X387091D03*
X383421Y1311394D03*
X388441Y1311340D03*
X384367Y1314425D03*
Y1317382D03*
X392950Y1315280D03*
X392910Y1317880D03*
X383381Y1326841D03*
X384481Y1321192D03*
Y1324092D03*
X388211Y1328546D03*
X393883Y1342318D03*
X388311Y1331546D03*
X386145Y1333176D03*
Y1330276D03*
X386611Y1336056D03*
X388771Y1337546D03*
Y1334546D03*
X395376Y1353233D03*
X393883Y1344859D03*
X393321Y1385630D03*
X388718Y1387386D03*
X384270Y1389875D03*
X387913Y1452895D03*
X384513D03*
X397913D03*
X383813Y1462595D03*
X390513Y1452895D03*
X395313D03*
X381913D03*
X383823Y1450295D03*
X388603D03*
X383823Y1455495D03*
X388603D03*
X381903Y1459995D03*
X381213Y1462595D03*
X387913Y1452895D03*
X384513D03*
X381903Y1465195D03*
X395384Y1519250D03*
X387182Y1544997D03*
Y1548397D03*
X382458Y1550897D03*
X387182Y1550797D03*
X390082Y1549178D03*
X382458Y1544997D03*
X387182D03*
X382458Y1548397D03*
X387182D03*
X395359Y1546519D03*
X389290Y1561250D03*
X387939Y1565534D03*
X391526Y1582373D03*
X394521Y1575891D03*
X394915Y1590018D03*
X381711Y1593842D03*
X381607Y1590393D03*
X388445Y1585898D03*
X389333Y1598816D03*
X387805Y1607802D03*
Y1610802D03*
X387325Y1627212D03*
X387805Y1617302D03*
Y1614802D03*
X381350Y1649000D03*
Y1642900D03*
Y1645800D03*
X385502Y1667154D03*
X394824Y1667120D03*
X389824D03*
X382115Y1661545D03*
X387324Y1680495D03*
X392324D03*
X382642Y1680979D03*
X385068Y1683502D03*
X410701Y99148D03*
X410500Y104883D03*
X400426Y112815D03*
Y116215D03*
X403734Y118976D03*
X397426Y112815D03*
Y116215D03*
X410400Y107383D03*
X399264Y121144D03*
X400426Y112815D03*
Y116215D03*
X405606Y125815D03*
Y129715D03*
X402606Y129465D03*
Y126065D03*
X405606Y125815D03*
Y129715D03*
X403141Y144300D03*
Y148300D03*
X408603Y152278D03*
X396977Y216685D03*
X400000Y220300D03*
X396237Y315507D03*
X410000Y304000D03*
X399625Y479119D03*
X402184Y466469D03*
X404743Y494451D03*
X402184Y507101D03*
X406184Y507900D03*
X403657Y546915D03*
X403133Y565415D03*
X408550Y557850D03*
X404871Y567338D03*
X403157Y569415D03*
X403381Y573516D03*
X407543Y577415D03*
Y580490D03*
X408445Y687531D03*
X401880Y696220D03*
X404771Y698670D03*
X397793Y701715D03*
X410645Y691931D03*
X410545Y688931D03*
X408445Y690431D03*
Y693331D03*
X410415Y709137D03*
X409165Y711637D03*
Y714237D03*
Y716837D03*
X403062Y704375D03*
X397793Y704223D03*
X404555Y715290D03*
Y712749D03*
X400782Y707900D03*
X397779Y726899D03*
Y723792D03*
X402457Y722615D03*
X399991Y776560D03*
X397491Y768928D03*
Y771428D03*
Y773928D03*
Y776428D03*
X397487Y766428D03*
X399991Y771560D03*
Y769060D03*
X399987Y766428D03*
X399991Y774060D03*
X397487Y779060D03*
Y781560D03*
Y786560D03*
Y784060D03*
X399991D03*
Y779060D03*
Y781560D03*
X397461Y1015474D03*
X404941D03*
X401341D03*
X397461Y1022560D03*
X404941Y1019017D03*
Y1022560D03*
X397461Y1019017D03*
X401341D03*
Y1022560D03*
X403347Y1266162D03*
Y1268662D03*
X400847Y1266162D03*
X398347D03*
X400847Y1268662D03*
X398347D03*
X403347Y1271162D03*
Y1273662D03*
X400847Y1271162D03*
X398347D03*
X400847Y1273662D03*
X398347D03*
X403347Y1276162D03*
Y1278662D03*
X400847D03*
Y1276162D03*
X398347Y1278662D03*
Y1276162D03*
X398447Y1281262D03*
Y1283762D03*
X400947Y1281180D03*
Y1283680D03*
X403447D03*
Y1281180D03*
X400947Y1288680D03*
X403447D03*
X400947Y1286180D03*
X403447D03*
X398447Y1286262D03*
Y1288762D03*
X398461Y1291319D03*
X403461D03*
X400961D03*
X396129Y1334717D03*
X408459Y1330709D03*
X405859D03*
X400659D03*
X403259D03*
X408459Y1333816D03*
X405859D03*
X403259D03*
X400659D03*
X408459Y1336773D03*
X405859D03*
X402503Y1340572D03*
X407363D03*
X404933D03*
X407412Y1358587D03*
X407363Y1346172D03*
X404933D03*
X402503D03*
X400645Y1353385D03*
X408087Y1355430D03*
X404599Y1353830D03*
X407337Y1352862D03*
X400645Y1355893D03*
X397656Y1349708D03*
X410002Y1375093D03*
X405978Y1377794D03*
X401953Y1380494D03*
X397187Y1383354D03*
X401313Y1452895D03*
X403913D03*
X397223Y1450295D03*
X402003D03*
X397223Y1455495D03*
X402003D03*
X401313Y1452895D03*
X397913D03*
X408683Y1478082D03*
Y1480682D03*
Y1484082D03*
Y1494082D03*
Y1486682D03*
Y1491482D03*
X406083Y1479992D03*
Y1484772D03*
Y1493392D03*
X408683Y1480682D03*
Y1484082D03*
Y1497482D03*
Y1500082D03*
X406083Y1498172D03*
X401583Y1504872D03*
X408683Y1497482D03*
Y1494082D03*
X404147Y1509654D03*
X401536Y1516120D03*
Y1512220D03*
X397206Y1516953D03*
Y1511953D03*
Y1514453D03*
X397891Y1521436D03*
X401659Y1519845D03*
X404686Y1516120D03*
Y1512220D03*
X410650Y1509469D03*
X408150D03*
X407836Y1512220D03*
Y1516120D03*
X407561Y1519845D03*
X404699Y1521436D03*
Y1523953D03*
X398782Y1531073D03*
X401282D03*
X403782D03*
X410108Y1535680D03*
X398201Y1548563D03*
X405331Y1548928D03*
X410672Y1561170D03*
X410851Y1557434D03*
X402912Y1558011D03*
X396452Y1577738D03*
X403004Y1582457D03*
X408925Y1573805D03*
Y1576805D03*
X400905Y1596091D03*
X403417Y1606224D03*
X403837Y1609056D03*
Y1612456D03*
X399447Y1612609D03*
X399801Y1606376D03*
X406697Y1604207D03*
X403848Y1615354D03*
X408856Y1623435D03*
X405436Y1620268D03*
X406343Y1613847D03*
X405747Y1623350D03*
X400623Y1629772D03*
X406075Y1641000D03*
X397822Y1629615D03*
X409552Y1633606D03*
X405342Y1628611D03*
X404661Y1634139D03*
X399824Y1667120D03*
X409000Y1667025D03*
X401666Y1677925D03*
X405000Y1675000D03*
X397324Y1680495D03*
X409000Y1683500D03*
X417535Y49379D03*
X424975Y54762D03*
X417025D03*
X413949Y69270D03*
X425555Y92014D03*
X417617Y79073D03*
X425555Y82014D03*
X423376Y96664D03*
X424084Y110839D03*
X417486Y124179D03*
Y127579D03*
X411952Y132751D03*
Y123051D03*
X414486Y127579D03*
Y124179D03*
X417486D03*
Y127579D03*
X424086Y123023D03*
X422890Y136700D03*
X424086Y133265D03*
X412370Y188210D03*
X411800Y220200D03*
X411610Y223140D03*
X424815Y217646D03*
X419299Y212096D03*
X423299D03*
X422936Y228147D03*
Y232793D03*
X420115Y226323D03*
X411940Y235442D03*
X420288Y244184D03*
X412715Y254165D03*
X423730Y249570D03*
X412715Y251165D03*
Y262165D03*
Y270165D03*
Y258165D03*
Y266165D03*
X419617Y308000D03*
X424151Y453174D03*
X413425Y479042D03*
X415984Y466392D03*
X418543Y494374D03*
X415984Y507024D03*
X424784Y496572D03*
X411500Y510800D03*
X412771Y524820D03*
X414402Y544690D03*
X424026Y681221D03*
X423351Y684378D03*
X424101Y686946D03*
X412711Y687301D03*
X424075Y693636D03*
X425579Y703035D03*
X422979D03*
X424075Y699236D03*
X414682Y703139D03*
X420335Y693636D03*
X415475D03*
X417905D03*
X412711Y690201D03*
X414712Y699440D03*
Y696540D03*
X411765Y711637D03*
Y714237D03*
Y716837D03*
X415435Y709083D03*
X417879Y709099D03*
X425579D03*
X422979D03*
X420379D03*
X425579Y705992D03*
X422979D03*
X414682Y706096D03*
X420158Y748643D03*
X415158Y756175D03*
Y751175D03*
Y753675D03*
X417658Y748643D03*
X415158D03*
Y761175D03*
X420158D03*
X417658D03*
X415158Y758675D03*
X420162Y751143D03*
Y753643D03*
Y756143D03*
X417662D03*
Y753643D03*
Y751143D03*
X420162Y758643D03*
X417662D03*
X415158Y771175D03*
X420158Y763675D03*
Y766175D03*
X417658Y768675D03*
X415158D03*
X417658Y763675D03*
Y766175D03*
X415158Y763675D03*
Y766175D03*
X418918Y1006025D03*
Y1013505D03*
X423811Y1009400D03*
X418918Y1009765D03*
X415318D03*
Y1006025D03*
X424873Y1014745D03*
X423811Y1005800D03*
X415318Y1013505D03*
X418918Y1024726D03*
Y1020986D03*
Y1028466D03*
Y1017245D03*
X423811Y1028831D03*
X424873Y1023013D03*
Y1018879D03*
X415318Y1028466D03*
Y1020986D03*
Y1024726D03*
Y1017245D03*
Y1032206D03*
X418918D03*
X423811Y1032431D03*
X424024Y1267144D03*
X414247Y1268662D03*
X416747D03*
X419247D03*
X424024Y1269644D03*
Y1272144D03*
X414247Y1281180D03*
Y1283680D03*
X416747D03*
Y1281180D03*
Y1271162D03*
X414247D03*
X416747Y1278662D03*
Y1276162D03*
X419247Y1278662D03*
Y1276162D03*
Y1273662D03*
X416747D03*
X414247Y1278662D03*
Y1276162D03*
Y1273662D03*
X419361Y1283719D03*
Y1281219D03*
X419247Y1271162D03*
X424024Y1274644D03*
X414247Y1288680D03*
X416747D03*
X414247Y1286180D03*
X416747D03*
X419361Y1288719D03*
Y1291219D03*
X414361D03*
X416861D03*
X419361Y1286219D03*
X423521Y1311969D03*
X421091Y1311219D03*
X419673Y1325571D03*
Y1322971D03*
Y1328171D03*
X422273Y1322971D03*
Y1325571D03*
Y1328171D03*
X416949Y1336713D03*
Y1333756D03*
X424333Y1331447D03*
X411059Y1330709D03*
X416003Y1330725D03*
X413559Y1330709D03*
X421023Y1330671D03*
X417063Y1340523D03*
Y1343423D03*
X415963Y1346172D03*
X413533D03*
X411103D03*
X421315Y1354276D03*
Y1351376D03*
X421205Y1348586D03*
Y1345686D03*
X418675Y1352166D03*
Y1349266D03*
X414132Y1372234D03*
X427286Y1480190D03*
Y1483590D03*
X424686Y1484280D03*
Y1479500D03*
X411283Y1479992D03*
Y1484772D03*
Y1493392D03*
X427286Y1501990D03*
Y1505390D03*
X424686Y1506080D03*
Y1501300D03*
X411283Y1498172D03*
X415862Y1503715D03*
X425631Y1517138D03*
X425087Y1510708D03*
X422587D03*
X423131Y1517138D03*
X412086Y1512076D03*
Y1514576D03*
X422557Y1530595D03*
X420057D03*
X412862Y1526750D03*
X417098Y1533764D03*
Y1531264D03*
X422557Y1537595D03*
X420057D03*
X417098Y1536411D03*
X418157Y1549295D03*
X423157Y1541795D03*
Y1544295D03*
X415657Y1541795D03*
X418157Y1546795D03*
Y1544295D03*
Y1541795D03*
X415657Y1549295D03*
Y1546795D03*
Y1544295D03*
X420657Y1541795D03*
Y1544295D03*
Y1546795D03*
Y1549295D03*
X417098Y1538911D03*
X424115Y1548199D03*
Y1551099D03*
X421697Y1551844D03*
X421683Y1565312D03*
X421108Y1560235D03*
X424616Y1560086D03*
X414202Y1559396D03*
X421294Y1557729D03*
X421059Y1569168D03*
X421277Y1571923D03*
X416163Y1594450D03*
X422007Y1592330D03*
X413396Y1594597D03*
X410991Y1597002D03*
X425469Y1595433D03*
X422069D03*
X413100Y1607600D03*
X418293Y1607495D03*
X423379Y1607675D03*
X413200Y1612700D03*
X423439Y1612407D03*
X411515Y1599649D03*
X419277Y1600725D03*
X413100Y1617900D03*
X418500Y1618000D03*
X423349Y1617857D03*
X416962Y1634123D03*
X415437Y1636382D03*
X417365Y1630495D03*
X420765D03*
X421347Y1636668D03*
X414500Y1639075D03*
X417365Y1627695D03*
X420765D03*
X411500Y1653500D03*
X417441Y1643946D03*
X411448Y1650598D03*
X420000Y1664925D03*
X411500Y1657500D03*
X417000Y1675000D03*
X413000Y1683500D03*
X415500Y1672500D03*
X422596Y1737117D03*
X439535Y49379D03*
X430564Y56348D03*
X430500Y72900D03*
X436090Y116007D03*
Y120007D03*
Y124007D03*
Y132007D03*
Y128007D03*
X440090Y132007D03*
X433997Y166400D03*
X437997D03*
Y170701D03*
X433997D03*
X431299Y204145D03*
X433124Y222253D03*
Y225205D03*
X439299Y220046D03*
X440029Y240381D03*
X434420Y239930D03*
X426947Y320749D03*
X433277Y471970D03*
X427225Y478965D03*
X429784Y466315D03*
X426208Y468977D03*
X436226Y475526D03*
X432343Y494297D03*
X439500Y484000D03*
X429784Y506947D03*
X427500Y510553D03*
X426011Y524888D03*
X440591Y684518D03*
X436130Y683281D03*
X436062Y686575D03*
X426839Y685978D03*
X430793Y683915D03*
X426505Y693636D03*
X428935D03*
Y699236D03*
X426505D03*
X437555Y697490D03*
Y694949D03*
X433782Y690100D03*
X430779Y709099D03*
Y705992D03*
X428179Y709099D03*
Y705992D03*
X435457Y704915D03*
X439411Y733527D03*
X436811D03*
X439411Y736147D03*
X436811D03*
X436411Y738717D03*
X439011D03*
X436411Y743917D03*
X439011D03*
X436411Y741317D03*
X439011D03*
X430958Y748643D03*
X433458D03*
X433462Y751143D03*
Y753643D03*
Y756143D03*
X430962D03*
Y753643D03*
Y751143D03*
Y758643D03*
X440159Y966741D03*
Y970341D03*
Y981741D03*
Y974241D03*
Y977841D03*
Y985341D03*
X438359Y993766D03*
X438434Y989766D03*
X438359Y997766D03*
X431291Y1009400D03*
X438316Y1014745D03*
X427551Y1009400D03*
X435031D03*
X438771D03*
X428473Y1014745D03*
X427551Y1005800D03*
X434716Y1014745D03*
X431291Y1005800D03*
X435031D03*
X438771D03*
X438359Y1001766D03*
X438771Y1028831D03*
X438316Y1023013D03*
X427551Y1028831D03*
X435031D03*
X438316Y1018879D03*
X428473D03*
Y1023013D03*
X431291Y1028831D03*
X434716Y1018879D03*
Y1023013D03*
X439284Y1038766D03*
Y1042766D03*
X431291Y1032431D03*
X435031D03*
X438771D03*
X427551D03*
X427615Y1282917D03*
Y1275417D03*
Y1280417D03*
Y1277917D03*
X427251Y1291747D03*
X436903Y1285694D03*
Y1289694D03*
X431830Y1311240D03*
X438561Y1321622D03*
X432561D03*
X435561D03*
X436924Y1462595D03*
X433524D03*
X440224Y1452895D03*
X439524Y1462595D03*
X437624Y1452895D03*
X430924Y1462595D03*
X439534Y1450295D03*
Y1455495D03*
X437614Y1459995D03*
X432834D03*
X436924Y1462595D03*
X433524D03*
X440224Y1452895D03*
X437614Y1465195D03*
X432834D03*
X427286Y1477590D03*
Y1486190D03*
X429886Y1484280D03*
Y1479500D03*
X427286Y1483590D03*
Y1480190D03*
Y1499490D03*
X429886Y1506080D03*
Y1501300D03*
X427286Y1507990D03*
X436140Y1499320D03*
X427286Y1501990D03*
Y1505390D03*
X437661Y1518040D03*
Y1514420D03*
Y1510800D03*
X428746Y1521727D03*
X438153Y1528731D03*
X427730Y1536606D03*
X427704Y1531902D03*
Y1529402D03*
X426704Y1523331D03*
Y1526731D03*
X438732Y1546977D03*
X427730Y1539106D03*
X430027Y1546795D03*
Y1544295D03*
X432527Y1541795D03*
Y1549295D03*
Y1546795D03*
Y1544295D03*
X430027Y1541795D03*
Y1549295D03*
X435027D03*
Y1546795D03*
Y1544295D03*
Y1541795D03*
X427527Y1549295D03*
Y1546795D03*
Y1544295D03*
Y1541795D03*
X426620Y1551844D03*
X437736Y1544392D03*
X432051Y1560635D03*
X437910Y1553910D03*
X430239Y1581726D03*
X426688Y1598003D03*
X439283Y1608704D03*
X436776Y1610394D03*
X430500Y1605835D03*
X432559Y1627500D03*
X439404Y1615146D03*
X431664Y1624342D03*
X436776Y1613794D03*
X430500Y1613709D03*
X428000Y1640500D03*
X434500Y1641500D03*
X431000Y1640500D03*
X428500Y1650000D03*
X436925Y1649500D03*
X441182Y77125D03*
X455502Y88711D03*
X452102D03*
X450102Y87011D03*
X455502Y88711D03*
X452102D03*
X448414Y94684D03*
X445014D03*
X450414Y92384D03*
X443014D03*
X448414Y94684D03*
X445014D03*
X452948Y104003D03*
X444090Y116007D03*
X452090D03*
X448090D03*
X452090Y124007D03*
Y132007D03*
X444090D03*
X452090Y128007D03*
X445997Y166400D03*
X453997D03*
X449997D03*
X441997Y170701D03*
X449997D03*
X453783Y217646D03*
X443299Y220046D03*
X447299D03*
X443400Y247880D03*
X455422Y244103D03*
X444310Y243370D03*
X448852Y283318D03*
X452480Y273420D03*
X454518Y280793D03*
X447840Y275970D03*
X441320Y298170D03*
Y295170D03*
Y304170D03*
Y310170D03*
Y301170D03*
Y307170D03*
Y313170D03*
Y316170D03*
X442297Y474442D03*
X449496Y474009D03*
X446547Y480123D03*
X449760Y497240D03*
X448024Y505345D03*
X452084Y511870D03*
X453723Y526558D03*
X444441Y565549D03*
X452565Y652837D03*
X450305Y669036D03*
X452735D03*
X447875D03*
X440845Y668731D03*
Y665831D03*
X445111Y662701D03*
X442945Y664331D03*
X440845Y662931D03*
X443045Y667331D03*
X445111Y665601D03*
X447212Y671640D03*
X455379Y678435D03*
X450279Y684499D03*
X455379D03*
X452779D03*
X455379Y681392D03*
X444165Y687037D03*
X441565D03*
X443235Y684637D03*
X447835Y684483D03*
X447162Y678409D03*
Y681366D03*
X447212Y674540D03*
X444325Y702449D03*
X441725D03*
X444165Y689637D03*
Y692237D03*
X441565D03*
Y689637D03*
X446591Y716837D03*
X443991D03*
X446591Y719437D03*
X443991D03*
X446686Y726660D03*
Y729160D03*
Y731660D03*
X449190Y726528D03*
Y729028D03*
Y731528D03*
X451690D03*
Y729028D03*
Y726528D03*
X446686Y724028D03*
X449186D03*
X451686D03*
Y741660D03*
X449186D03*
Y739160D03*
Y736660D03*
X451686Y739160D03*
Y736660D03*
X446686Y741660D03*
Y736660D03*
Y739160D03*
Y734160D03*
X449190Y734028D03*
X451690D03*
X441959Y993766D03*
Y997766D03*
X442034Y989766D03*
X442511Y1009400D03*
X449992D03*
X446252D03*
X453732D03*
X441959Y1001766D03*
X447174Y1014745D03*
X453810D03*
X449992Y1005800D03*
X453732D03*
X443574Y1014745D03*
X446252Y1005800D03*
X442511D03*
X446252Y1028831D03*
X453732D03*
X449992D03*
X447174Y1023013D03*
X442511Y1028831D03*
X447174Y1018879D03*
X453810Y1023013D03*
X443574D03*
X453810Y1018879D03*
X443574D03*
X453732Y1032431D03*
X442884Y1038766D03*
X442511Y1032431D03*
X442884Y1042766D03*
X446252Y1032431D03*
X449992D03*
X441159Y1055141D03*
Y1051541D03*
X443764Y1179395D03*
X448688Y1305947D03*
X449440Y1308386D03*
X450220Y1310834D03*
X451083Y1313347D03*
X441561Y1321622D03*
X444561D03*
X452089Y1316074D03*
X452936Y1318775D03*
X453823Y1321436D03*
X454603Y1324033D03*
X454909Y1326721D03*
X443624Y1452895D03*
X446224D03*
X444314Y1450295D03*
Y1455495D03*
X443624Y1452895D03*
X457024Y1472295D03*
X453624D03*
X451024D03*
X452934Y1469695D03*
Y1474895D03*
X453624Y1472295D03*
X452427Y1544997D03*
Y1548397D03*
X457151Y1544997D03*
Y1548397D03*
X447587Y1552567D03*
X452427Y1550797D03*
Y1544997D03*
Y1548397D03*
X446810Y1565020D03*
X446910Y1562098D03*
X440846Y1576526D03*
X446653Y1573264D03*
X441931Y1581662D03*
X455739Y1592380D03*
X452339D03*
X451561Y1589884D03*
Y1594876D03*
X452339Y1592380D03*
X443590Y1593880D03*
X441460Y1596020D03*
X444128Y1600200D03*
X450500Y1612450D03*
X455739Y1624292D03*
X452339D03*
X451561Y1621796D03*
Y1626788D03*
X448776Y1622266D03*
Y1617166D03*
Y1619766D03*
X452339Y1624292D03*
X450180Y1614950D03*
X452500Y1637559D03*
X447387Y1641441D03*
X445800Y1633200D03*
Y1636000D03*
X454099Y1649575D03*
X446000Y1650000D03*
X444596Y1737117D03*
X461535Y49379D03*
X468228Y70016D03*
X462653Y72525D03*
X457502Y87011D03*
X462456Y95101D03*
X459056D03*
X464456Y93101D03*
X457056D03*
X462456Y95101D03*
X459056D03*
X470010Y141070D03*
X461997Y166400D03*
X457931Y212703D03*
X464051Y224799D03*
X461931Y212703D03*
X468574Y213104D03*
X464440Y218253D03*
X463402Y229970D03*
X457731Y237588D03*
X463653Y237390D03*
X460624Y240953D03*
Y244103D03*
X462703Y242342D03*
X463240Y244980D03*
X465699Y282833D03*
X456720Y285158D03*
X457248Y280143D03*
Y282643D03*
X469323Y306273D03*
X462093Y310123D03*
X467943Y311563D03*
X465153Y310123D03*
X467893Y308643D03*
X458873Y310173D03*
X455813D03*
X467644Y353417D03*
X467545Y356864D03*
X465925Y489925D03*
X457424Y497978D03*
X458725Y524480D03*
X470331Y566632D03*
X465331D03*
X467831D03*
X462831D03*
X467831Y569132D03*
X470331D03*
X459931Y566632D03*
X457431D03*
X462831Y569132D03*
X457431D03*
X459931D03*
X465331D03*
X470331Y576132D03*
X467831Y571632D03*
X465331D03*
X467831Y576132D03*
X465331D03*
X470331Y571632D03*
X462831D03*
Y576132D03*
X457431Y571632D03*
Y574132D03*
X459931Y571632D03*
Y574132D03*
X457431Y576632D03*
X459931D03*
X462831Y598514D03*
X467831D03*
X470331D03*
X465331D03*
X457711D03*
X460211D03*
X462831Y601014D03*
X467831D03*
X470331D03*
X465331D03*
X457711D03*
X460211D03*
X469046Y657062D03*
X456426Y656621D03*
X458905Y669036D03*
X456475D03*
X461335D03*
X469955Y672890D03*
X463193Y659315D03*
X468462Y661975D03*
X455751Y659778D03*
X459239Y661378D03*
X469955Y670349D03*
X456501Y662346D03*
X466182Y665500D03*
X457979Y678435D03*
X460579Y684499D03*
X457979D03*
X460579Y681392D03*
X457979D03*
X467957Y680315D03*
X463179Y684499D03*
Y681392D03*
X461335Y674636D03*
X456475D03*
X458905D03*
X462490Y731528D03*
Y726528D03*
Y729028D03*
X464990D03*
Y726528D03*
X467486Y724028D03*
X464986D03*
X462486D03*
X467490Y726660D03*
X457472Y1009400D03*
X462365Y1006025D03*
X457410Y1014745D03*
X462365Y1009765D03*
Y1013505D03*
X457472Y1005800D03*
X465965Y1009765D03*
Y1006025D03*
Y1013505D03*
X462365Y1020986D03*
X457410Y1018879D03*
X462365Y1028466D03*
Y1024726D03*
Y1017245D03*
X457410Y1023013D03*
X457472Y1028831D03*
X465965Y1020986D03*
Y1024726D03*
Y1028466D03*
Y1017245D03*
X462365Y1032206D03*
X465965D03*
X457472Y1032431D03*
X463724Y1462595D03*
X470424Y1452895D03*
X460324Y1462595D03*
X467024Y1452895D03*
X466324Y1462595D03*
X457724D03*
X459634Y1459995D03*
X464414D03*
X466334Y1450295D03*
X464424Y1452895D03*
X466334Y1455495D03*
X463724Y1462595D03*
X470424Y1452895D03*
X460324Y1462595D03*
X467024Y1452895D03*
X459624Y1472295D03*
X459634Y1465195D03*
X464414D03*
X457714Y1469695D03*
Y1474895D03*
X457024Y1472295D03*
X461876Y1544997D03*
X466600D03*
X461876Y1548397D03*
X466600D03*
X471325Y1544997D03*
Y1548397D03*
X461876Y1550897D03*
X457151Y1550797D03*
X466600Y1550697D03*
X457151Y1544997D03*
X461876D03*
X466600D03*
X457151Y1548397D03*
X461876D03*
X466600D03*
X462215Y1581510D03*
X467799Y1592380D03*
X464399D03*
X468577Y1589884D03*
Y1594876D03*
X456517Y1589884D03*
X463621D03*
Y1594876D03*
X456517D03*
X464399Y1592380D03*
X455739D03*
X467799D03*
X458369Y1602380D03*
X461769D03*
X470429D03*
Y1614292D03*
X458369D03*
X461769D03*
X457591Y1599884D03*
X462547D03*
Y1604876D03*
X457591D03*
X462547Y1611796D03*
X457591D03*
X469651D03*
Y1599884D03*
Y1604876D03*
X458369Y1602380D03*
X461769D03*
X467799Y1624292D03*
X464399D03*
X462547Y1616788D03*
X457591D03*
X469651D03*
X468577Y1621796D03*
Y1626788D03*
X463621Y1621796D03*
Y1626788D03*
X456517Y1621796D03*
Y1626788D03*
X464399Y1624292D03*
X455739D03*
X467799D03*
X458369Y1614292D03*
X461769D03*
X462753Y1641289D03*
X457240Y1629500D03*
X462500Y1655500D03*
X461000Y1650000D03*
X467500Y1651500D03*
X457000Y1650000D03*
X466041Y1664913D03*
X470463Y1670038D03*
X464925Y1662500D03*
X470500Y1674075D03*
X467500Y1678500D03*
X462500Y1701000D03*
Y1697000D03*
X468500Y1708500D03*
X466000Y1714575D03*
X467416Y1724808D03*
X469975D03*
X464734Y1730518D03*
X466596Y1737117D03*
X462500Y1733500D03*
X483535Y49379D03*
X478949Y60029D03*
Y55135D03*
Y64975D03*
X479400Y94574D03*
Y97574D03*
Y110930D03*
X479465Y119644D03*
Y115644D03*
X476295Y130020D03*
X472895D03*
X482255Y133222D03*
Y129822D03*
X470895Y128020D03*
X478295D03*
X482255Y127322D03*
Y135722D03*
X476295Y130020D03*
X472895D03*
X482255Y133222D03*
Y129822D03*
X479465Y123644D03*
X482380Y141942D03*
X485780D03*
X479630D03*
X482380D03*
X483800Y189400D03*
X480200Y191900D03*
X483467Y209755D03*
X480700Y208200D03*
X480715Y211099D03*
X471371Y231764D03*
Y235764D03*
X483227Y233000D03*
X483800Y270440D03*
X480323Y291023D03*
X474691Y306073D03*
X471743Y304923D03*
X473643Y308683D03*
X471003Y311563D03*
X470953Y308643D03*
X484063Y313956D03*
X479148Y315502D03*
X480773Y307153D03*
X471015Y527283D03*
X475731Y566632D03*
X473231D03*
Y569132D03*
X475731D03*
Y574132D03*
Y571632D03*
X473231Y574132D03*
Y571632D03*
X475731Y576632D03*
X473231D03*
X485335Y642536D03*
X480475D03*
X482905D03*
X473445Y642231D03*
X477711Y639101D03*
X475645Y640831D03*
X473445Y639331D03*
X475545Y637831D03*
X473445Y636431D03*
X477711Y636201D03*
X475415Y658037D03*
X482879Y657999D03*
X480435Y657983D03*
X485379Y657999D03*
X479822Y651989D03*
Y654946D03*
X479812Y645240D03*
Y648140D03*
X476765Y660537D03*
X474165D03*
X476765Y663137D03*
X474165D03*
X476765Y665737D03*
X474165D03*
X479058Y702660D03*
Y700160D03*
X484062Y700028D03*
Y702528D03*
X481562D03*
Y700028D03*
X479058Y697528D03*
X481558D03*
X484058D03*
X479058Y717660D03*
Y707660D03*
Y712660D03*
Y710160D03*
Y715160D03*
X484058Y710160D03*
Y712660D03*
X481558Y710160D03*
Y712660D03*
X484058Y715160D03*
X481558D03*
X484062Y707528D03*
X481562D03*
X479058Y705160D03*
X484062Y705028D03*
X481562D03*
X477203Y1015474D03*
X484784D03*
X480803D03*
X477203Y1019017D03*
X484784D03*
X477203Y1022560D03*
X484784D03*
X480803D03*
Y1019017D03*
X487124Y1462595D03*
X484524D03*
X471114Y1450295D03*
X473024Y1452895D03*
X471114Y1455495D03*
X483824Y1472295D03*
X480424D03*
X477824D03*
X484514Y1469695D03*
X479734D03*
X484514Y1474895D03*
X479734D03*
X483824Y1472295D03*
X480424D03*
X476049Y1544997D03*
X480774D03*
X476049Y1548397D03*
X480774D03*
X485498Y1544997D03*
Y1548397D03*
X480774Y1550697D03*
X476049Y1550897D03*
X471325D03*
Y1544997D03*
X476049D03*
X480774D03*
X471325Y1548397D03*
X476049D03*
X480774D03*
X476459Y1592380D03*
X479859D03*
X480637Y1589884D03*
Y1594876D03*
X475681D03*
Y1589884D03*
X476459Y1592380D03*
X479859D03*
X482489Y1602380D03*
X473829D03*
X485889D03*
Y1614292D03*
X482489D03*
X473829D03*
X481711Y1611796D03*
Y1599884D03*
Y1604876D03*
X474607Y1611796D03*
Y1599884D03*
Y1604876D03*
X470429Y1602380D03*
X482489D03*
X473829D03*
X476459Y1624292D03*
X479859D03*
X481711Y1616788D03*
X474607D03*
X475681Y1621796D03*
X480637D03*
X475681Y1626788D03*
X480637D03*
X476459Y1624292D03*
X479859D03*
X470429Y1614292D03*
X482489D03*
X473829D03*
X478500Y1655500D03*
X477538Y1661463D03*
X478500Y1697000D03*
Y1710500D03*
Y1733500D03*
X491849Y55095D03*
Y60105D03*
X497885Y51315D03*
X491849Y64965D03*
X487590Y105969D03*
X494810D03*
X492300Y121389D03*
X490380Y131442D03*
X493780D03*
X487880D03*
X496280D03*
X492300Y124389D03*
X490380Y131442D03*
X493780D03*
X488580Y141942D03*
X485780D03*
X500136Y141058D03*
X494200Y158800D03*
X495500Y161386D03*
X497700Y157200D03*
X492685Y160994D03*
X486682Y193516D03*
X495232D03*
Y185516D03*
X486682Y189516D03*
X498776Y209285D03*
X486600Y200800D03*
X495232Y197516D03*
X491635Y212577D03*
X498776Y213285D03*
X500269Y225071D03*
X499380Y222510D03*
X491635Y225970D03*
X487442Y223377D03*
X491635Y215652D03*
X487541Y226527D03*
X500209Y238119D03*
X491577Y238120D03*
X488908Y242754D03*
X491577Y243240D03*
X485962Y290679D03*
X488076Y350420D03*
X487827Y354017D03*
X490419Y362138D03*
X488260Y418980D03*
X498500Y419425D03*
X493935Y642536D03*
X489075D03*
X491505D03*
X489026Y630121D03*
X495793Y632815D03*
X488351Y633278D03*
X491839Y634878D03*
X489101Y635846D03*
X498782Y639000D03*
X493935Y648136D03*
X487979Y651935D03*
X490579D03*
X493179Y654892D03*
Y657999D03*
X487979Y654892D03*
X490579D03*
Y657999D03*
X487979D03*
X495779Y654892D03*
Y657999D03*
X489075Y648136D03*
X491505D03*
X497362Y700028D03*
Y702528D03*
X494862D03*
Y700028D03*
X499858Y697528D03*
X497358D03*
X494858D03*
X499862Y700160D03*
Y702660D03*
X494862Y705028D03*
X497362D03*
X499862Y705160D03*
X492284Y1015474D03*
X488384D03*
X495884D03*
X492284Y1019017D03*
Y1022560D03*
X488384D03*
Y1019017D03*
X495884Y1022560D03*
Y1019017D03*
X490524Y1462595D03*
X497224Y1452895D03*
X493824D03*
X499824D03*
X491224D03*
X493124Y1462595D03*
X497914Y1450295D03*
X493134D03*
X497914Y1455495D03*
X493134D03*
X486434Y1459995D03*
X491214D03*
X490524Y1462595D03*
X497224Y1452895D03*
X487124Y1462595D03*
X493824Y1452895D03*
X486424Y1472295D03*
X486434Y1465195D03*
X491214D03*
X499672Y1544997D03*
X490223D03*
X494947D03*
X499672Y1548397D03*
X490223D03*
X494947D03*
X485498Y1550797D03*
X490223Y1550897D03*
X494947D03*
X499672D03*
Y1544997D03*
X485498D03*
X490223D03*
X494947D03*
X499672Y1548397D03*
X485498D03*
X490223D03*
X494947D03*
X500579Y1592380D03*
X488519D03*
X491919D03*
X499801Y1594876D03*
X492697Y1589884D03*
X487741Y1594876D03*
X492697D03*
X499801Y1589884D03*
X487741D03*
X488519Y1592380D03*
X491919D03*
X494549Y1602380D03*
X497949D03*
Y1614292D03*
X494549D03*
X498727Y1611796D03*
Y1599884D03*
Y1604876D03*
X486667Y1611796D03*
X493771D03*
Y1599884D03*
Y1604876D03*
X486667Y1599884D03*
Y1604876D03*
X494549Y1602380D03*
X485889D03*
X497949D03*
X500579Y1624292D03*
X488519D03*
X491919D03*
X498727Y1616788D03*
X499801Y1621796D03*
Y1626788D03*
X486667Y1616788D03*
X493771D03*
X492697Y1621796D03*
X487741D03*
X492697Y1626788D03*
X487741D03*
X488519Y1624292D03*
X491919D03*
X494549Y1614292D03*
X485889D03*
X497949D03*
X488596Y1737117D03*
X512658Y46613D03*
X510810Y49193D03*
X510815Y69562D03*
X504796Y86320D03*
X514240Y97146D03*
X502815Y106984D03*
X512654Y94967D03*
X514240Y97146D03*
X500836Y119092D03*
X511140Y109829D03*
X513772Y121220D03*
X503000Y135600D03*
X509346Y125842D03*
X514418Y145171D03*
X503161Y149895D03*
X514418Y149171D03*
Y141171D03*
Y153171D03*
X507945Y160919D03*
X503161Y154620D03*
X500600Y157100D03*
X513360Y169190D03*
X503507Y185516D03*
X511771Y199576D03*
X508238Y199506D03*
X511170Y224930D03*
X515151Y220166D03*
X511684Y221219D03*
X504351Y215901D03*
X511170Y227882D03*
X501718Y240558D03*
X508723Y280721D03*
X510223Y289035D03*
X507698D03*
Y297090D03*
X510223D03*
X515223Y289035D03*
X507698Y305145D03*
X510223D03*
X510606Y314124D03*
X508081D03*
X515223Y313200D03*
Y305145D03*
X501500Y433000D03*
X513775Y608436D03*
X506745Y608131D03*
X508945Y606731D03*
X506745Y602331D03*
Y605231D03*
X508845Y603731D03*
X511011Y602101D03*
Y605001D03*
X513012Y611040D03*
X510065Y626437D03*
X508715Y623937D03*
X507465Y626437D03*
X513735Y623883D03*
X513012Y620706D03*
Y617749D03*
Y613940D03*
X510065Y629037D03*
X507465D03*
X510065Y631637D03*
X507465D03*
X514771Y643138D03*
X501062Y635475D03*
X500457Y653715D03*
X502555Y646390D03*
Y643849D03*
X514162Y673428D03*
Y665928D03*
Y668428D03*
Y670928D03*
X514158Y663428D03*
Y678460D03*
Y683460D03*
Y680960D03*
Y675960D03*
X509572Y865327D03*
X513572D03*
X506261Y865338D03*
X513924Y1462595D03*
X511324D03*
X513234Y1459995D03*
X513924Y1462595D03*
X510624Y1472295D03*
X507224D03*
X513224D03*
X504624D03*
X513234Y1465195D03*
X511314Y1469695D03*
X506534D03*
X511314Y1474895D03*
X506534D03*
X510624Y1472295D03*
X507224D03*
X504396Y1544997D03*
X509120D03*
X513844D03*
X504396Y1548397D03*
X509120D03*
X513844D03*
Y1550897D03*
X509120Y1550697D03*
X504396Y1550897D03*
Y1544997D03*
X509120D03*
X513844D03*
X504396Y1548397D03*
X509120D03*
X513844D03*
X512639Y1592380D03*
X516039D03*
X503979D03*
X511861Y1594876D03*
X504757Y1589884D03*
Y1594876D03*
X511861Y1589884D03*
X500579Y1592380D03*
X512639D03*
X503979D03*
X506609Y1602380D03*
X510009D03*
X506609Y1614292D03*
X510009D03*
X505831Y1611796D03*
X510787D03*
X505831Y1599884D03*
Y1604876D03*
X510787Y1599884D03*
Y1604876D03*
X506609Y1602380D03*
X510009D03*
X512639Y1624292D03*
X516039D03*
X503979D03*
X511861Y1621796D03*
Y1626788D03*
X505831Y1616788D03*
X510787D03*
X504757Y1621796D03*
Y1626788D03*
X500579Y1624292D03*
X512639D03*
X503979D03*
X506609Y1614292D03*
X510009D03*
X518843Y23788D03*
X519765Y40328D03*
X523165D03*
X516058Y46613D03*
X517915Y42257D03*
X525001D03*
X519765Y40328D03*
X523165D03*
X517896Y49193D03*
X524763Y49189D03*
X519743Y71436D03*
X523143D03*
X517907Y69507D03*
X524993D03*
X519743Y71436D03*
X523143D03*
X526460Y100895D03*
Y97495D03*
X517640Y97146D03*
X523831Y95445D03*
Y102931D03*
X516020Y102870D03*
X519240Y94967D03*
X526460Y100895D03*
Y97495D03*
X517640Y97146D03*
X521420Y109829D03*
X516020Y111770D03*
X524993Y125914D03*
X522418Y137171D03*
X526418D03*
X518418D03*
X522418Y153171D03*
X521618Y165428D03*
X519268Y167428D03*
X518691Y191846D03*
X519579Y207435D03*
X517314Y200449D03*
X517973Y211998D03*
X519248Y280721D03*
X516723D03*
X521773D03*
X520273Y289035D03*
X517748D03*
X522798D03*
X520273Y313200D03*
X517748D03*
X520273Y305145D03*
X517748D03*
X515523Y335613D03*
X529317Y403784D03*
X524680Y417602D03*
X522831Y443712D03*
X522326Y596021D03*
X529153Y598735D03*
X524805Y608436D03*
X522375D03*
X527235D03*
X529235Y601543D03*
X521651Y599178D03*
X525139Y600778D03*
X522401Y601746D03*
X516205Y608436D03*
X518635D03*
X526479Y620792D03*
Y623899D03*
X523879Y620792D03*
X521279D03*
X523879Y623899D03*
X521279D03*
X518679D03*
X516179D03*
X529079Y620792D03*
Y623899D03*
X523879Y617835D03*
X521279D03*
X527235Y614036D03*
X522375D03*
X524805D03*
X521771Y643138D03*
X528771D03*
X529962Y673428D03*
Y670928D03*
Y668428D03*
Y665928D03*
X516662Y673428D03*
Y670928D03*
Y668428D03*
Y665928D03*
X527462Y673428D03*
Y665928D03*
Y668428D03*
Y670928D03*
X516658Y663428D03*
X527458D03*
X529958D03*
X516658Y678460D03*
Y683460D03*
Y680960D03*
X527458Y678460D03*
X516658Y675960D03*
X527458D03*
X529958D03*
Y678460D03*
X526474Y851934D03*
Y849434D03*
X516572Y865327D03*
X517009Y856494D03*
X523074Y853439D03*
Y855939D03*
X528220Y1167366D03*
X517118D03*
X520818D03*
X517324Y1462595D03*
X524024Y1452895D03*
X520624D03*
X519924Y1462595D03*
X526624Y1452895D03*
X518024D03*
X519934Y1450295D03*
X524714D03*
X519934Y1455495D03*
X524714D03*
X518014Y1459995D03*
X517324Y1462595D03*
X524024Y1452895D03*
X520624D03*
X518014Y1465195D03*
X518569Y1544997D03*
X523293D03*
X518569Y1548397D03*
X523293D03*
Y1550797D03*
X518569Y1550897D03*
X528940Y1548260D03*
X518569Y1544997D03*
X523293D03*
X518569Y1548397D03*
X523293D03*
X528099Y1592380D03*
X524699D03*
X528877Y1589884D03*
Y1594876D03*
X516817Y1589884D03*
Y1594876D03*
X523921D03*
Y1589884D03*
X524699Y1592380D03*
X516039D03*
X528099D03*
X518669Y1602380D03*
X522069D03*
X530729D03*
Y1614292D03*
X518669D03*
X522069D03*
X529951Y1611796D03*
Y1599790D03*
Y1604876D03*
X517891Y1611796D03*
X522847D03*
Y1599884D03*
X517891D03*
X522847Y1604876D03*
X517891D03*
X518669Y1602380D03*
X522069D03*
X528099Y1624292D03*
X524699D03*
X529951Y1616788D03*
X528877Y1621796D03*
Y1626788D03*
X517891Y1616788D03*
X522847D03*
X523921Y1621796D03*
X516817D03*
X523921Y1626788D03*
X516817D03*
X524699Y1624292D03*
X516039D03*
X528099D03*
X518669Y1614292D03*
X522069D03*
X539120Y31340D03*
X540843Y23788D03*
X535117Y31340D03*
X533918Y47067D03*
X537318D03*
X542723Y39562D03*
X533918Y47067D03*
X537318D03*
X532070Y49193D03*
X539156D03*
X532080Y69507D03*
X539166D03*
X541003Y71436D03*
X544403D03*
X538210Y90618D03*
X540615Y88213D03*
X543277Y88632D03*
X538210Y90618D03*
X540615Y88213D03*
X538620Y93289D03*
X535170Y108730D03*
Y117630D03*
X530567Y125914D03*
X543408Y133912D03*
X538166Y130698D03*
X530418Y145171D03*
Y137171D03*
Y149171D03*
Y141171D03*
X541675Y146874D03*
Y151470D03*
Y142021D03*
Y137169D03*
X530418Y153171D03*
X541675Y156195D03*
X533442Y164428D03*
X531280Y210922D03*
X532222Y207849D03*
X541013Y222441D03*
X540695Y217874D03*
X537051Y211959D03*
X534277Y235560D03*
X533097Y246780D03*
X539217Y245270D03*
X538567Y294777D03*
X543780Y294168D03*
X541808Y289743D03*
X544628Y291633D03*
Y289133D03*
X542813Y319173D03*
X542983Y334531D03*
X533211Y350838D03*
X533543Y404130D03*
X530729Y398634D03*
X532000Y426500D03*
X543170Y434737D03*
X544844Y439701D03*
X543500Y463500D03*
X531753Y453232D03*
X540616Y463486D03*
X534471Y595987D03*
X538067Y592652D03*
X542071Y593089D03*
X535855Y612290D03*
X539657Y607658D03*
X534362Y601375D03*
X535855Y609749D03*
X532082Y604900D03*
X533857Y619615D03*
X534271Y643138D03*
X540106Y657325D03*
X534962Y670960D03*
Y665960D03*
Y668460D03*
X532462D03*
Y665960D03*
Y670960D03*
Y673460D03*
Y663460D03*
X534962D03*
Y673460D03*
Y675960D03*
X532462D03*
X531921Y1167366D03*
X537424Y1452895D03*
X534024D03*
X540024D03*
X531424D03*
X533334Y1450295D03*
X538114D03*
X533334Y1455495D03*
X538114D03*
X544814Y1459995D03*
X537424Y1452895D03*
X534024D03*
X544794Y1478082D03*
Y1480682D03*
Y1484082D03*
Y1494082D03*
Y1491482D03*
Y1486682D03*
X542194Y1479992D03*
Y1484772D03*
Y1493392D03*
X544794Y1480682D03*
Y1484082D03*
Y1497482D03*
Y1500082D03*
X537694Y1504872D03*
X542194Y1498172D03*
X544794Y1497482D03*
Y1494082D03*
X543947Y1516120D03*
Y1512220D03*
X543672Y1519845D03*
X540810Y1521436D03*
X533317Y1511953D03*
Y1514453D03*
Y1516953D03*
X531495Y1519250D03*
X537770Y1519845D03*
X537647Y1516120D03*
Y1512220D03*
X534002Y1521436D03*
X540797Y1516120D03*
Y1512220D03*
X540810Y1523953D03*
X543759Y1536882D03*
X540193Y1531073D03*
X537693D03*
X535193D03*
X541259Y1536882D03*
X543719Y1549295D03*
Y1546795D03*
X541219D03*
Y1549295D03*
X538719D03*
Y1546795D03*
X531339Y1546481D03*
X536759Y1592380D03*
X540159D03*
X540937Y1589884D03*
Y1594876D03*
X535981D03*
Y1589884D03*
X536759Y1592380D03*
X540159D03*
X542789Y1602380D03*
X534129D03*
X546189D03*
X542789Y1614292D03*
X546189D03*
X534129D03*
X542011Y1611796D03*
Y1599884D03*
Y1604876D03*
X534907Y1611796D03*
Y1599790D03*
Y1604876D03*
X530729Y1602380D03*
X542789D03*
X534129D03*
X536759Y1624292D03*
X540159D03*
X542011Y1616788D03*
X540937Y1621796D03*
Y1626788D03*
X534907Y1616788D03*
X535981Y1621796D03*
Y1626788D03*
X536759Y1624292D03*
X540159D03*
X530729Y1614292D03*
X542789D03*
X534129D03*
X532596Y1737117D03*
X553620Y31048D03*
X549919D03*
X554984Y45312D03*
X546350Y39562D03*
X548610Y57990D03*
X558576Y71436D03*
X555176D03*
X546253Y69507D03*
X553340D03*
X555176Y71436D03*
X558576D03*
X545935Y77516D03*
X553821D03*
X559069Y105385D03*
Y101985D03*
Y105385D03*
Y101985D03*
X552105Y112203D03*
X555505D03*
X553780Y121240D03*
X546400Y120700D03*
X553780Y118740D03*
X557091Y114382D03*
X550505D03*
X552105Y112203D03*
X555505D03*
X553780Y121240D03*
Y124640D03*
Y127140D03*
Y124640D03*
X549800Y147000D03*
X553300Y164500D03*
X556811Y152742D03*
X559484Y156667D03*
X553757Y160075D03*
X547196Y195256D03*
Y190256D03*
X550196D03*
X554196D03*
X553578Y193541D03*
X547196Y199256D03*
X550553Y200304D03*
Y197778D03*
X548963Y218441D03*
X553100Y227700D03*
X555567Y236970D03*
X549248Y234152D03*
X559774Y243176D03*
X546800Y262800D03*
X552699Y291833D03*
X557243Y294693D03*
X556323Y315273D03*
X558743Y313923D03*
X545873Y319173D03*
X549093Y319123D03*
X558003Y320563D03*
X554943D03*
X552153Y319123D03*
X554893Y317643D03*
X557953D03*
X551044Y373085D03*
X551200Y377650D03*
X550573Y399586D03*
Y403586D03*
Y414274D03*
X549854Y406298D03*
X547529Y425411D03*
X551591Y443665D03*
X548856Y440452D03*
X552510Y446490D03*
X547751Y472678D03*
X550925Y475178D03*
X553360Y477822D03*
X558379Y482096D03*
X556993Y616406D03*
X550993D03*
X553993D03*
X547993D03*
X549957Y658478D03*
Y661478D03*
X551171Y1167678D03*
X558690Y1226149D03*
X561586Y1462595D03*
X558986D03*
X545931Y1451344D03*
X559090Y1452185D03*
X558876Y1454905D03*
Y1458305D03*
X546253Y1454107D03*
Y1457507D03*
X555348Y1480190D03*
Y1477590D03*
Y1483590D03*
Y1486190D03*
X552748Y1484280D03*
Y1479500D03*
X557948Y1484280D03*
Y1479500D03*
X547394Y1479992D03*
Y1484772D03*
Y1493392D03*
X555348Y1483590D03*
Y1480190D03*
Y1501990D03*
Y1505390D03*
Y1499490D03*
X552748Y1506080D03*
Y1501300D03*
X557948Y1506080D03*
Y1501300D03*
X555348Y1507990D03*
X547394Y1498172D03*
X555348Y1501990D03*
Y1505390D03*
X556965Y1521561D03*
X548197Y1514641D03*
X550471Y1513584D03*
Y1511031D03*
X548197Y1512088D03*
X556642Y1529389D03*
X554715Y1531564D03*
X548119Y1530595D03*
X550619D03*
X550540Y1526910D03*
X556197Y1536687D03*
X554766Y1523331D03*
Y1526731D03*
X550939Y1536646D03*
X559215Y1530596D03*
X556197Y1539187D03*
X546219Y1549295D03*
Y1541795D03*
Y1546795D03*
Y1544295D03*
X548719Y1549295D03*
Y1546795D03*
Y1541795D03*
Y1544295D03*
X551219D03*
Y1541795D03*
X549674Y1538890D03*
X558089Y1541795D03*
Y1544295D03*
Y1546795D03*
Y1549295D03*
X555589Y1541795D03*
Y1549295D03*
Y1546795D03*
Y1544295D03*
X549759Y1551844D03*
X552177Y1551099D03*
X554682Y1551844D03*
X552177Y1548199D03*
X560879Y1592380D03*
X548819D03*
X552219D03*
X552997Y1589884D03*
X548041Y1594876D03*
X552997D03*
X548041Y1589884D03*
X548819Y1592380D03*
X552219D03*
X554849Y1602380D03*
X558249D03*
Y1614292D03*
X554849D03*
X559027Y1611796D03*
Y1599884D03*
Y1604876D03*
X546967Y1611796D03*
X554071D03*
Y1599884D03*
Y1604876D03*
X546967Y1599884D03*
Y1604876D03*
X554849Y1602380D03*
X546189D03*
X558249D03*
X560879Y1624292D03*
X548819D03*
X552219D03*
X559027Y1616788D03*
X546967D03*
X554071D03*
X552997Y1621796D03*
Y1626788D03*
X548041D03*
Y1621796D03*
X548819Y1624292D03*
X552219D03*
X554849Y1614292D03*
X546189D03*
X558249D03*
X554596Y1737117D03*
X562843Y23788D03*
X564431Y45132D03*
X564794Y58911D03*
X567997Y58992D03*
X573763Y58688D03*
X562331Y48438D03*
X560426Y69507D03*
X561248Y106985D03*
Y100399D03*
X570860Y121310D03*
Y118310D03*
Y121310D03*
Y124710D03*
X565210Y125819D03*
X570860Y127510D03*
Y124710D03*
X568472Y149226D03*
X563951Y157494D03*
X572003Y169415D03*
X564603Y197778D03*
Y200304D03*
X573911Y212196D03*
X568804Y221926D03*
X571427Y217771D03*
X569004Y228571D03*
X568736Y235821D03*
X562475Y242721D03*
X565093Y242640D03*
X567323Y300023D03*
X572447Y299470D03*
X561691Y315073D03*
X560643Y317683D03*
X568573Y321993D03*
X566148Y324502D03*
X567773Y316153D03*
X562208Y387227D03*
Y376427D03*
Y401158D03*
X568433Y415846D03*
X563230Y426508D03*
X568709Y434227D03*
X563575Y448425D03*
X569464Y462140D03*
X567297Y487551D03*
X560890Y484664D03*
X569923Y490726D03*
X559993Y616406D03*
X561346Y1228547D03*
X564669Y1238907D03*
X564283Y1231192D03*
X565537Y1235456D03*
X574200Y1229900D03*
X567127Y1249536D03*
X561580Y1242740D03*
X571271Y1259488D03*
X570775Y1263008D03*
X564986Y1462595D03*
X571686Y1452895D03*
X568286D03*
X567586Y1462595D03*
X574286Y1452895D03*
X565686D03*
X567596Y1450295D03*
X572376D03*
X567596Y1455495D03*
X572376D03*
X565676Y1459995D03*
X560896D03*
X564986Y1462595D03*
X571686Y1452895D03*
X561586Y1462595D03*
X568286Y1452895D03*
X565676Y1465195D03*
X560896D03*
X562860Y1499360D03*
X565723Y1510800D03*
Y1514420D03*
Y1518040D03*
X566215Y1528731D03*
X568779Y1546333D03*
X560589Y1541795D03*
Y1544295D03*
Y1546795D03*
Y1549295D03*
X563089Y1541795D03*
Y1549295D03*
Y1546795D03*
Y1544295D03*
X567214Y1544299D03*
X572939Y1592380D03*
X576339D03*
X564279D03*
X572161Y1594876D03*
X565057Y1589884D03*
X560101Y1594876D03*
X565057D03*
X572161Y1589884D03*
X560101D03*
X572939Y1592380D03*
X560879D03*
X564279D03*
X566909Y1602380D03*
X570309D03*
X566909Y1614292D03*
X570309D03*
X571087Y1611796D03*
Y1599884D03*
Y1604876D03*
X566131Y1611796D03*
Y1599884D03*
Y1604876D03*
X566909Y1602380D03*
X570309D03*
X572939Y1624292D03*
X576339D03*
X564279D03*
X571087Y1616788D03*
X572161Y1621796D03*
Y1626788D03*
X566131Y1616788D03*
X565057Y1621796D03*
X560101D03*
X565057Y1626788D03*
X560101D03*
X572939Y1624292D03*
X560879D03*
X564279D03*
X566909Y1614292D03*
X570309D03*
X584843Y23788D03*
X578621Y45112D03*
X576478Y58563D03*
X583685Y70678D03*
X586390Y69291D03*
X579561Y73090D03*
X585000Y82500D03*
X584752Y86248D03*
X578454Y88926D03*
X576510Y125819D03*
X580485Y133056D03*
Y130530D03*
X583485D03*
Y133056D03*
X581203Y164356D03*
X585685Y178125D03*
Y174975D03*
X581203Y169415D03*
X575425Y189835D03*
X582124Y194150D03*
X588244Y208991D03*
X575440Y200785D03*
X582002Y197481D03*
X588554Y221277D03*
X585296Y222954D03*
X577859Y212196D03*
X582766Y225496D03*
Y221421D03*
X588554Y217277D03*
Y225277D03*
X580343Y217771D03*
X588554Y229277D03*
X578172Y231393D03*
X582816Y228696D03*
X587140Y257630D03*
X575524Y261171D03*
X581099Y263680D03*
X586157Y366827D03*
X581985Y379577D03*
Y387227D03*
Y376427D03*
Y390377D03*
Y404308D03*
Y401158D03*
X588723Y415846D03*
Y423949D03*
X575917Y421390D03*
X588742Y431976D03*
X577845Y437151D03*
X587829Y445138D03*
X575345Y437151D03*
X580523Y435949D03*
X583505Y457925D03*
X575075Y451263D03*
X582390Y464701D03*
X587812Y474353D03*
X577801Y466000D03*
X587500Y470308D03*
X587795Y479631D03*
X586000Y808862D03*
X581421Y813078D03*
X588500Y812093D03*
X578830Y1218588D03*
X585501Y1229536D03*
X578830Y1238075D03*
X578071Y1244425D03*
X588630Y1255075D03*
X583630D03*
X588386Y1462595D03*
X585786D03*
X587696Y1459995D03*
X588386Y1462595D03*
X585086Y1472295D03*
X581686D03*
X587686D03*
X579086D03*
X587696Y1465195D03*
X580996Y1469695D03*
X585776D03*
X580996Y1474895D03*
X585776D03*
X585086Y1472295D03*
X581686D03*
X580489Y1544997D03*
X585213D03*
X580489Y1548397D03*
X585213D03*
X589938Y1544997D03*
Y1548397D03*
X575649Y1552567D03*
X585213Y1550797D03*
X580489D03*
Y1544997D03*
X585213D03*
X580489Y1548397D03*
X585213D03*
X588399Y1592380D03*
X584999D03*
X589177Y1589884D03*
Y1594876D03*
X577117Y1589884D03*
Y1594876D03*
X584221D03*
Y1589884D03*
X584999Y1592380D03*
X576339D03*
X588399D03*
X578969Y1602380D03*
X582369D03*
X591029D03*
Y1614292D03*
X578969D03*
X582369D03*
X578191Y1611796D03*
X583147D03*
Y1599884D03*
X578191D03*
X583147Y1604876D03*
X578191D03*
X578969Y1602380D03*
X582369D03*
X588399Y1624292D03*
X584999D03*
X589177Y1621796D03*
Y1626788D03*
X578191Y1616788D03*
X583147D03*
X584221Y1621796D03*
X577117D03*
X584221Y1626788D03*
X577117D03*
X584999Y1624292D03*
X576339D03*
X588399D03*
X578969Y1614292D03*
X582369D03*
X576596Y1737117D03*
X595682Y44842D03*
X603064Y44523D03*
X599284Y32866D03*
X593920Y49193D03*
X601073Y60301D03*
X603379Y70512D03*
X603350Y73642D03*
X591385Y109165D03*
X602328Y109062D03*
X603344Y139131D03*
X593975Y164440D03*
X598552Y159066D03*
X599678Y175534D03*
X600793Y193185D03*
X596661Y188775D03*
X590300Y190660D03*
X600161Y188776D03*
X593661D03*
X595563Y239128D03*
X603526Y229995D03*
X597050Y281950D03*
X595723Y289721D03*
X594698Y298035D03*
X597223D03*
X602223D03*
X603723Y289721D03*
X594698Y314145D03*
X597223D03*
X594698Y306090D03*
X597223D03*
X602223Y314145D03*
X597223Y322200D03*
X594698D03*
X602223D03*
X598414Y372357D03*
X598208Y387227D03*
Y376427D03*
X600520Y401728D03*
X603283Y419744D03*
X599884Y412000D03*
X599164Y432209D03*
X603326Y429530D03*
X590326Y445015D03*
X594430Y463600D03*
X592529Y461563D03*
X598496Y451421D03*
X602833Y791746D03*
X597071Y799268D03*
X592612Y805986D03*
X590710Y804192D03*
X603743Y794963D03*
X595619Y806084D03*
X600337Y800649D03*
X596821Y802688D03*
X592572Y809088D03*
X592761Y1220688D03*
X594330Y1238075D03*
X595671Y1245688D03*
X595598Y1251075D03*
X599659Y1241734D03*
X596621Y1240366D03*
X603947Y1258575D03*
X595947D03*
X595532Y1262668D03*
X594991Y1285582D03*
Y1289582D03*
X591786Y1462595D03*
X598486Y1452895D03*
X595086D03*
X594386Y1462595D03*
X592476Y1459995D03*
X594396Y1450295D03*
X599176D03*
X592486Y1452895D03*
X601086D03*
X594396Y1455495D03*
X599176D03*
X591786Y1462595D03*
X598486Y1452895D03*
X595086D03*
X592476Y1465195D03*
X594662Y1544997D03*
X599387D03*
X604111D03*
X594662Y1548397D03*
X599387D03*
X604111D03*
X599387Y1550897D03*
X604111D03*
X589938D03*
X594662Y1550697D03*
X589938Y1544997D03*
X594662D03*
X599387D03*
X604111D03*
X589938Y1548397D03*
X594662D03*
X599387D03*
X604111D03*
X597059Y1592380D03*
X600459D03*
X601237Y1589884D03*
Y1594876D03*
X596281D03*
Y1589884D03*
X597059Y1592380D03*
X600459D03*
X603089Y1602380D03*
X594429D03*
X606489D03*
X603089Y1614292D03*
X606489D03*
X594429D03*
X602311Y1611796D03*
Y1599884D03*
Y1604876D03*
X590251Y1611796D03*
X595207D03*
Y1599884D03*
X590251D03*
X595207Y1604876D03*
X590251D03*
X591029Y1602380D03*
X603089D03*
X594429D03*
X597059Y1624292D03*
X600459D03*
X602311Y1616788D03*
X601237Y1621796D03*
Y1626788D03*
X590251Y1616788D03*
X595207D03*
X596281Y1621796D03*
Y1626788D03*
X597059Y1624292D03*
X600459D03*
X591029Y1614292D03*
X603089D03*
X594429D03*
X598596Y1737117D03*
X606843Y23788D03*
X618427Y43432D03*
X613025Y42725D03*
X612608Y35961D03*
X618732Y39913D03*
X615180Y49193D03*
X606263Y60301D03*
X616815Y60277D03*
X611579D03*
X615190Y70533D03*
Y74533D03*
X615772Y106645D03*
X617420Y119640D03*
X619240Y123232D03*
X605853Y149640D03*
Y145640D03*
X618600Y160750D03*
X605853Y152140D03*
Y155131D03*
X613207Y182229D03*
X616357D03*
X607834Y222611D03*
X612414Y227041D03*
X604718Y257562D03*
X607868D03*
X618705Y285305D03*
X608773Y289721D03*
X609798Y298035D03*
X607273D03*
X606248Y289721D03*
X604748Y298035D03*
X609798Y314145D03*
X607273D03*
X604748D03*
X609798Y322200D03*
X607273D03*
X604748D03*
X615464Y347522D03*
X607871Y359262D03*
X611118Y359462D03*
X619035Y369542D03*
X617985Y379577D03*
Y387227D03*
Y376427D03*
Y398578D03*
Y390377D03*
X606032Y418968D03*
X610935Y409996D03*
X617985Y407346D03*
X617998Y415546D03*
X606811Y429528D03*
X605796Y425585D03*
X615075Y443000D03*
X612969Y447260D03*
X611925Y437000D03*
X605769Y442593D03*
X615903Y493474D03*
X608886Y494400D03*
X618957Y502306D03*
X616457D03*
X611896Y535178D03*
X613761Y790418D03*
X616171Y780364D03*
X618645Y783582D03*
X609402Y788678D03*
X615571Y788448D03*
X606559Y796116D03*
X612871Y1248488D03*
X612947Y1252075D03*
X609159Y1240234D03*
X608940Y1265991D03*
X610551Y1262988D03*
X612447Y1258575D03*
X605771Y1267098D03*
X618761Y1266988D03*
Y1278668D03*
X606619Y1278302D03*
X610551Y1269888D03*
X616037Y1367166D03*
X616654Y1382864D03*
X616615Y1386232D03*
X616629Y1375082D03*
X616527Y1390732D03*
X618586Y1462595D03*
X615186D03*
X619286Y1452895D03*
X612586Y1462595D03*
X614496Y1459995D03*
X619276D03*
X618586Y1462595D03*
X615186D03*
X611886Y1472295D03*
X608486D03*
X614486D03*
X605886D03*
X614496Y1465195D03*
X619276D03*
X612576Y1469695D03*
X607796D03*
X612576Y1474895D03*
X607796D03*
X611886Y1472295D03*
X608486D03*
X608836Y1544997D03*
X613560D03*
X618285D03*
X608836Y1548397D03*
X613560D03*
X618285D03*
X613560Y1550797D03*
X618285Y1550897D03*
X608836Y1550697D03*
Y1544997D03*
X613560D03*
X618285D03*
X608836Y1548397D03*
X613560D03*
X618285D03*
X621179Y1592380D03*
X609119D03*
X612519D03*
X613297Y1589884D03*
X608341Y1594876D03*
X613297D03*
X608341Y1589884D03*
X609119Y1592380D03*
X612519D03*
X615149Y1602380D03*
X618549D03*
Y1614292D03*
X615149D03*
X619327Y1611796D03*
Y1599884D03*
Y1604876D03*
X607267Y1611796D03*
X614371D03*
Y1599884D03*
Y1604876D03*
X607267Y1599884D03*
Y1604876D03*
X615149Y1602380D03*
X606489D03*
X618549D03*
X621179Y1624292D03*
X609119D03*
X612519D03*
X619327Y1616788D03*
X607267D03*
X614371D03*
X613297Y1621796D03*
X608341D03*
X613297Y1626788D03*
X608341D03*
X609119Y1624292D03*
X612519D03*
X615149Y1614292D03*
X606489D03*
X618549D03*
X613948Y1641600D03*
X628843Y23788D03*
X624937Y44019D03*
X620390Y36794D03*
X628410Y45381D03*
X624689Y58262D03*
X627496Y74977D03*
X628885Y127057D03*
X630810Y122089D03*
X625574Y150177D03*
X625532Y146982D03*
X625553Y152683D03*
X625755Y168917D03*
X626372Y193431D03*
X626824Y182080D03*
X623605Y219277D03*
X620455D03*
X623605Y228777D03*
X620455D03*
X631505Y284355D03*
X633805Y302289D03*
X626473Y305338D03*
X626388Y330536D03*
X631694Y341300D03*
X626555Y343929D03*
X624133Y346520D03*
X626596Y360196D03*
X624760Y424569D03*
X631075Y429888D03*
X632281Y441904D03*
X622174Y438925D03*
X622197Y436116D03*
X620800Y474700D03*
X621916Y465088D03*
X632996Y478309D03*
X632984Y471462D03*
X621309Y483346D03*
X630758Y505874D03*
X633406Y497964D03*
X624381Y503765D03*
X631510Y510613D03*
X624718Y553428D03*
X633882Y587488D03*
X634288Y766646D03*
X631557Y773359D03*
X631741Y770318D03*
X630477Y1350109D03*
Y1353109D03*
X632695Y1366157D03*
Y1372257D03*
Y1378257D03*
X625286Y1452895D03*
X621886D03*
X627886D03*
X621186Y1462595D03*
X625976Y1450295D03*
X621196D03*
X625976Y1455495D03*
X621196D03*
X625286Y1452895D03*
X621886D03*
X635286Y1472295D03*
X632686D03*
X627734Y1544997D03*
X632458D03*
X623009D03*
X627734Y1548397D03*
X632458D03*
X623009D03*
X632458Y1550897D03*
X623009D03*
X627734D03*
Y1544997D03*
X632458D03*
X623009D03*
X627734Y1548397D03*
X632458D03*
X623009D03*
X633239Y1592380D03*
X624579D03*
X632461Y1594876D03*
X625357Y1589884D03*
X620401Y1594876D03*
X625357D03*
X632461Y1589884D03*
X620401D03*
X621179Y1592380D03*
X633239D03*
X624579D03*
X627209Y1602380D03*
X630609D03*
X627209Y1614292D03*
X630609D03*
X631387Y1611796D03*
Y1599790D03*
Y1604876D03*
X626431Y1611796D03*
Y1599790D03*
Y1604876D03*
X627209Y1602380D03*
X630609D03*
X633239Y1624292D03*
X624579D03*
X631387Y1616788D03*
X632461Y1626788D03*
Y1621796D03*
X626431Y1616788D03*
X620401Y1621796D03*
X625357D03*
X620401Y1626788D03*
X625357D03*
X621179Y1624292D03*
X633239D03*
X624579D03*
X627209Y1614292D03*
X630609D03*
X627958Y1654114D03*
X629808Y1668863D03*
X631643Y1670946D03*
X620596Y1737117D03*
X644963Y29143D03*
X648487Y44106D03*
X638490Y33340D03*
X645151Y69507D03*
X640670Y74369D03*
X644202Y84604D03*
X643800Y166053D03*
X641111Y158300D03*
X641006Y161829D03*
X643800Y161862D03*
X640923Y169388D03*
X642481Y184862D03*
X641276Y187557D03*
X643012Y201913D03*
Y199313D03*
X637804Y235371D03*
X640804D03*
X637804Y239371D03*
X640804D03*
X640084Y227113D03*
X637804Y243371D03*
X640804D03*
X646285Y297171D03*
X642171Y311280D03*
X641013Y324459D03*
X640922Y360342D03*
X639000Y364862D03*
X642128Y363279D03*
X636579Y366941D03*
X640317Y391085D03*
X640784Y395957D03*
X634566Y407848D03*
X635200Y415425D03*
X637160Y405449D03*
X635243Y433518D03*
X637432Y428935D03*
X642406Y427614D03*
X644673Y425816D03*
X639211Y433862D03*
Y438191D03*
X635449Y449797D03*
X639002Y449862D03*
X639500Y442362D03*
X637504Y454352D03*
X639313Y452361D03*
X635690Y461441D03*
X635640Y464257D03*
X647576Y497964D03*
X643053Y502891D03*
X635906Y497964D03*
X636614Y512597D03*
X642310Y535773D03*
X639757Y533440D03*
X636055Y528605D03*
X642816Y574185D03*
X639482Y587488D03*
X645446Y587300D03*
X634529Y674890D03*
X640129D03*
X643649Y674781D03*
X646446Y674643D03*
X642854Y760178D03*
Y756832D03*
X647354Y776911D03*
X640271Y763488D03*
X636551Y767900D03*
X642804Y763525D03*
X636247Y771179D03*
X647354Y783604D03*
Y807029D03*
Y813722D03*
Y820415D03*
Y843840D03*
Y850533D03*
Y857226D03*
Y880651D03*
Y887344D03*
Y894037D03*
Y917462D03*
Y924155D03*
Y930848D03*
Y954273D03*
Y960966D03*
Y967659D03*
Y974352D03*
Y981045D03*
Y987737D03*
Y994430D03*
Y1004470D03*
Y1034588D03*
Y1041281D03*
Y1047974D03*
Y1054667D03*
Y1061360D03*
Y1071399D03*
Y1078092D03*
Y1101517D03*
Y1108210D03*
Y1114903D03*
Y1138328D03*
Y1145021D03*
Y1151714D03*
Y1175139D03*
Y1181832D03*
Y1188525D03*
Y1211950D03*
Y1218643D03*
Y1225336D03*
Y1248761D03*
Y1255454D03*
X635092Y1277102D03*
X642436Y1350877D03*
X646236D03*
X638436D03*
X638695Y1366157D03*
X644795D03*
X643395Y1372857D03*
X638695Y1378257D03*
X644795D03*
X634995Y1384457D03*
X647401Y1384160D03*
X643563Y1392581D03*
X647445Y1392605D03*
X645386Y1462595D03*
X641986D03*
X648686Y1452895D03*
X647986Y1462595D03*
X646086Y1452895D03*
X639386Y1462595D03*
X647996Y1450295D03*
Y1455495D03*
X641296Y1459995D03*
X646076D03*
X645386Y1462595D03*
X641986D03*
X648686Y1452895D03*
X638686Y1472295D03*
X641286D03*
X641296Y1465195D03*
X646076D03*
X639376Y1469695D03*
X634596D03*
X639376Y1474895D03*
X634596D03*
X638686Y1472295D03*
X635286D03*
X637182Y1544997D03*
X641906D03*
X646631D03*
X637182Y1548397D03*
X641906D03*
X646631D03*
X651355Y1544997D03*
Y1548397D03*
X646631Y1550897D03*
X637182Y1550697D03*
X641906Y1550897D03*
X637182Y1544997D03*
X641906D03*
X646631D03*
X637182Y1548397D03*
X641906D03*
X646631D03*
X639907Y1570443D03*
X639132Y1573127D03*
X636639Y1592380D03*
X637417Y1589884D03*
Y1594876D03*
X636639Y1592380D03*
X645180Y1597800D03*
X645190Y1595050D03*
X639269Y1602380D03*
X642669D03*
X639269Y1614292D03*
X642669D03*
X643447Y1599884D03*
X638491D03*
X643447Y1604876D03*
X638491D03*
X643447Y1611796D03*
X638491D03*
X639269Y1602380D03*
X642669D03*
X636639Y1624292D03*
X643447Y1616788D03*
X637417Y1626788D03*
X638491Y1616788D03*
X637417Y1621796D03*
X636639Y1624292D03*
X639269Y1614292D03*
X642669D03*
X649153Y1625726D03*
X649297Y1623185D03*
X640520Y1635483D03*
X640242Y1639951D03*
X647630Y1641522D03*
X643128Y1639803D03*
X649266Y1650126D03*
X642151Y1649961D03*
X643074Y1668505D03*
X647574D03*
X639284Y1683049D03*
X647500Y1682850D03*
Y1674805D03*
X640600D03*
X643300D03*
X639391Y1700695D03*
X640690Y1703547D03*
X635210Y1721545D03*
Y1718395D03*
X641825Y1730516D03*
X640865Y1719684D03*
X642596Y1737117D03*
X650843Y23788D03*
X649585Y29298D03*
X657921Y30864D03*
X663703Y32574D03*
X653570Y58363D03*
X654590Y49193D03*
X661676D03*
X660928Y60707D03*
X651014Y60820D03*
X656600Y60537D03*
X656501Y69662D03*
X656427Y75431D03*
X660775Y78330D03*
X653821Y90326D03*
X654037Y93241D03*
X651950Y99890D03*
X658949Y139840D03*
X662881Y149912D03*
Y146912D03*
X649441Y177003D03*
X653700Y179962D03*
X659881Y208262D03*
Y205762D03*
Y210762D03*
X662781Y207862D03*
Y205362D03*
Y210362D03*
X659918Y326503D03*
X661019Y344831D03*
X663551Y346035D03*
X662740Y375240D03*
X649500Y373500D03*
Y382500D03*
X652425Y385924D03*
X659095Y381020D03*
X649495Y385118D03*
X659354Y393938D03*
X661297Y409857D03*
X662016Y417897D03*
X660885Y412588D03*
X652027Y415930D03*
X654273Y419251D03*
X654248Y422500D03*
X657535Y422694D03*
X651432Y433532D03*
X662000Y429844D03*
X653013Y443200D03*
X664170Y445711D03*
X651384Y445252D03*
X661546Y444497D03*
X662000Y449862D03*
X654441Y449618D03*
X662000Y437844D03*
X653449Y458542D03*
X662570Y461547D03*
Y457755D03*
X662000Y473862D03*
X650268Y479141D03*
X651072Y465939D03*
X654000Y465824D03*
X654014Y473862D03*
X662000Y465862D03*
X651114Y473884D03*
X662000Y469862D03*
X653266Y479106D03*
X663374Y484295D03*
X652380Y482390D03*
X657520Y486330D03*
X649500Y490260D03*
X658758Y497964D03*
X655917D03*
X649771Y505736D03*
X661718Y498056D03*
X651406Y501178D03*
X650404Y496102D03*
X652576Y497964D03*
X659398Y516260D03*
X659425Y521075D03*
X649922Y545610D03*
X655967Y544375D03*
X658642Y573893D03*
X649936Y574185D03*
X661718Y579932D03*
X653368Y581468D03*
X655572Y572603D03*
X656832Y577205D03*
X662992Y598660D03*
X651046Y587300D03*
X658613Y599534D03*
X660062Y672761D03*
X654676Y674806D03*
X662628Y674761D03*
X657428D03*
X663580Y731509D03*
X658946Y756766D03*
X651904D03*
Y760266D03*
X663496Y773564D03*
X658946Y763766D03*
X651904Y767266D03*
X658947Y767300D03*
Y771100D03*
X651905Y763766D03*
X652804Y790297D03*
X658046Y786950D03*
X663496Y780257D03*
X651754Y795316D03*
X652804Y800336D03*
X658046Y796989D03*
X663496Y803682D03*
Y810375D03*
Y817068D03*
X651754Y832127D03*
X652804Y837147D03*
Y827108D03*
X658046Y833800D03*
Y823761D03*
X663496Y840493D03*
Y847186D03*
X652804Y863919D03*
X658046Y860572D03*
X663496Y853879D03*
X651754Y868938D03*
X652804Y873958D03*
X658046Y870611D03*
X663496Y877304D03*
Y883997D03*
Y890690D03*
X651754Y905750D03*
X652804Y900730D03*
Y910769D03*
X658046Y897383D03*
Y907423D03*
X663496Y914115D03*
Y920808D03*
X652804Y937541D03*
X658046Y934194D03*
X663496Y927501D03*
X651754Y942561D03*
X652804Y947580D03*
X658046Y944234D03*
X663496Y950926D03*
Y957619D03*
Y964312D03*
Y971005D03*
Y960966D03*
X657996D03*
X663496Y977698D03*
Y984391D03*
Y991084D03*
Y997777D03*
Y1004470D03*
Y1031241D03*
Y1037934D03*
Y1044627D03*
Y1051320D03*
Y1058013D03*
Y1068052D03*
Y1074745D03*
X651754Y1089805D03*
X652804Y1084785D03*
X658046Y1081438D03*
X652804Y1094824D03*
X658046Y1091478D03*
X663496Y1098171D03*
Y1104863D03*
X658046Y1118249D03*
X663496Y1111556D03*
X651754Y1126616D03*
X652804Y1121596D03*
Y1131635D03*
X658046Y1128289D03*
X663496Y1134982D03*
Y1141675D03*
Y1148367D03*
X651754Y1163427D03*
X652804Y1158407D03*
X658046Y1155060D03*
Y1165100D03*
X652804Y1168446D03*
X663496Y1171793D03*
Y1178486D03*
X658046Y1191871D03*
X663496Y1185178D03*
X651754Y1200238D03*
X652804Y1205257D03*
Y1195218D03*
X658046Y1201911D03*
X663496Y1208604D03*
Y1215297D03*
Y1221989D03*
X651754Y1237049D03*
X652804Y1232029D03*
X658046Y1238722D03*
Y1228682D03*
X652804Y1242068D03*
X663496Y1245415D03*
Y1252108D03*
X662600Y1311502D03*
Y1308502D03*
X657836Y1350877D03*
X653836D03*
X650036D03*
X661685Y1367283D03*
X661713Y1373981D03*
X661719Y1363394D03*
X651973Y1363038D03*
X653149Y1372500D03*
X661813Y1370081D03*
X653117Y1378037D03*
X655702Y1391107D03*
X659559Y1391027D03*
X651877Y1391074D03*
X653999Y1426757D03*
Y1423357D03*
Y1426757D03*
Y1423357D03*
X655873Y1428844D03*
X652189Y1421276D03*
X652086Y1452895D03*
X662086D03*
X665486D03*
X654686D03*
X659486D03*
X661396Y1450295D03*
X652776D03*
X661396Y1455495D03*
X652776D03*
X652086Y1452895D03*
X662086D03*
X663160Y1511734D03*
Y1516734D03*
Y1519234D03*
Y1521734D03*
X660660Y1519234D03*
X663160Y1524234D03*
X662374Y1548563D03*
X654005Y1548999D03*
X651355Y1550797D03*
Y1544997D03*
Y1548397D03*
X660953Y1539998D03*
X663133Y1543744D03*
Y1541244D03*
Y1538744D03*
X660953Y1542498D03*
X659532Y1546519D03*
X651840Y1567752D03*
X664246Y1561009D03*
X661731Y1561083D03*
X661156Y1626532D03*
X650966Y1618934D03*
X651870Y1612986D03*
X650753Y1615912D03*
X660542Y1638169D03*
X657392Y1628137D03*
X652274Y1630366D03*
X650895Y1648115D03*
X660058Y1648889D03*
X654712Y1653813D03*
X664315Y1654484D03*
X655914Y1668744D03*
X650074Y1668505D03*
X658648Y1664169D03*
X655683Y1664212D03*
X653154Y1683265D03*
X664159Y1674844D03*
X661528Y1674865D03*
X650200Y1674805D03*
X659436Y1694697D03*
X658491Y1688965D03*
X649464Y1691180D03*
X649526Y1709274D03*
X663997Y1703111D03*
X659557Y1714672D03*
X658759Y1707147D03*
X659028Y1710047D03*
X662153Y1727718D03*
X659673Y1722174D03*
X661845Y1717340D03*
X654508Y1728000D03*
X654527Y1718229D03*
X659673Y1732836D03*
X672843Y23788D03*
X670613Y42464D03*
X674013D03*
X668739Y45262D03*
X677594Y36205D03*
X675887Y45262D03*
X677476Y33317D03*
X666506Y32750D03*
X677305Y57947D03*
X675849Y49193D03*
X668763D03*
X665469Y58525D03*
X666411Y69507D03*
X678664Y88080D03*
X673751Y78092D03*
X675509Y88173D03*
X677561Y118409D03*
X677738Y115428D03*
X665651Y147692D03*
X673011Y169021D03*
X673691Y200672D03*
X673301Y211332D03*
X679035Y204181D03*
X678226Y215771D03*
X674348Y218580D03*
X666552Y346115D03*
X677111Y345662D03*
X672111D03*
X674611D03*
X676800Y369362D03*
X672800D03*
Y382362D03*
X671753Y397936D03*
X671500Y390862D03*
X675500Y398862D03*
Y390862D03*
X670018Y418690D03*
X669929Y407999D03*
X666000Y433862D03*
Y425862D03*
X670000Y429864D03*
Y433844D03*
Y425894D03*
X666000Y437844D03*
X670000Y442362D03*
Y437844D03*
X666000Y442362D03*
X670000Y446362D03*
X679062Y455140D03*
X670000Y457844D03*
X666000Y453844D03*
Y457862D03*
X670000Y453844D03*
X666000Y461862D03*
X664634Y449952D03*
X670000Y469824D03*
Y465844D03*
Y477862D03*
Y482862D03*
X669955Y495468D03*
X672699Y506907D03*
X664741Y506865D03*
X671500Y529500D03*
X665425Y537000D03*
X664454Y574896D03*
X665774Y571762D03*
X666192Y598660D03*
X679047Y678733D03*
X673287Y733156D03*
X674123Y736083D03*
X667101Y736071D03*
X667996Y756832D03*
X672555D03*
Y760178D03*
X677055Y776911D03*
X668046Y766871D03*
X667996Y763525D03*
X672505D03*
X668046Y770218D03*
X677055Y780257D03*
Y786950D03*
Y793643D03*
X667896Y791970D03*
X677055Y783604D03*
Y780257D03*
Y786950D03*
Y803682D03*
Y796989D03*
Y807029D03*
Y803682D03*
Y793643D03*
Y796989D03*
Y817068D03*
Y810375D03*
Y823761D03*
Y813722D03*
Y820415D03*
Y817068D03*
Y810375D03*
Y830454D03*
Y833800D03*
X667896Y828781D03*
X677055Y823761D03*
Y830454D03*
Y833800D03*
Y840493D03*
Y847186D03*
Y853879D03*
Y843840D03*
Y850533D03*
Y840493D03*
Y847186D03*
Y860572D03*
Y867265D03*
X667896Y865592D03*
X677055Y857226D03*
Y853879D03*
Y860572D03*
Y877304D03*
Y870611D03*
Y883997D03*
Y880651D03*
Y877304D03*
Y867265D03*
Y870611D03*
Y890690D03*
Y897383D03*
Y887344D03*
Y894037D03*
Y883997D03*
Y890690D03*
Y904076D03*
Y907423D03*
X667896Y902403D03*
X677055Y897383D03*
Y904076D03*
Y907423D03*
Y914115D03*
Y920808D03*
Y927501D03*
Y917462D03*
Y924155D03*
Y914115D03*
Y920808D03*
Y934194D03*
Y940887D03*
X667896Y939214D03*
X677055Y930848D03*
Y927501D03*
Y934194D03*
Y940887D03*
Y950926D03*
Y944234D03*
Y957619D03*
Y954273D03*
Y950926D03*
Y944234D03*
Y964312D03*
Y971005D03*
Y960966D03*
Y967659D03*
Y964312D03*
Y957619D03*
Y971005D03*
Y977698D03*
Y984391D03*
Y974352D03*
Y981045D03*
Y977698D03*
Y984391D03*
Y1001123D03*
Y997777D03*
Y991084D03*
Y987737D03*
Y994430D03*
Y1001123D03*
Y997777D03*
Y991084D03*
Y1004470D03*
Y1031241D03*
Y1037934D03*
Y1044627D03*
Y1034588D03*
Y1041281D03*
Y1031241D03*
Y1037934D03*
Y1044627D03*
Y1058013D03*
Y1051320D03*
Y1047974D03*
Y1054667D03*
Y1058013D03*
Y1051320D03*
Y1074745D03*
Y1061360D03*
Y1071399D03*
Y1074745D03*
Y1068052D03*
Y1064706D03*
Y1081438D03*
Y1088131D03*
Y1091478D03*
X667896Y1086458D03*
X677055Y1078092D03*
Y1081438D03*
Y1088131D03*
Y1098171D03*
Y1104863D03*
Y1101517D03*
Y1098171D03*
Y1104863D03*
Y1091478D03*
Y1111556D03*
Y1118249D03*
Y1108210D03*
Y1114903D03*
Y1111556D03*
Y1118249D03*
Y1134982D03*
Y1124942D03*
Y1128289D03*
X667896Y1123269D03*
X677055Y1134982D03*
Y1124942D03*
Y1128289D03*
Y1148367D03*
Y1141675D03*
Y1138328D03*
Y1145021D03*
Y1148367D03*
Y1141675D03*
Y1155060D03*
Y1161753D03*
Y1165100D03*
X667896Y1160080D03*
X677055Y1151714D03*
Y1155060D03*
Y1161753D03*
Y1165100D03*
Y1171793D03*
Y1178486D03*
Y1175139D03*
Y1171793D03*
Y1178486D03*
Y1185178D03*
Y1191871D03*
Y1181832D03*
Y1188525D03*
Y1185178D03*
Y1191871D03*
Y1208604D03*
Y1198564D03*
Y1201911D03*
X667896Y1196891D03*
X677055Y1208604D03*
Y1198564D03*
Y1201911D03*
Y1215297D03*
Y1221989D03*
Y1211950D03*
Y1218643D03*
Y1215297D03*
Y1221989D03*
Y1228682D03*
Y1235375D03*
Y1238722D03*
X667896Y1233702D03*
X677055Y1225336D03*
Y1228682D03*
Y1235375D03*
Y1238722D03*
Y1245415D03*
Y1252108D03*
Y1248761D03*
Y1245415D03*
Y1252108D03*
Y1255454D03*
X674552Y1342488D03*
Y1351988D03*
Y1349488D03*
Y1344988D03*
X665167Y1380836D03*
Y1376836D03*
X673671Y1431922D03*
X675272Y1434525D03*
X668086Y1452895D03*
X666176Y1450295D03*
Y1455495D03*
X665486Y1452895D03*
X672856Y1478082D03*
Y1484082D03*
Y1480682D03*
Y1494082D03*
Y1486682D03*
Y1491482D03*
X675112Y1479602D03*
X675456Y1484772D03*
Y1493392D03*
X670256Y1479992D03*
Y1484772D03*
Y1493392D03*
X672856Y1484082D03*
Y1480682D03*
Y1497482D03*
Y1500082D03*
X665756Y1504872D03*
X675456Y1498172D03*
X670256D03*
X666050Y1501670D03*
X672856Y1497482D03*
Y1494082D03*
X678386Y1507965D03*
X672684Y1522690D03*
X674687Y1519726D03*
X677871Y1522079D03*
X678345Y1516994D03*
X677871Y1519579D03*
X673174Y1515806D03*
X675505Y1512606D03*
X678339Y1510960D03*
X665800Y1530575D03*
X674620Y1535271D03*
X677871Y1524579D03*
X678121Y1528516D03*
X665832Y1527425D03*
X672715Y1526626D03*
Y1530526D03*
X674620Y1542125D03*
X672617Y1545089D03*
Y1538235D03*
X678350Y1567400D03*
X669524Y1560850D03*
X672163Y1560899D03*
X673729Y1556768D03*
X666978Y1560945D03*
X672810Y1571560D03*
X666610Y1571580D03*
X668133Y1625828D03*
X670839Y1620863D03*
X674894Y1629042D03*
X673982Y1639289D03*
X673960Y1633042D03*
X669648Y1640917D03*
X665802Y1652337D03*
X674486Y1647842D03*
X670803Y1654606D03*
X671068Y1650818D03*
X674908Y1644481D03*
X673548Y1669550D03*
X678117Y1662787D03*
X675497Y1687253D03*
X673359Y1674409D03*
X671001Y1696017D03*
X671798Y1704542D03*
X673113Y1716599D03*
X668058Y1720092D03*
X673113Y1727261D03*
X664596Y1737117D03*
X693672Y32684D03*
X686855Y43701D03*
X690476Y32684D03*
X692466Y35950D03*
X679719Y59066D03*
X687018Y58357D03*
X683369Y58157D03*
X692390Y72692D03*
X687665Y73202D03*
X685781Y70022D03*
X682946Y69982D03*
X682891Y72642D03*
X688552Y79166D03*
X681895Y82212D03*
X685783Y78768D03*
X680580Y79230D03*
X684954Y104968D03*
X681054Y104668D03*
X687000Y119500D03*
X691058Y131408D03*
X685500Y124000D03*
X684521Y152482D03*
X688521D03*
X692521D03*
X679316Y209861D03*
X680576Y207105D03*
X681333Y212326D03*
X679737Y217763D03*
X682264Y224116D03*
X693621Y346169D03*
X680828Y363500D03*
X684800Y369362D03*
X680800D03*
X691484Y360643D03*
X691500Y382462D03*
X691547Y386834D03*
X687500Y390680D03*
X683500Y390862D03*
X679500D03*
X688249Y405628D03*
X679862Y409320D03*
X687612Y471850D03*
X691572Y465214D03*
X684800Y477862D03*
X687472Y486994D03*
X684680Y485942D03*
X684800Y481862D03*
X680187Y491243D03*
X682915Y500568D03*
X683000Y521500D03*
X694111Y537881D03*
X679500Y526834D03*
X691496Y575081D03*
X689574Y572866D03*
X681352Y681305D03*
X688078Y675493D03*
X691417Y680382D03*
X685786Y680936D03*
X686509Y677440D03*
X681605Y756766D03*
X681671Y760178D03*
X688647Y756766D03*
X693197Y776911D03*
Y773564D03*
X688647Y763766D03*
X681605Y767266D03*
X688648Y767300D03*
Y771100D03*
X693197Y776911D03*
X681606Y763766D03*
X693197Y783604D03*
Y790297D03*
Y793643D03*
X682505Y790297D03*
X687747Y786950D03*
X693197Y780257D03*
Y783604D03*
Y790297D03*
Y800336D03*
Y807029D03*
X681455Y795316D03*
X682505Y800336D03*
X687747Y796989D03*
X693197Y803682D03*
Y800336D03*
Y807029D03*
Y793643D03*
Y813722D03*
Y820415D03*
Y810375D03*
Y817068D03*
Y813722D03*
Y820415D03*
Y837147D03*
Y830454D03*
Y827108D03*
X681455Y832127D03*
X682505Y837147D03*
Y827108D03*
X687747Y833800D03*
Y823761D03*
X693197Y837147D03*
Y830454D03*
Y827108D03*
Y843840D03*
Y850533D03*
Y840493D03*
Y847186D03*
Y843840D03*
Y850533D03*
Y857226D03*
Y863919D03*
Y867265D03*
X682505Y863919D03*
X687747Y860572D03*
X693197Y853879D03*
Y857226D03*
Y863919D03*
Y873958D03*
Y880651D03*
X681455Y868938D03*
X682505Y873958D03*
X687747Y870611D03*
X693197Y877304D03*
Y873958D03*
Y880651D03*
Y867265D03*
Y887344D03*
Y894037D03*
Y883997D03*
Y890690D03*
Y887344D03*
Y894037D03*
Y910769D03*
Y904076D03*
Y900730D03*
X681455Y905750D03*
X682505Y900730D03*
Y910769D03*
X687747Y897383D03*
Y907423D03*
X693197Y910769D03*
Y904076D03*
Y900730D03*
Y924155D03*
Y917462D03*
Y914115D03*
Y920808D03*
Y924155D03*
Y917462D03*
Y930848D03*
Y940887D03*
Y937541D03*
X682505D03*
X687747Y934194D03*
X693197Y927501D03*
Y930848D03*
Y940887D03*
Y937541D03*
Y947580D03*
Y954273D03*
X681455Y942561D03*
X682505Y947580D03*
X687747Y944234D03*
X693197Y950926D03*
Y947580D03*
Y954273D03*
Y967659D03*
X687697Y960966D03*
X693197Y957619D03*
Y964312D03*
Y971005D03*
Y960966D03*
X687697D03*
X693197Y967659D03*
Y974352D03*
Y981045D03*
Y987737D03*
Y977698D03*
Y984391D03*
Y974352D03*
Y981045D03*
Y994430D03*
Y1001123D03*
Y991084D03*
Y997777D03*
Y987737D03*
Y994430D03*
Y1001123D03*
Y1004470D03*
Y1027895D03*
D03*
Y1034588D03*
Y1041281D03*
Y1047974D03*
Y1031241D03*
Y1037934D03*
Y1044627D03*
Y1034588D03*
Y1041281D03*
Y1054667D03*
Y1061360D03*
Y1051320D03*
Y1058013D03*
Y1047974D03*
Y1054667D03*
Y1071399D03*
Y1064706D03*
Y1068052D03*
Y1074745D03*
Y1061360D03*
Y1071399D03*
Y1064706D03*
Y1078092D03*
Y1088131D03*
Y1084785D03*
X681455Y1089805D03*
X682505Y1084785D03*
X687747Y1081438D03*
X693197Y1078092D03*
Y1088131D03*
Y1084785D03*
Y1094824D03*
Y1101517D03*
X682505Y1094824D03*
X687747Y1091478D03*
X693197Y1098171D03*
Y1104863D03*
Y1094824D03*
Y1101517D03*
Y1108210D03*
Y1114903D03*
Y1121596D03*
X687747Y1118249D03*
X693197Y1111556D03*
Y1108210D03*
Y1114903D03*
Y1131635D03*
Y1124942D03*
X681455Y1126616D03*
X682505Y1121596D03*
Y1131635D03*
X687747Y1128289D03*
X693197Y1134982D03*
Y1131635D03*
Y1124942D03*
Y1121596D03*
Y1138328D03*
Y1145021D03*
Y1151714D03*
Y1141675D03*
Y1148367D03*
Y1138328D03*
Y1145021D03*
Y1161753D03*
Y1158407D03*
X681455Y1163427D03*
X682505Y1158407D03*
X687747Y1155060D03*
Y1165100D03*
X693197Y1151714D03*
Y1161753D03*
Y1158407D03*
Y1168446D03*
Y1175139D03*
Y1181832D03*
X682505Y1168446D03*
X693197Y1171793D03*
Y1178486D03*
Y1168446D03*
Y1175139D03*
Y1188525D03*
Y1195218D03*
X687747Y1191871D03*
X693197Y1185178D03*
Y1181832D03*
Y1188525D03*
Y1205257D03*
Y1198564D03*
Y1211950D03*
X681455Y1200238D03*
X682505Y1205257D03*
Y1195218D03*
X687747Y1201911D03*
X693197Y1208604D03*
Y1205257D03*
Y1198564D03*
Y1195218D03*
Y1218643D03*
Y1225336D03*
Y1215297D03*
Y1221989D03*
Y1211950D03*
Y1218643D03*
Y1235375D03*
Y1232029D03*
X681455Y1237049D03*
X682505Y1232029D03*
X687747Y1238722D03*
Y1228682D03*
X693197Y1225336D03*
Y1235375D03*
Y1232029D03*
Y1242068D03*
Y1248761D03*
X682505Y1242068D03*
X693197Y1245415D03*
Y1252108D03*
Y1242068D03*
Y1248761D03*
X688076Y1297506D03*
Y1305206D03*
Y1300006D03*
Y1302606D03*
X687961Y1314308D03*
Y1320308D03*
Y1323308D03*
Y1317308D03*
X684868Y1327117D03*
X682348D03*
Y1339617D03*
X683052Y1342548D03*
X684868Y1329617D03*
X682348D03*
X684868Y1332117D03*
X682348D03*
X684868Y1334617D03*
X682348D03*
X684868Y1337117D03*
Y1339617D03*
X682348Y1337117D03*
X683052Y1352048D03*
Y1349548D03*
Y1345048D03*
X685187Y1368700D03*
Y1363500D03*
Y1366100D03*
X681289Y1418291D03*
X687577Y1425054D03*
X683391Y1420531D03*
X685448Y1423137D03*
X691587Y1429515D03*
X689538Y1427467D03*
X692376Y1438326D03*
X691943Y1441626D03*
X691276Y1455112D03*
X694676D03*
X691276D03*
X688540Y1455140D03*
X687040Y1452300D03*
X684280Y1452260D03*
X684603Y1507851D03*
X681517Y1508034D03*
X687529Y1508173D03*
X690683Y1508058D03*
X693395D03*
X688120Y1519601D03*
X680710Y1520284D03*
X683674Y1522287D03*
X693532Y1510755D03*
X690820D03*
X687666Y1510870D03*
X687711Y1513612D03*
X690751Y1513750D03*
X693655Y1513818D03*
X693587Y1516470D03*
X690752Y1516516D03*
X683666Y1515189D03*
X680717Y1513292D03*
X684557Y1510685D03*
X681563Y1510708D03*
X683352Y1530526D03*
Y1526526D03*
X682016Y1539067D03*
X679854Y1551492D03*
X679413Y1548843D03*
X680107Y1554330D03*
X681780Y1574280D03*
X684080Y1576500D03*
X686949Y1625144D03*
X689897Y1621781D03*
X691036Y1625508D03*
X686994Y1629077D03*
X688308Y1631636D03*
X693150Y1640773D03*
X693451Y1628733D03*
X683067Y1641758D03*
X682925Y1657116D03*
X686825Y1647430D03*
X686075Y1657082D03*
X679413Y1653251D03*
X685719Y1672391D03*
X685747Y1669303D03*
X693608Y1671081D03*
X685485Y1682259D03*
X685635Y1675310D03*
X691560Y1682047D03*
X693480Y1673940D03*
X692390Y1687594D03*
X694843Y23788D03*
X701839Y45112D03*
X697893Y35950D03*
X702481Y48327D03*
X698462Y60683D03*
X695220Y60455D03*
X701081Y72450D03*
X694752Y70212D03*
X707608Y69718D03*
X696701Y72462D03*
X698711Y86035D03*
X696371Y78512D03*
X696728Y81552D03*
Y84052D03*
X706721Y100462D03*
X702721Y102162D03*
X701221Y104862D03*
X697721D03*
X695721Y102162D03*
X694221Y104862D03*
X699221Y102162D03*
X698599Y115178D03*
X705686D03*
X702142D03*
X698599Y112678D03*
X705686D03*
X702142D03*
X695056D03*
Y115178D03*
X705570Y133760D03*
X704144Y122602D03*
X707243Y123946D03*
X701927Y166535D03*
X704771Y179599D03*
Y182999D03*
X701927Y172441D03*
Y178346D03*
X704771Y179599D03*
Y171188D03*
Y167788D03*
Y194810D03*
Y191410D03*
X701927Y184252D03*
Y196063D03*
Y190157D03*
X704771Y182999D03*
Y194810D03*
Y191410D03*
Y206621D03*
Y203221D03*
X701927Y201968D03*
Y207874D03*
X704771Y206621D03*
Y203221D03*
Y218432D03*
Y215032D03*
X701927Y213779D03*
Y219685D03*
X704771Y218432D03*
Y215032D03*
X703486Y345507D03*
X699813Y344798D03*
X697400Y345761D03*
X706139Y345597D03*
X695500Y374362D03*
X699500D03*
X703500D03*
X696105Y364149D03*
X707500Y374362D03*
X707943Y360643D03*
X696391Y368617D03*
X703477Y369409D03*
X695500Y382362D03*
X707500Y386862D03*
X703700Y386832D03*
X695500Y386862D03*
X699500Y390862D03*
X695500D03*
X707500D03*
X703500D03*
X695796Y418358D03*
X708395Y424657D03*
X705245D03*
Y427807D03*
X702095D03*
X708395Y434106D03*
X705245Y430957D03*
X708395D03*
X702095Y421508D03*
Y434106D03*
X698946Y427807D03*
Y430957D03*
X705245Y434106D03*
X702095Y430957D03*
X698946Y437256D03*
X705245Y446705D03*
X708395Y440405D03*
Y443555D03*
X702095Y446705D03*
X705245Y443555D03*
X702095Y437256D03*
Y440405D03*
Y443555D03*
X705245Y440405D03*
X708395Y437256D03*
X698946Y446705D03*
X708395D03*
Y462373D03*
Y449854D03*
X702095D03*
X705245Y459223D03*
X702095Y456074D03*
Y459223D03*
X705245Y462373D03*
X702095D03*
X705245Y456074D03*
X695796Y449854D03*
X708395Y459223D03*
Y465523D03*
Y474971D03*
X698946Y468672D03*
X705245D03*
X702095D03*
X698946Y471822D03*
X702095Y465523D03*
X695796Y471822D03*
X705245D03*
X695796Y465523D03*
X702095Y478121D03*
X705245Y474971D03*
X708395Y468672D03*
X705245Y465523D03*
X702095Y471822D03*
X698946Y465523D03*
X705245Y478121D03*
X702095Y474971D03*
X698946Y487570D03*
Y481271D03*
X695796Y487570D03*
X698946Y484420D03*
X705245Y481271D03*
X702095D03*
X695796Y484420D03*
X708395Y481271D03*
X699431Y513344D03*
X707664Y513375D03*
X703788Y521817D03*
X696020Y521844D03*
X699800Y521760D03*
X696500Y529862D03*
X708500D03*
X700790Y537732D03*
X704500Y537862D03*
X708500Y533862D03*
X696829Y533604D03*
X702657Y533695D03*
X704500Y545862D03*
X696283Y546530D03*
X708500Y555451D03*
X701496Y580556D03*
X698996Y575081D03*
X704056D03*
X697392Y601686D03*
X706387Y621686D03*
X703781Y641805D03*
X704965Y638767D03*
X707833Y655325D03*
X704549Y655238D03*
X701233Y655355D03*
X694812Y680188D03*
X698756Y676388D03*
X694837Y676412D03*
X701386Y679683D03*
X703584Y676544D03*
X708012Y676836D03*
X705697Y679533D03*
X697571Y730453D03*
X704598Y732288D03*
X700205Y733211D03*
X697642Y733401D03*
X702553Y735811D03*
X697697Y756832D03*
X702256D03*
Y760178D03*
X706756Y776911D03*
X697747Y766871D03*
X697697Y763525D03*
X702206D03*
X697747Y770218D03*
X706756Y780257D03*
Y786950D03*
Y793643D03*
X697597Y791970D03*
X706756Y783604D03*
Y780257D03*
Y786950D03*
Y803682D03*
Y796989D03*
Y807029D03*
Y803682D03*
Y793643D03*
Y796989D03*
Y817068D03*
Y810375D03*
Y823761D03*
Y813722D03*
Y820415D03*
Y817068D03*
Y810375D03*
Y830454D03*
Y833800D03*
X697597Y828781D03*
X706756Y823761D03*
Y830454D03*
Y833800D03*
Y840493D03*
Y847186D03*
Y853879D03*
Y843840D03*
Y850533D03*
Y840493D03*
Y847186D03*
Y860572D03*
Y867265D03*
X697597Y865592D03*
X706756Y857226D03*
Y853879D03*
Y860572D03*
Y877304D03*
Y870611D03*
Y883997D03*
Y880651D03*
Y877304D03*
Y867265D03*
Y870611D03*
Y890690D03*
Y897383D03*
Y887344D03*
Y894037D03*
Y883997D03*
Y890690D03*
Y904076D03*
Y907423D03*
X697597Y902403D03*
X706756Y897383D03*
Y904076D03*
Y907423D03*
Y914115D03*
Y920808D03*
Y927501D03*
Y924155D03*
Y917462D03*
Y914115D03*
Y920808D03*
Y934194D03*
Y940887D03*
X697597Y939214D03*
X706756Y930848D03*
Y927501D03*
Y934194D03*
Y940887D03*
Y950926D03*
Y944234D03*
Y957619D03*
Y954273D03*
Y950926D03*
Y944234D03*
Y964312D03*
Y971005D03*
Y960966D03*
Y967659D03*
Y964312D03*
Y957619D03*
Y971005D03*
Y977698D03*
Y984391D03*
Y974352D03*
Y981045D03*
Y977698D03*
Y984391D03*
Y1001123D03*
Y997777D03*
Y991084D03*
Y987737D03*
Y994430D03*
Y1001123D03*
Y997777D03*
Y991084D03*
Y1004470D03*
Y1031241D03*
Y1037934D03*
Y1044627D03*
Y1041281D03*
Y1034588D03*
Y1031241D03*
Y1037934D03*
Y1044627D03*
Y1058013D03*
Y1051320D03*
Y1047974D03*
Y1054667D03*
Y1058013D03*
Y1051320D03*
Y1074745D03*
Y1071399D03*
Y1061360D03*
Y1074745D03*
Y1068052D03*
Y1064706D03*
Y1081438D03*
Y1088131D03*
Y1091478D03*
Y1078092D03*
X697597Y1086458D03*
X706756Y1081438D03*
Y1088131D03*
Y1098171D03*
Y1104863D03*
Y1101517D03*
Y1098171D03*
Y1104863D03*
Y1091478D03*
Y1111556D03*
Y1118249D03*
Y1114903D03*
Y1108210D03*
Y1111556D03*
Y1118249D03*
Y1134982D03*
Y1124942D03*
Y1128289D03*
X697597Y1123269D03*
X706756Y1134982D03*
Y1124942D03*
Y1128289D03*
Y1148367D03*
Y1141675D03*
Y1145021D03*
Y1138328D03*
Y1148367D03*
Y1141675D03*
Y1155060D03*
Y1161753D03*
Y1165100D03*
Y1151714D03*
X697597Y1160080D03*
X706756Y1155060D03*
Y1161753D03*
Y1165100D03*
Y1171793D03*
Y1178486D03*
Y1175139D03*
Y1171793D03*
Y1178486D03*
Y1185178D03*
Y1191871D03*
Y1181832D03*
Y1188525D03*
Y1185178D03*
Y1191871D03*
Y1208604D03*
Y1198564D03*
Y1201911D03*
X697597Y1196891D03*
X706756Y1208604D03*
Y1198564D03*
Y1201911D03*
Y1215297D03*
Y1221989D03*
Y1211950D03*
Y1218643D03*
Y1215297D03*
Y1221989D03*
Y1228682D03*
Y1235375D03*
Y1238722D03*
Y1225336D03*
X697597Y1233702D03*
X706756Y1228682D03*
Y1235375D03*
Y1238722D03*
Y1245415D03*
Y1252108D03*
Y1248761D03*
Y1245415D03*
Y1252108D03*
Y1255454D03*
X697483Y1297506D03*
Y1305206D03*
Y1300006D03*
Y1302606D03*
X697461Y1314008D03*
Y1320008D03*
Y1323008D03*
X702388Y1327127D03*
X699868D03*
X697461Y1317008D03*
X701771Y1342488D03*
X702388Y1337127D03*
Y1339627D03*
X699868Y1337127D03*
Y1339627D03*
X702388Y1329627D03*
X699868D03*
X702388Y1332127D03*
X699868D03*
X702388Y1334627D03*
X699868D03*
X701771Y1351988D03*
Y1349488D03*
Y1344988D03*
X699467Y1368710D03*
Y1363510D03*
Y1366110D03*
X703568Y1379476D03*
X705657Y1387027D03*
X701689Y1399545D03*
X697731Y1397513D03*
X706351Y1397588D03*
X705657Y1389568D03*
X695162Y1441350D03*
X694676Y1455112D03*
X697300Y1454140D03*
X696237Y1508149D03*
X699049Y1510892D03*
X696374Y1510846D03*
X696329Y1513818D03*
X696330Y1516584D03*
X706172Y1552082D03*
X699500Y1559000D03*
X699610Y1568523D03*
Y1572523D03*
Y1576523D03*
Y1584523D03*
X699500Y1596500D03*
Y1588500D03*
X699000Y1604500D03*
X699500Y1599500D03*
Y1608500D03*
X709020Y1609101D03*
X706681Y1627361D03*
X699424Y1616627D03*
X695933Y1623460D03*
X701114Y1640345D03*
X705833Y1633568D03*
X702683Y1633715D03*
X706089Y1643411D03*
X705815Y1654918D03*
X703563Y1644116D03*
X702402Y1650469D03*
X703473Y1663001D03*
X700528Y1661468D03*
X697503Y1661331D03*
X703102Y1665554D03*
X695400Y1685887D03*
X705366Y1684064D03*
X698003Y1684692D03*
X725925Y-25571D03*
X723479Y-28508D03*
X725925Y-22171D03*
Y-15571D03*
Y-12171D03*
X723479Y-19234D03*
Y-9234D03*
X716843Y23788D03*
X722581Y49182D03*
X717342Y57098D03*
X721163Y58588D03*
X715745Y86300D03*
X712725Y84714D03*
X713420Y102060D03*
X712291Y106722D03*
X715934Y117488D03*
Y114588D03*
X712734Y117488D03*
Y114588D03*
X720434Y135088D03*
X717434D03*
X719934Y124488D03*
X723134D03*
X716699Y177087D03*
Y173687D03*
X719195Y172873D03*
Y177865D03*
X714203Y172873D03*
Y177865D03*
X710284Y169826D03*
X716699Y177087D03*
Y173687D03*
Y189087D03*
Y185687D03*
Y197187D03*
X719195Y196373D03*
X714203D03*
X719195Y184873D03*
Y189865D03*
X714203Y184873D03*
Y189865D03*
X716699Y189087D03*
Y185687D03*
Y200587D03*
Y209021D03*
Y212421D03*
X714203Y208207D03*
X719195D03*
Y201365D03*
X714203D03*
X716699Y200587D03*
Y197187D03*
Y209021D03*
X714203Y213199D03*
X719195D03*
X717021Y220862D03*
X716699Y212421D03*
X720328Y344824D03*
X714867Y344943D03*
X717712Y346103D03*
X715500Y374362D03*
X719500D03*
X711500Y360862D03*
X719500D03*
X723500D03*
X711500Y374362D03*
X715500Y360862D03*
X719500Y368862D03*
X711363Y369274D03*
X711500Y382362D03*
X723632Y386862D03*
X711500D03*
X715500D03*
X722500Y383162D03*
X723500Y390862D03*
X719500D03*
X715500D03*
X711500D03*
X720993Y418358D03*
X717843D03*
Y421508D03*
X720993Y430957D03*
X711544D03*
X714694D03*
X720993Y434106D03*
X717843Y430957D03*
X720993Y421508D03*
X711544Y434106D03*
X714694D03*
X720993Y424657D03*
X717843D03*
Y427807D03*
X714694Y424657D03*
Y427807D03*
X711544Y421508D03*
Y424657D03*
Y427807D03*
X717843Y437256D03*
X720993D03*
X714694D03*
X711544D03*
X720993Y443555D03*
Y446705D03*
X717843D03*
Y440405D03*
X711544Y443555D03*
X717843D03*
X714694Y446705D03*
Y440405D03*
X720993D03*
X711544D03*
X714694Y443555D03*
X711544Y446705D03*
Y459223D03*
X720993Y449854D03*
Y462373D03*
Y459223D03*
Y456074D03*
X717843Y459223D03*
X714694D03*
X717843Y462373D03*
Y456074D03*
Y449854D03*
X714694Y462373D03*
X711544D03*
X714694Y449854D03*
X711544D03*
X714694Y456074D03*
X711544D03*
X720993Y471822D03*
X711544Y478121D03*
X717843Y474971D03*
X720993Y478121D03*
X717843D03*
X720993Y474971D03*
X714694Y465523D03*
X717843D03*
Y471822D03*
Y468672D03*
X714694Y471822D03*
X711544D03*
Y468672D03*
X720993Y465523D03*
X714694Y478121D03*
Y474971D03*
X711544Y465523D03*
X717843Y481271D03*
X714694D03*
X720993D03*
X711544Y484420D03*
Y481271D03*
X711617Y513531D03*
X716500Y517362D03*
X720452Y513362D03*
X716716Y513368D03*
X720499Y533474D03*
X719841Y537348D03*
X712113Y537797D03*
X720500Y546211D03*
X712115Y541872D03*
X712409Y555413D03*
X710464Y557036D03*
X711556Y575081D03*
X722201Y579306D03*
X723483Y574890D03*
X714583Y587642D03*
Y590792D03*
X716181Y585562D03*
X715037Y603278D03*
Y606428D03*
X716313Y610134D03*
X720787Y627907D03*
X716721D03*
X713280Y636897D03*
X712319Y654954D03*
X711702Y646533D03*
X711295Y665117D03*
X718129Y666725D03*
X722129D03*
X712164Y676912D03*
X712120Y680287D03*
X717515Y679833D03*
X720563Y679886D03*
X720613Y677040D03*
X723814Y736782D03*
X711306Y756766D03*
Y760178D03*
X718348Y756766D03*
X722898Y776911D03*
Y773564D03*
X718348Y763766D03*
X711306Y767266D03*
X718349Y767300D03*
Y771100D03*
X722898Y776911D03*
X711307Y763766D03*
X722898Y783604D03*
Y790297D03*
Y793643D03*
Y780257D03*
X717448Y786950D03*
X712206Y790297D03*
X722898Y783604D03*
Y790297D03*
Y800336D03*
Y807029D03*
Y803682D03*
X712206Y800336D03*
X711156Y795316D03*
X717448Y796989D03*
X722898Y800336D03*
Y807029D03*
Y793643D03*
Y813722D03*
Y820415D03*
Y810375D03*
Y817068D03*
Y813722D03*
Y820415D03*
Y837147D03*
Y830454D03*
Y827108D03*
X717448Y823761D03*
Y833800D03*
X712206Y827108D03*
Y837147D03*
X711156Y832127D03*
X722898Y837147D03*
Y830454D03*
Y827108D03*
Y843840D03*
Y850533D03*
Y847186D03*
Y840493D03*
Y843840D03*
Y850533D03*
Y857226D03*
Y863919D03*
Y867265D03*
Y853879D03*
X717448Y860572D03*
X712206Y863919D03*
X722898Y857226D03*
Y863919D03*
Y873958D03*
Y880651D03*
Y877304D03*
X712206Y873958D03*
X717448Y870611D03*
X711156Y868938D03*
X722898Y873958D03*
Y880651D03*
Y867265D03*
Y887344D03*
Y894037D03*
Y883997D03*
Y890690D03*
Y887344D03*
Y894037D03*
Y910769D03*
Y904076D03*
Y900730D03*
X717448Y897383D03*
X712206Y900730D03*
X717448Y907423D03*
X712206Y910769D03*
X711156Y905750D03*
X722898Y910769D03*
Y904076D03*
Y900730D03*
Y924155D03*
Y917462D03*
Y920808D03*
Y914115D03*
Y924155D03*
Y917462D03*
Y930848D03*
Y940887D03*
Y937541D03*
Y927501D03*
X712206Y937541D03*
X717448Y934194D03*
X722898Y930848D03*
Y940887D03*
Y937541D03*
Y947580D03*
Y954273D03*
Y950926D03*
X717448Y944234D03*
X712206Y947580D03*
X711156Y942561D03*
X722898Y947580D03*
Y954273D03*
Y967659D03*
X717398Y960966D03*
X722898Y957619D03*
Y971005D03*
Y964312D03*
Y960966D03*
X717398D03*
X722898Y967659D03*
Y974352D03*
Y981045D03*
Y987737D03*
Y984391D03*
Y977698D03*
Y974352D03*
Y981045D03*
Y994430D03*
Y1001123D03*
Y991084D03*
Y997777D03*
Y987737D03*
Y994430D03*
Y1001123D03*
Y1004470D03*
Y1027895D03*
D03*
Y1034588D03*
Y1041281D03*
Y1047974D03*
Y1031241D03*
Y1037934D03*
Y1044627D03*
Y1034588D03*
Y1041281D03*
Y1054667D03*
Y1061360D03*
Y1051320D03*
Y1058013D03*
Y1047974D03*
Y1054667D03*
Y1071399D03*
Y1064706D03*
Y1068052D03*
Y1074745D03*
Y1061360D03*
Y1071399D03*
Y1064706D03*
Y1078092D03*
Y1088131D03*
Y1084785D03*
X717448Y1081438D03*
X712206Y1084785D03*
X711156Y1089805D03*
X722898Y1078092D03*
Y1088131D03*
Y1084785D03*
Y1094824D03*
Y1101517D03*
X712206Y1094824D03*
X717448Y1091478D03*
X722898Y1098171D03*
Y1104863D03*
Y1094824D03*
Y1101517D03*
Y1108210D03*
Y1114903D03*
Y1121596D03*
Y1111556D03*
X717448Y1118249D03*
X722898Y1108210D03*
Y1114903D03*
Y1131635D03*
Y1124942D03*
X717448Y1128289D03*
X712206Y1121596D03*
X711156Y1126616D03*
X722898Y1134982D03*
X712206Y1131635D03*
X722898D03*
Y1124942D03*
Y1121596D03*
Y1138328D03*
Y1145021D03*
Y1151714D03*
Y1148367D03*
Y1141675D03*
Y1138328D03*
Y1145021D03*
Y1161753D03*
Y1158407D03*
X717448Y1165100D03*
X711156Y1163427D03*
X717448Y1155060D03*
X712206Y1158407D03*
X722898Y1151714D03*
Y1161753D03*
Y1158407D03*
Y1168446D03*
Y1175139D03*
Y1181832D03*
Y1178486D03*
Y1171793D03*
X712206Y1168446D03*
X722898D03*
Y1175139D03*
Y1188525D03*
Y1195218D03*
Y1185178D03*
X717448Y1191871D03*
X722898Y1181832D03*
Y1188525D03*
Y1205257D03*
Y1198564D03*
Y1211950D03*
Y1208604D03*
X712206Y1195218D03*
X711156Y1200238D03*
X717448Y1201911D03*
X712206Y1205257D03*
X722898D03*
Y1198564D03*
Y1195218D03*
Y1218643D03*
Y1225336D03*
Y1215297D03*
Y1221989D03*
Y1211950D03*
Y1218643D03*
Y1235375D03*
Y1232029D03*
X717448Y1228682D03*
X712206Y1232029D03*
X717448Y1238722D03*
X711156Y1237049D03*
X722898Y1225336D03*
Y1235375D03*
Y1232029D03*
Y1242068D03*
Y1248761D03*
X712206Y1242068D03*
X722898Y1252108D03*
Y1245415D03*
Y1242068D03*
Y1248761D03*
X721361Y1297546D03*
X711954D03*
X721361Y1305246D03*
Y1302646D03*
Y1300046D03*
X711954Y1305246D03*
Y1302646D03*
Y1300046D03*
X721339Y1314048D03*
X711839Y1314348D03*
X721339Y1323048D03*
Y1320048D03*
Y1317048D03*
X715828Y1327277D03*
X710488Y1327177D03*
X713008D03*
X711839Y1323348D03*
Y1320348D03*
Y1317348D03*
X713008Y1329877D03*
Y1332377D03*
Y1334877D03*
X715828Y1332877D03*
Y1330377D03*
X713008Y1337377D03*
Y1339877D03*
X715828Y1335377D03*
X710288Y1339677D03*
Y1337177D03*
X710221Y1342488D03*
X710288Y1334677D03*
Y1332177D03*
Y1329677D03*
X710221Y1351988D03*
Y1349488D03*
Y1344988D03*
X716707Y1385281D03*
X719137D03*
X720233Y1378525D03*
Y1381482D03*
Y1375418D03*
X722833D03*
X714277Y1385281D03*
X715033Y1378525D03*
X717633D03*
X712433D03*
X717633Y1381482D03*
X715033Y1375418D03*
X717633D03*
X712433D03*
X719186Y1403296D03*
X719137Y1390881D03*
X714277D03*
X716707D03*
X712419Y1398094D03*
X719861Y1400139D03*
X719111Y1397571D03*
X712419Y1400602D03*
X709430Y1394417D03*
X722877Y1390881D03*
X722141Y1405912D03*
X709551Y1406578D03*
X721916Y1414339D03*
Y1416939D03*
X722141Y1408412D03*
X712099Y1416973D03*
X714599D03*
X717099D03*
X712099Y1414473D03*
X714599D03*
X717099D03*
X709599Y1416973D03*
Y1414473D03*
X721916Y1428989D03*
Y1431589D03*
X717099Y1432773D03*
X712099D03*
X714599D03*
X717099Y1430273D03*
X712099D03*
X714599D03*
X709599Y1432773D03*
Y1427373D03*
Y1424873D03*
Y1430273D03*
Y1419873D03*
Y1422373D03*
X714259Y1447483D03*
X719471Y1467422D03*
X711671D03*
X714271D03*
X716871D03*
X720217Y1472287D03*
X717617D03*
X715017D03*
X720926Y1469814D03*
X718326D03*
X715726D03*
X713126D03*
X716067Y1474792D03*
X718667D03*
X721267D03*
X717358Y1477038D03*
X719958D03*
X716770Y1531459D03*
X715122Y1533378D03*
X716989Y1537249D03*
X713357Y1535212D03*
X715224Y1539083D03*
X713459Y1540917D03*
X714474Y1566333D03*
X714110Y1581475D03*
X721963Y1576932D03*
X719963Y1578932D03*
Y1585790D03*
X721963Y1587790D03*
X723408Y1608740D03*
X722876Y1611343D03*
X717798Y1607335D03*
X717229Y1612376D03*
X722104Y1626253D03*
X715744Y1622842D03*
X711298Y1632534D03*
X718122Y1636332D03*
X718116Y1639129D03*
X717749Y1654921D03*
X709771Y1654927D03*
X713771D03*
X722480Y1657616D03*
X712354Y1682279D03*
X719117Y1682722D03*
X723181Y1688825D03*
X731743Y-30584D03*
X734996Y-30570D03*
X731758Y-28069D03*
X735011Y-28055D03*
X728718Y-29264D03*
X725925Y-25571D03*
Y-22171D03*
Y-15571D03*
X731757Y-20090D03*
X735010Y-20104D03*
X728717Y-18895D03*
X734995Y-17589D03*
X731742Y-17575D03*
X735041Y-23025D03*
X735026Y-25540D03*
X735041Y-14717D03*
X725925Y-12171D03*
X735026Y-12202D03*
X734996Y-7172D03*
X728718Y-8478D03*
X735011Y-9687D03*
X731743Y-7158D03*
X731758Y-9673D03*
X738843Y23788D03*
X728981Y39872D03*
X736791Y39832D03*
X730131Y60757D03*
X736524Y58069D03*
X726789Y60562D03*
X738590Y59868D03*
X730785Y58068D03*
X728285Y58135D03*
X724645Y58362D03*
X734769Y60757D03*
X730958Y71014D03*
X738044Y71526D03*
X725769Y69737D03*
X727200Y73210D03*
X727944Y88972D03*
X731555Y83685D03*
X737009Y83169D03*
X729918Y90998D03*
X727986Y101979D03*
X729900Y98090D03*
X727986Y105477D03*
X737624Y98858D03*
X734524Y98758D03*
X735734Y111988D03*
X728734Y132088D03*
Y129288D03*
Y126388D03*
X724134Y141288D03*
X735500Y143000D03*
X724147Y345291D03*
X729211Y346379D03*
X726431Y346384D03*
X738773Y346716D03*
X734463Y346712D03*
X735500Y368862D03*
X734166Y360782D03*
X727564Y368862D03*
X731500Y360862D03*
X731406Y374331D03*
X731500Y386862D03*
X735500D03*
Y390862D03*
X727500D03*
X731208Y398737D03*
X735500Y399330D03*
X733512Y418358D03*
X727292D03*
X724143D03*
X736661Y424657D03*
Y430957D03*
Y434106D03*
X733512D03*
Y421508D03*
Y427807D03*
X727292Y421508D03*
X733512Y424657D03*
Y430957D03*
X727292D03*
Y434106D03*
X724143Y430957D03*
X727292Y427807D03*
X736661D03*
X724143Y434106D03*
Y421508D03*
Y427807D03*
Y424657D03*
X733512Y437256D03*
X736661Y443555D03*
X733512Y446705D03*
Y443555D03*
X727292Y446705D03*
Y443555D03*
X724143D03*
X727292Y440405D03*
X724143Y446705D03*
X736661D03*
X733512Y440405D03*
X736661D03*
X727292Y437256D03*
X724143Y440405D03*
Y437256D03*
X736661D03*
X724143Y462373D03*
X727292D03*
X733512Y459223D03*
X727292D03*
X733512Y462373D03*
X736661D03*
Y459223D03*
Y456074D03*
X733512D03*
Y449854D03*
X736661D03*
X727292Y456074D03*
X724143Y459223D03*
Y456074D03*
X727292Y449854D03*
X724143D03*
X727292Y471822D03*
X724143Y468672D03*
X727292D03*
X736661D03*
X724143Y474971D03*
X727292D03*
X733512Y478121D03*
X724143Y465523D03*
X727292D03*
X733512D03*
X736661D03*
X733512Y474971D03*
Y468672D03*
X736661Y478121D03*
Y471822D03*
X724143Y478121D03*
X727292D03*
X736661Y474971D03*
Y487570D03*
Y484420D03*
X724143D03*
X736661Y481271D03*
X733512D03*
X738672Y494444D03*
X727292Y481271D03*
X724143Y487570D03*
X727292Y484420D03*
X724500Y513362D03*
X732500D03*
X728500Y521862D03*
X724500D03*
X728500Y513362D03*
X736609Y518426D03*
X728500Y529862D03*
X724336Y537527D03*
X728500Y533862D03*
X736500D03*
X732500D03*
X724433Y530870D03*
X732500Y529862D03*
X732580Y537193D03*
X724697Y535053D03*
X728652Y545862D03*
X728695Y550943D03*
X736670Y545864D03*
X724684D03*
X724281Y553438D03*
X726720Y574910D03*
X736528Y576480D03*
X724246Y627939D03*
X736362Y636854D03*
X724001Y636790D03*
X733382Y633574D03*
X726952Y648667D03*
X729489Y666547D03*
X734442Y675695D03*
X730837Y678940D03*
X738486Y679139D03*
X724931Y678364D03*
X735316Y736742D03*
X725712Y734135D03*
X729391D03*
X727576Y736756D03*
X727398Y756832D03*
X731957D03*
Y760178D03*
X736457Y776911D03*
X727398Y763525D03*
X731462Y766871D03*
X731907Y763525D03*
X727448Y770218D03*
X736457Y780257D03*
Y786950D03*
Y793643D03*
Y783604D03*
X727298Y791970D03*
X736457Y780257D03*
Y786950D03*
Y803682D03*
Y796989D03*
Y807029D03*
Y803682D03*
Y793643D03*
Y796989D03*
Y817068D03*
Y810375D03*
Y823761D03*
Y813722D03*
Y820415D03*
Y817068D03*
Y810375D03*
Y830454D03*
Y833800D03*
X727298Y828781D03*
X736457Y823761D03*
Y830454D03*
Y833800D03*
Y840493D03*
Y847186D03*
Y853879D03*
Y843840D03*
Y850533D03*
Y840493D03*
Y847186D03*
Y860572D03*
Y867265D03*
X727298Y865592D03*
X736457Y857226D03*
Y853879D03*
Y860572D03*
Y877304D03*
Y870611D03*
Y883997D03*
Y880651D03*
Y877304D03*
Y867265D03*
Y870611D03*
Y890690D03*
Y897383D03*
Y887344D03*
Y894037D03*
Y883997D03*
Y890690D03*
Y904076D03*
Y907423D03*
X727298Y902403D03*
X736457Y897383D03*
Y904076D03*
Y907423D03*
Y914115D03*
Y920808D03*
Y927501D03*
Y924155D03*
Y917462D03*
Y914115D03*
Y920808D03*
Y934194D03*
Y940887D03*
X727298Y939214D03*
X736457Y930848D03*
Y927501D03*
Y934194D03*
Y940887D03*
Y950926D03*
Y944234D03*
Y957619D03*
Y954273D03*
Y950926D03*
Y944234D03*
Y964312D03*
Y971005D03*
Y960966D03*
Y967659D03*
Y964312D03*
Y957619D03*
Y971005D03*
Y977698D03*
Y984391D03*
Y974352D03*
Y981045D03*
Y977698D03*
Y984391D03*
Y1001123D03*
Y997777D03*
Y991084D03*
Y987737D03*
Y994430D03*
Y1001123D03*
Y997777D03*
Y991084D03*
Y1004470D03*
Y1031241D03*
Y1037934D03*
Y1044627D03*
Y1034588D03*
Y1041281D03*
Y1031241D03*
Y1037934D03*
Y1044627D03*
Y1058013D03*
Y1051320D03*
Y1047974D03*
Y1054667D03*
Y1058013D03*
Y1051320D03*
Y1074745D03*
Y1071399D03*
Y1061360D03*
Y1074745D03*
Y1068052D03*
Y1064706D03*
Y1081438D03*
Y1088131D03*
Y1091478D03*
X727298Y1086458D03*
X736457Y1078092D03*
Y1081438D03*
Y1088131D03*
Y1098171D03*
Y1104863D03*
Y1101517D03*
Y1098171D03*
Y1104863D03*
Y1091478D03*
Y1111556D03*
Y1118249D03*
Y1114903D03*
Y1108210D03*
Y1111556D03*
Y1118249D03*
Y1134982D03*
Y1124942D03*
Y1128289D03*
X727298Y1123269D03*
X736457Y1134982D03*
Y1124942D03*
Y1128289D03*
Y1148367D03*
Y1141675D03*
Y1145021D03*
Y1138328D03*
Y1148367D03*
Y1141675D03*
Y1155060D03*
Y1161753D03*
Y1165100D03*
X727298Y1160080D03*
X736457Y1151714D03*
Y1155060D03*
Y1161753D03*
Y1165100D03*
Y1171793D03*
Y1178486D03*
Y1175139D03*
Y1171793D03*
Y1178486D03*
Y1185178D03*
Y1191871D03*
Y1181832D03*
Y1188525D03*
Y1185178D03*
Y1191871D03*
Y1208604D03*
Y1198564D03*
Y1201911D03*
X727298Y1196891D03*
X736457Y1208604D03*
Y1198564D03*
Y1201911D03*
Y1215297D03*
Y1221989D03*
Y1211950D03*
Y1218643D03*
Y1215297D03*
Y1221989D03*
Y1228682D03*
Y1235375D03*
Y1238722D03*
X727298Y1233702D03*
X736457Y1225336D03*
Y1228682D03*
Y1235375D03*
Y1238722D03*
Y1245415D03*
Y1252108D03*
Y1248761D03*
Y1245415D03*
Y1252108D03*
Y1255454D03*
X735954Y1297546D03*
Y1305246D03*
Y1302646D03*
Y1300046D03*
X735739Y1314048D03*
Y1320048D03*
Y1317048D03*
X724788Y1327277D03*
X727501Y1327230D03*
X730021D03*
X727401Y1332430D03*
Y1329930D03*
Y1334930D03*
X724788Y1330377D03*
Y1332877D03*
X727401Y1339930D03*
Y1337430D03*
X724788Y1335377D03*
X730021Y1337230D03*
Y1339730D03*
Y1334730D03*
Y1329730D03*
Y1332230D03*
X730795Y1342444D03*
X727098Y1351977D03*
X730900Y1352131D03*
X727098Y1349077D03*
X730900Y1349231D03*
X730795Y1344944D03*
X734047Y1372880D03*
X731447D03*
X734047Y1370280D03*
Y1367680D03*
X731447D03*
Y1370280D03*
X728348Y1380832D03*
Y1377875D03*
X736280Y1379580D03*
X732797Y1375380D03*
X725333Y1375418D03*
X727777Y1375434D03*
X738439Y1387127D03*
X728198Y1388026D03*
Y1385126D03*
X738230Y1402898D03*
X738439Y1389668D03*
X727737Y1390881D03*
X725307D03*
X734767Y1396986D03*
Y1394086D03*
X732567Y1392586D03*
X732667Y1395586D03*
X730501Y1397216D03*
Y1394316D03*
X734767Y1391186D03*
X735418Y1426122D03*
Y1423122D03*
Y1420122D03*
X732418Y1426122D03*
Y1423122D03*
Y1420122D03*
X735453Y1525368D03*
X737551Y1524008D03*
X727325Y1563400D03*
X727571Y1558353D03*
X736782Y1555496D03*
X733782D03*
X727571Y1555353D03*
X733782Y1567496D03*
X736782D03*
X730782D03*
X733782Y1558496D03*
Y1561496D03*
X736782Y1558496D03*
Y1561496D03*
X733782Y1564496D03*
X736782D03*
X730782Y1558496D03*
Y1561496D03*
Y1564496D03*
X723963Y1578932D03*
X730782Y1570496D03*
X736782D03*
X733782D03*
X733380Y1577231D03*
X727780Y1582361D03*
Y1577231D03*
X723963Y1585790D03*
X733380Y1587491D03*
X727780D03*
X736998Y1597463D03*
X730998D03*
X733998D03*
X736998Y1594463D03*
X730998D03*
X733998D03*
X736998Y1600463D03*
X730998D03*
X733998D03*
Y1603663D03*
X736998D03*
X733998Y1606663D03*
X736998D03*
X730998Y1603663D03*
Y1606663D03*
X730647Y1623629D03*
X727320Y1623698D03*
X736723Y1623938D03*
X731119Y1647997D03*
X735642Y1648537D03*
X734925Y1657826D03*
X730302Y1658050D03*
X726302Y1658022D03*
X738370Y1677909D03*
X730347Y1682902D03*
X725638Y1682890D03*
X736001Y1695509D03*
X732434Y1690660D03*
X738550Y1693215D03*
X738030Y1723903D03*
Y1726903D03*
X738108Y1721157D03*
X738075Y1718082D03*
X742841Y39832D03*
X744477Y58373D03*
X744988Y49062D03*
X747488D03*
X752261Y59782D03*
X749478Y59902D03*
X746588Y59754D03*
X740817Y58503D03*
X745131Y69507D03*
X750090Y72820D03*
X740537Y73564D03*
X750034Y89988D03*
Y92888D03*
X748034Y116288D03*
X748261Y112552D03*
X751221Y137864D03*
X743547Y147703D03*
X748915Y158608D03*
X745031Y161463D03*
X748125Y170618D03*
X745712Y212760D03*
X746705Y315647D03*
X750717Y319907D03*
X747696Y332772D03*
X751337Y343849D03*
X748752Y343582D03*
X745132Y344964D03*
X747500Y368862D03*
X751500D03*
X743500D03*
Y374362D03*
X749389Y360816D03*
X739500Y374362D03*
X747500D03*
X747454Y386817D03*
X751652Y386862D03*
X739652Y390862D03*
X743500D03*
X747500D03*
X751500D03*
X739811Y424657D03*
Y427807D03*
X742961Y424657D03*
Y427807D03*
X746110Y424657D03*
Y427807D03*
X752409Y430957D03*
Y434106D03*
X749260D03*
X752409Y421508D03*
Y424657D03*
X749260D03*
X746110Y430957D03*
X749260D03*
X742961D03*
X752409Y427807D03*
X739811Y434106D03*
X742961D03*
X746110D03*
X752409Y443555D03*
X739811Y437256D03*
X746110D03*
X742961D03*
X746110Y440405D03*
X749260Y437256D03*
X739811Y443555D03*
Y446705D03*
X742961Y440405D03*
X739811D03*
X742961Y443555D03*
Y446705D03*
X749260Y440405D03*
Y446705D03*
X752409Y437256D03*
Y446705D03*
X746110D03*
Y443555D03*
X749260D03*
X739811Y449854D03*
Y456074D03*
Y459223D03*
Y462373D03*
X742961Y459223D03*
Y462373D03*
Y456074D03*
Y449854D03*
X752409Y456074D03*
X749260Y449854D03*
X746110Y459223D03*
X752409D03*
X749260D03*
X746110Y456074D03*
Y449854D03*
Y462373D03*
X749260D03*
X752409Y449854D03*
X749260Y456074D03*
X742961Y474971D03*
Y468672D03*
X739811Y478121D03*
Y474971D03*
Y471822D03*
X749260D03*
X739811Y468672D03*
X749260D03*
Y474971D03*
X742961Y471822D03*
X749260Y478121D03*
X742961Y465523D03*
X752409Y468672D03*
X742961Y478121D03*
X746110Y468672D03*
X739811Y465523D03*
X752409Y471822D03*
Y465523D03*
X746110D03*
X749260D03*
X752409Y474971D03*
X746110Y478121D03*
Y471822D03*
X749260Y481271D03*
X742961Y484420D03*
X739811Y481271D03*
X746110Y484420D03*
X749260D03*
X752409Y487570D03*
X742961D03*
X752409Y484420D03*
X742961Y490070D03*
X746110Y481271D03*
X752409D03*
X742961D03*
X753252Y495234D03*
X748381Y495244D03*
X752652Y504106D03*
X752500Y517362D03*
X744500Y513362D03*
X748661Y517060D03*
X740500Y513362D03*
X748500D03*
X748077Y521789D03*
X740500Y537862D03*
X747637Y534874D03*
X748143Y530269D03*
X744916Y530268D03*
X752500Y529862D03*
X741851Y553544D03*
X745645Y545880D03*
X740638Y549900D03*
X745091Y553563D03*
X748500Y545862D03*
X752195Y554761D03*
X742278Y566667D03*
X748482Y557085D03*
X751731Y557714D03*
X739128Y566639D03*
X741624Y580707D03*
X741200Y577470D03*
X749131Y570340D03*
X750062Y655415D03*
X753309Y655515D03*
X750074Y648739D03*
X751885Y666724D03*
X753231Y678679D03*
X753500Y675800D03*
X742579Y676093D03*
X746665Y678879D03*
X750168Y675833D03*
X748049Y756766D03*
X741007D03*
Y760266D03*
X752599Y776911D03*
Y773564D03*
X741007Y767266D03*
X748049Y763766D03*
Y767300D03*
Y771100D03*
X752599Y776911D03*
X741007Y763766D03*
X752599Y783604D03*
Y790297D03*
Y793643D03*
Y780257D03*
X747149Y786950D03*
X741907Y790297D03*
X752599Y783604D03*
Y790297D03*
Y800336D03*
Y807029D03*
Y803682D03*
X747149Y796989D03*
X741907Y800336D03*
X740857Y795316D03*
X752599Y800336D03*
Y807029D03*
Y793643D03*
Y813722D03*
Y820415D03*
Y810375D03*
Y817068D03*
Y813722D03*
Y820415D03*
Y837147D03*
Y830454D03*
Y827108D03*
X747149Y823761D03*
Y833800D03*
X741907Y827108D03*
Y837147D03*
X740857Y832127D03*
X752599Y837147D03*
Y830454D03*
Y827108D03*
Y843840D03*
Y850533D03*
Y840493D03*
Y847186D03*
Y843840D03*
Y850533D03*
Y857226D03*
Y863919D03*
Y867265D03*
Y853879D03*
X747149Y860572D03*
X741907Y863919D03*
X752599Y857226D03*
Y863919D03*
Y873958D03*
Y880651D03*
Y877304D03*
X741907Y873958D03*
X747149Y870611D03*
X740857Y868938D03*
X752599Y873958D03*
Y880651D03*
Y867265D03*
Y887344D03*
Y894037D03*
Y890690D03*
Y883997D03*
Y887344D03*
Y894037D03*
Y910769D03*
Y904076D03*
Y900730D03*
X747149Y897383D03*
X741907Y900730D03*
X747149Y907423D03*
X741907Y910769D03*
X740857Y905750D03*
X752599Y910769D03*
Y904076D03*
Y900730D03*
Y924155D03*
Y917462D03*
Y920808D03*
Y914115D03*
Y924155D03*
Y917462D03*
Y930848D03*
Y940887D03*
Y937541D03*
X747149Y934194D03*
X752599Y927501D03*
X741907Y937541D03*
X752599Y930848D03*
Y940887D03*
Y937541D03*
Y947580D03*
Y954273D03*
Y950926D03*
X747149Y944234D03*
X741907Y947580D03*
X740857Y942561D03*
X752599Y947580D03*
Y954273D03*
Y967659D03*
X747099Y960966D03*
X752599Y957619D03*
Y971005D03*
Y964312D03*
Y960966D03*
X747099D03*
X752599Y967659D03*
Y974352D03*
Y981045D03*
Y987737D03*
Y984391D03*
Y977698D03*
Y974352D03*
Y981045D03*
Y994430D03*
Y1001123D03*
Y991084D03*
Y997777D03*
Y987737D03*
Y994430D03*
Y1001123D03*
Y1004470D03*
Y1027895D03*
D03*
Y1034588D03*
Y1041281D03*
Y1047974D03*
Y1031241D03*
Y1037934D03*
Y1044627D03*
Y1034588D03*
Y1041281D03*
Y1054667D03*
Y1061360D03*
Y1051320D03*
Y1058013D03*
Y1047974D03*
Y1054667D03*
Y1071399D03*
Y1064706D03*
Y1068052D03*
Y1074745D03*
Y1061360D03*
Y1071399D03*
Y1064706D03*
Y1078092D03*
Y1088131D03*
Y1084785D03*
X747149Y1081438D03*
X741907Y1084785D03*
X740857Y1089805D03*
X752599Y1078092D03*
Y1088131D03*
Y1084785D03*
Y1094824D03*
Y1101517D03*
Y1098171D03*
Y1104863D03*
X741907Y1094824D03*
X747149Y1091478D03*
X752599Y1094824D03*
Y1101517D03*
Y1108210D03*
Y1114903D03*
Y1121596D03*
Y1111556D03*
X747149Y1118249D03*
X752599Y1108210D03*
Y1114903D03*
Y1131635D03*
Y1124942D03*
X747149Y1128289D03*
X740857Y1126616D03*
X741907Y1121596D03*
X752599Y1134982D03*
X741907Y1131635D03*
X752599D03*
Y1124942D03*
Y1121596D03*
Y1138328D03*
Y1145021D03*
Y1151714D03*
Y1148367D03*
Y1141675D03*
Y1138328D03*
Y1145021D03*
Y1161753D03*
Y1158407D03*
X740857Y1163427D03*
X747149Y1165100D03*
X741907Y1158407D03*
X747149Y1155060D03*
X752599Y1151714D03*
Y1161753D03*
Y1158407D03*
Y1168446D03*
Y1175139D03*
Y1181832D03*
Y1178486D03*
Y1171793D03*
X741907Y1168446D03*
X752599D03*
Y1175139D03*
Y1188525D03*
Y1195218D03*
Y1185178D03*
X747149Y1191871D03*
X752599Y1181832D03*
Y1188525D03*
Y1205257D03*
Y1198564D03*
Y1211950D03*
Y1208604D03*
X741907Y1195218D03*
X740857Y1200238D03*
X747149Y1201911D03*
X741907Y1205257D03*
X752599D03*
Y1198564D03*
Y1195218D03*
Y1218643D03*
Y1225336D03*
Y1215297D03*
Y1221989D03*
Y1211950D03*
Y1218643D03*
Y1235375D03*
Y1232029D03*
X747149Y1228682D03*
X741907Y1232029D03*
X747149Y1238722D03*
X740857Y1237049D03*
X752599Y1225336D03*
Y1235375D03*
Y1232029D03*
Y1242068D03*
Y1248761D03*
X741907Y1242068D03*
X752599Y1252108D03*
Y1245415D03*
Y1242068D03*
Y1248761D03*
X745475Y1297246D03*
Y1304946D03*
Y1302346D03*
Y1299746D03*
X745439Y1314048D03*
X748188Y1327317D03*
X745491Y1327124D03*
X742971D03*
X745439Y1323048D03*
Y1320048D03*
Y1317048D03*
X745691Y1332424D03*
Y1329924D03*
Y1334924D03*
X748188Y1333017D03*
Y1330517D03*
X745691Y1339924D03*
Y1337424D03*
X748188Y1335517D03*
X742971Y1337124D03*
Y1339624D03*
Y1334624D03*
Y1329624D03*
Y1332124D03*
X739501Y1342244D03*
X739500Y1352031D03*
Y1349131D03*
X739501Y1344744D03*
X753015Y1381582D03*
Y1378625D03*
Y1375518D03*
X747059Y1385381D03*
X745215Y1378625D03*
X747815D03*
Y1375518D03*
X745215D03*
X750415Y1381582D03*
Y1378625D03*
Y1375518D03*
X749489Y1385381D03*
X751919D03*
X751968Y1403396D03*
X751919Y1390981D03*
X747059D03*
X749489D03*
X739932Y1398042D03*
X745201Y1398194D03*
X752643Y1400239D03*
X749155Y1398639D03*
X751893Y1397671D03*
X742212Y1394517D03*
X739888Y1404849D03*
X739611Y1458211D03*
X750418Y1468893D03*
X750968Y1482349D03*
X746082Y1506931D03*
X746111Y1504125D03*
X745984Y1501052D03*
X745001Y1516471D03*
X750205Y1512307D03*
X750155Y1516451D03*
X739900Y1523152D03*
X748782Y1555496D03*
X742782D03*
X739782D03*
X745782D03*
X739782Y1558496D03*
Y1561496D03*
Y1564496D03*
X745782Y1558496D03*
X742782D03*
X745782Y1561496D03*
X742782D03*
X745782Y1564496D03*
X742782D03*
X739782Y1567496D03*
X742782D03*
X748782Y1558496D03*
Y1561496D03*
Y1564496D03*
X747110Y1575863D03*
X739782Y1570496D03*
X742782D03*
X738880Y1582361D03*
Y1577231D03*
Y1587491D03*
X745998Y1597463D03*
X742998D03*
X745998Y1594463D03*
X742998D03*
X739998Y1597463D03*
Y1594463D03*
X745998Y1600463D03*
X742998D03*
X739998D03*
X745998Y1603663D03*
X742998D03*
X739998D03*
X745998Y1606663D03*
X742998D03*
X739998D03*
X743664Y1626945D03*
X743740Y1657327D03*
X743039Y1643326D03*
X751521Y1656008D03*
X739880Y1648046D03*
X742792Y1647982D03*
X751030Y1668583D03*
X745075Y1665675D03*
X748254Y1674771D03*
X752187Y1682994D03*
X748413Y1679367D03*
X740328Y1698376D03*
X747289Y1693063D03*
X741030Y1723903D03*
Y1726903D03*
X741160Y1721150D03*
X741025Y1718195D03*
X752596Y1737117D03*
X760843Y23788D03*
X757721Y62132D03*
X760221D03*
X762721D03*
X755621Y51602D03*
X758621D03*
X754621Y74562D03*
X757721Y64632D03*
X760221D03*
X754634Y105288D03*
X757694Y98108D03*
Y100653D03*
X760193Y106500D03*
X754634Y108288D03*
X762173Y123898D03*
X762199Y126684D03*
Y129684D03*
X756000Y145500D03*
X754825Y163397D03*
X756303Y158417D03*
X765950Y190669D03*
X762300Y188910D03*
X765000Y186500D03*
X754737Y185469D03*
X756083Y220240D03*
X757629Y239295D03*
X754286Y266319D03*
X754291Y269322D03*
X756692Y278942D03*
X765285Y276374D03*
X757464Y284087D03*
X754556Y283976D03*
X761067Y280355D03*
X763384Y279231D03*
X763508Y284404D03*
X763463Y281840D03*
X760614Y284100D03*
X754759Y281007D03*
X755335Y295589D03*
X760462Y295662D03*
X758959Y319596D03*
X768130Y335363D03*
X753959Y343790D03*
X758245Y343763D03*
X764331Y374401D03*
X756347Y360851D03*
X764983Y368052D03*
X766304Y372862D03*
X768304Y374362D03*
X759652D03*
X755500Y386862D03*
X759500D03*
X767500D03*
X759500Y390791D03*
X755500Y390862D03*
X767500D03*
X763500D03*
X765008Y418358D03*
X755559D03*
X758709D03*
X761858D03*
X755559Y427807D03*
Y430957D03*
X758709D03*
X765008Y424657D03*
X755559D03*
X758709D03*
Y421508D03*
X761858Y424657D03*
X765008Y430957D03*
X755559Y434106D03*
X761858Y430957D03*
Y427807D03*
X765008D03*
Y446705D03*
X758709D03*
X755559Y443555D03*
Y446705D03*
X758709Y437256D03*
X755559D03*
X758709Y440405D03*
X755559D03*
X758709Y443555D03*
X761858Y446705D03*
X755559Y456074D03*
Y449854D03*
Y459223D03*
X765008Y456074D03*
X755559Y462373D03*
X758709D03*
Y456074D03*
Y449854D03*
X755559Y478121D03*
X758709Y468672D03*
X755559D03*
Y471822D03*
X758709D03*
X761858Y478121D03*
Y474971D03*
Y471822D03*
X758709Y474971D03*
X765008Y471822D03*
Y465523D03*
X761858Y468672D03*
Y465523D03*
X765008Y468672D03*
X755559Y465523D03*
Y474971D03*
Y481271D03*
X762800Y493654D03*
X755559Y484420D03*
X765008Y487570D03*
Y481271D03*
X761858D03*
X758709D03*
X764500Y521862D03*
X756500Y513340D03*
X760500Y521189D03*
X756186Y529888D03*
X764500Y534424D03*
X760500Y534352D03*
X764500Y529862D03*
X760500Y529845D03*
X757860Y537859D03*
X756500Y545862D03*
X764500D03*
X759568Y545867D03*
X768340Y563678D03*
X765809Y563410D03*
X758103Y556873D03*
X765041Y565867D03*
X762530Y565340D03*
X757745Y655353D03*
X755765Y666904D03*
X762656Y667835D03*
X756936Y676319D03*
X768565Y677573D03*
X760529Y677715D03*
X764401Y676968D03*
X762396Y732915D03*
X754532Y735859D03*
X760425Y736233D03*
X764568Y736183D03*
X757099Y756832D03*
X761658D03*
Y760178D03*
X766158Y776911D03*
X757149Y766871D03*
X757099Y763525D03*
X761608D03*
X757149Y770218D03*
X766158Y780257D03*
Y786950D03*
Y793643D03*
Y783604D03*
X756999Y791970D03*
X766158Y780257D03*
Y786950D03*
Y803682D03*
Y796989D03*
Y807029D03*
Y803682D03*
Y793643D03*
Y796989D03*
Y817068D03*
Y810375D03*
Y823761D03*
Y813722D03*
Y820415D03*
Y817068D03*
Y810375D03*
Y830454D03*
Y833800D03*
X756999Y828781D03*
X766158Y823761D03*
Y830454D03*
Y833800D03*
Y840493D03*
Y847186D03*
Y853879D03*
Y843840D03*
Y850533D03*
Y840493D03*
Y847186D03*
Y860572D03*
Y867265D03*
Y857226D03*
X756999Y865592D03*
X766158Y853879D03*
Y860572D03*
Y877304D03*
Y870611D03*
Y883997D03*
Y880651D03*
Y877304D03*
Y867265D03*
Y870611D03*
Y890690D03*
Y897383D03*
Y887344D03*
Y894037D03*
Y883997D03*
Y890690D03*
Y904076D03*
Y907423D03*
X756999Y902403D03*
X766158Y897383D03*
Y904076D03*
Y907423D03*
Y914115D03*
Y920808D03*
Y927501D03*
Y924155D03*
Y917462D03*
Y914115D03*
Y920808D03*
Y934194D03*
Y940887D03*
X756999Y939214D03*
X766158Y930848D03*
Y927501D03*
Y934194D03*
Y940887D03*
Y950926D03*
Y944234D03*
Y957619D03*
Y954273D03*
Y950926D03*
Y944234D03*
Y964312D03*
Y971005D03*
Y960966D03*
Y967659D03*
Y964312D03*
Y957619D03*
Y971005D03*
Y977698D03*
Y984391D03*
Y974352D03*
Y981045D03*
Y977698D03*
Y984391D03*
Y1001123D03*
Y997777D03*
Y991084D03*
Y987737D03*
Y994430D03*
Y1001123D03*
Y997777D03*
Y991084D03*
Y1004470D03*
Y1031241D03*
Y1037934D03*
Y1044627D03*
Y1041281D03*
Y1034588D03*
Y1031241D03*
Y1037934D03*
Y1044627D03*
Y1058013D03*
Y1051320D03*
Y1047974D03*
Y1054667D03*
Y1058013D03*
Y1051320D03*
Y1074745D03*
Y1071399D03*
Y1061360D03*
Y1074745D03*
Y1068052D03*
Y1064706D03*
Y1081438D03*
Y1088131D03*
Y1091478D03*
X756999Y1086458D03*
X766158Y1078092D03*
Y1081438D03*
Y1088131D03*
Y1098171D03*
Y1104863D03*
Y1101517D03*
Y1098171D03*
Y1104863D03*
Y1091478D03*
Y1111556D03*
Y1118249D03*
Y1114903D03*
Y1108210D03*
Y1111556D03*
Y1118249D03*
Y1134982D03*
Y1124942D03*
Y1128289D03*
X756999Y1123269D03*
X766158Y1134982D03*
Y1124942D03*
Y1128289D03*
Y1148367D03*
Y1141675D03*
Y1145021D03*
Y1138328D03*
Y1148367D03*
Y1141675D03*
Y1155060D03*
Y1161753D03*
Y1165100D03*
X756999Y1160080D03*
X766158Y1151714D03*
Y1155060D03*
Y1161753D03*
Y1165100D03*
Y1171793D03*
Y1178486D03*
Y1175139D03*
Y1171793D03*
Y1178486D03*
Y1185178D03*
Y1191871D03*
Y1181832D03*
Y1188525D03*
Y1185178D03*
Y1191871D03*
Y1208604D03*
Y1198564D03*
Y1201911D03*
X756999Y1196891D03*
X766158Y1208604D03*
Y1198564D03*
Y1201911D03*
Y1215297D03*
Y1221989D03*
Y1211950D03*
Y1218643D03*
Y1215297D03*
Y1221989D03*
Y1228682D03*
Y1235375D03*
Y1238722D03*
Y1225336D03*
X756999Y1233702D03*
X766158Y1228682D03*
Y1235375D03*
Y1238722D03*
Y1245415D03*
Y1252108D03*
Y1248761D03*
Y1245415D03*
Y1252108D03*
Y1255454D03*
X759854Y1297246D03*
Y1304946D03*
Y1302346D03*
Y1299746D03*
X759839Y1313948D03*
Y1319948D03*
X760204Y1327314D03*
X762754D03*
X759839Y1316948D03*
X757638Y1327317D03*
X759839Y1322948D03*
X760204Y1332514D03*
Y1330014D03*
Y1335014D03*
X757638Y1333017D03*
Y1330517D03*
X760194Y1340024D03*
Y1337524D03*
X757638Y1335517D03*
X762844Y1337324D03*
Y1339824D03*
X762754Y1334814D03*
Y1329814D03*
Y1332314D03*
X762261Y1343424D03*
X761800Y1352031D03*
Y1349131D03*
X762261Y1345924D03*
X764229Y1372880D03*
X766829D03*
Y1370380D03*
Y1367780D03*
X764229D03*
Y1370380D03*
X761130Y1380932D03*
Y1377975D03*
X755615Y1375518D03*
X758115D03*
X760559Y1375534D03*
X765579Y1375480D03*
X760980Y1385146D03*
Y1388046D03*
X758089Y1390981D03*
X760519D03*
X755659D03*
X767549Y1391286D03*
Y1397086D03*
Y1394186D03*
X765349Y1392686D03*
X765449Y1395686D03*
X763283Y1397316D03*
Y1394416D03*
X758179Y1482049D03*
X758163Y1490789D03*
Y1498663D03*
Y1494726D03*
Y1502600D03*
Y1522286D03*
Y1510474D03*
X758056Y1518349D03*
X758163Y1526223D03*
X758179Y1534963D03*
X760650Y1570633D03*
Y1578733D03*
Y1574733D03*
X757610Y1576023D03*
X766212Y1568043D03*
X757650Y1580023D03*
X767750Y1584108D03*
X757610Y1589023D03*
X760650Y1587733D03*
X760521Y1595500D03*
X759723Y1626161D03*
X755261Y1628208D03*
X755408Y1672381D03*
X758030Y1668583D03*
X754839Y1678069D03*
X757161Y1696424D03*
X769475Y75360D03*
X781441Y118637D03*
X782819Y149471D03*
X780159Y146961D03*
X772270Y153728D03*
X773457Y249792D03*
X782712Y260466D03*
X777408Y256648D03*
X777421Y277962D03*
X779884Y281705D03*
X774485Y286879D03*
X773221Y296262D03*
X780618Y296345D03*
X769790Y296231D03*
X777468Y296315D03*
X769861Y302462D03*
X782641Y310888D03*
X779121Y306155D03*
X773944Y312588D03*
X779681Y313053D03*
X770190Y312563D03*
X779121Y303410D03*
Y308755D03*
X780046Y328268D03*
X772119Y333537D03*
X771964Y339716D03*
X781812Y341863D03*
X779118Y341749D03*
X769000Y364000D03*
X776500Y371000D03*
X771512Y386862D03*
X770000Y380787D03*
X777612Y403505D03*
X771512Y390862D03*
X780295Y403538D03*
X780808Y419865D03*
X773181Y415197D03*
X773233Y409154D03*
X770159Y410257D03*
X780877Y427344D03*
X771718Y426804D03*
X780877Y423344D03*
Y431368D03*
X780577Y435564D03*
X780877Y447344D03*
X780977Y459524D03*
X780877Y463344D03*
Y455344D03*
X783377Y451344D03*
X780877Y475344D03*
X780759Y479344D03*
X772427Y475344D03*
X781242Y489574D03*
X780877Y483344D03*
X772390Y491047D03*
X783351Y499221D03*
X775100Y502504D03*
X772427Y495344D03*
X774998Y511306D03*
X774964Y514204D03*
X777200Y530250D03*
X772000Y529862D03*
Y545862D03*
X776345Y545733D03*
X777754Y558740D03*
X778747Y572269D03*
X779448Y632498D03*
X772459Y655290D03*
X771553Y677963D03*
X777900Y756766D03*
X770708D03*
Y760266D03*
X782300Y776911D03*
Y773564D03*
X770708Y767266D03*
X777900Y763766D03*
X777750Y767300D03*
Y771100D03*
X782300Y776911D03*
X770708Y763766D03*
X782300Y783604D03*
Y790297D03*
Y793643D03*
X776850Y786950D03*
X771608Y790297D03*
X782300Y780257D03*
Y783604D03*
Y790297D03*
Y800336D03*
Y807029D03*
X776850Y796989D03*
X771608Y800336D03*
X770558Y795316D03*
X782300Y803682D03*
Y800336D03*
Y807029D03*
Y793643D03*
Y813722D03*
Y820415D03*
Y810375D03*
Y817068D03*
Y813722D03*
Y820415D03*
Y837147D03*
Y830454D03*
Y827108D03*
X771608Y837147D03*
X770558Y832127D03*
X776850Y823761D03*
Y833800D03*
X771608Y827108D03*
X782300Y837147D03*
Y830454D03*
Y827108D03*
Y843840D03*
Y850533D03*
Y847186D03*
Y840493D03*
Y843840D03*
Y850533D03*
Y857226D03*
Y863919D03*
Y867265D03*
X776850Y860572D03*
X771608Y863919D03*
X782300Y853879D03*
Y857226D03*
Y863919D03*
Y873958D03*
Y880651D03*
X771608Y873958D03*
X782300Y877304D03*
X776850Y870611D03*
X770558Y868938D03*
X782300Y873958D03*
Y880651D03*
Y867265D03*
Y887344D03*
Y894037D03*
Y890690D03*
Y883997D03*
Y887344D03*
Y894037D03*
Y910769D03*
Y904076D03*
Y900730D03*
X776850Y897383D03*
X771608Y900730D03*
X776850Y907423D03*
X771608Y910769D03*
X770558Y905750D03*
X782300Y910769D03*
Y904076D03*
Y900730D03*
Y924155D03*
Y917462D03*
Y920808D03*
Y914115D03*
Y924155D03*
Y917462D03*
Y930848D03*
Y940887D03*
Y937541D03*
X771608D03*
X776850Y934194D03*
X782300Y927501D03*
Y930848D03*
Y940887D03*
Y937541D03*
Y947580D03*
Y954273D03*
X776850Y944234D03*
X771608Y947580D03*
X770558Y942561D03*
X782300Y950926D03*
Y947580D03*
Y954273D03*
Y967659D03*
X776800Y960966D03*
X782300Y957619D03*
Y971005D03*
Y964312D03*
Y960966D03*
X776800D03*
X782300Y967659D03*
Y974352D03*
Y981045D03*
Y987737D03*
Y984391D03*
Y977698D03*
Y974352D03*
Y981045D03*
Y994430D03*
Y1001123D03*
Y991084D03*
Y997777D03*
Y987737D03*
Y994430D03*
Y1001123D03*
Y1004470D03*
Y1027895D03*
D03*
Y1034588D03*
Y1041281D03*
Y1047974D03*
Y1031241D03*
Y1037934D03*
Y1044627D03*
Y1034588D03*
Y1041281D03*
Y1054667D03*
Y1061360D03*
Y1051320D03*
Y1058013D03*
Y1047974D03*
Y1054667D03*
Y1071399D03*
Y1064706D03*
Y1068052D03*
Y1074745D03*
Y1061360D03*
Y1071399D03*
Y1064706D03*
Y1078092D03*
Y1088131D03*
Y1084785D03*
X776850Y1081438D03*
X771608Y1084785D03*
X770558Y1089805D03*
X782300Y1078092D03*
Y1088131D03*
Y1084785D03*
Y1094824D03*
Y1101517D03*
Y1098171D03*
Y1104863D03*
X776850Y1091478D03*
X771608Y1094824D03*
X782300D03*
Y1101517D03*
Y1108210D03*
Y1114903D03*
Y1121596D03*
X776850Y1118249D03*
X782300Y1111556D03*
Y1108210D03*
Y1114903D03*
Y1131635D03*
Y1124942D03*
X776850Y1128289D03*
X770558Y1126616D03*
X771608Y1121596D03*
Y1131635D03*
X782300Y1134982D03*
Y1131635D03*
Y1124942D03*
Y1121596D03*
Y1138328D03*
Y1145021D03*
Y1151714D03*
Y1148367D03*
Y1141675D03*
Y1138328D03*
Y1145021D03*
Y1161753D03*
Y1158407D03*
X776850Y1165100D03*
X770558Y1163427D03*
X776850Y1155060D03*
X771608Y1158407D03*
X782300Y1151714D03*
Y1161753D03*
Y1158407D03*
Y1168446D03*
Y1175139D03*
Y1181832D03*
Y1178486D03*
X771608Y1168446D03*
X782300Y1171793D03*
Y1168446D03*
Y1175139D03*
Y1188525D03*
Y1195218D03*
Y1185178D03*
X776850Y1191871D03*
X782300Y1181832D03*
Y1188525D03*
Y1205257D03*
Y1198564D03*
Y1211950D03*
Y1208604D03*
X771608Y1195218D03*
X770558Y1200238D03*
X776850Y1201911D03*
X771608Y1205257D03*
X782300D03*
Y1198564D03*
Y1195218D03*
Y1218643D03*
Y1225336D03*
Y1215297D03*
Y1221989D03*
Y1211950D03*
Y1218643D03*
Y1235375D03*
Y1232029D03*
X776850Y1228682D03*
X771608Y1232029D03*
X776850Y1238722D03*
X770558Y1237049D03*
X782300Y1225336D03*
Y1235375D03*
Y1232029D03*
Y1242068D03*
Y1248761D03*
X771608Y1242068D03*
X782300Y1252108D03*
Y1245415D03*
Y1242068D03*
Y1248761D03*
X769521Y1297199D03*
X783280Y1296009D03*
X778030Y1296259D03*
X780530D03*
X783280Y1298509D03*
X769521Y1304899D03*
Y1299699D03*
Y1302299D03*
X778030Y1310259D03*
X780530D03*
X769439Y1313948D03*
X783280Y1301009D03*
X769439Y1319948D03*
Y1322948D03*
Y1316948D03*
X779014Y1343262D03*
Y1340062D03*
X782014D03*
Y1337062D03*
Y1343262D03*
X770881Y1343344D03*
X770990Y1349091D03*
Y1351991D03*
X780000Y1353500D03*
X779014Y1346462D03*
Y1349862D03*
X782014Y1346462D03*
Y1349862D03*
X780000Y1357500D03*
X770881Y1345844D03*
X780000Y1363500D03*
Y1360500D03*
X773069Y1375500D03*
X770469D03*
X776010Y1380750D03*
X780111Y1405366D03*
X782758Y1405249D03*
X774646Y1516441D03*
X772906Y1522901D03*
X774616Y1520361D03*
X781850Y1556133D03*
Y1559133D03*
Y1562133D03*
Y1565133D03*
X778850Y1559133D03*
Y1562133D03*
Y1565133D03*
X771450Y1577333D03*
X781850Y1568133D03*
Y1571133D03*
X778850Y1568133D03*
Y1571133D03*
X779977Y1577233D03*
Y1582363D03*
X771550Y1587133D03*
X774420Y1587284D03*
X779977Y1587493D03*
X779550Y1594533D03*
X782550D03*
X776550Y1597533D03*
Y1594533D03*
X779550Y1597533D03*
X782550D03*
Y1600533D03*
X776550D03*
X779550D03*
Y1606533D03*
X782550Y1603533D03*
X779550D03*
X776550Y1606533D03*
Y1603533D03*
X782550Y1606533D03*
X773974Y1731920D03*
X787456Y49379D03*
X785181Y120947D03*
X792681D03*
X790181D03*
X787681D03*
X783941Y118637D03*
X786441D03*
X788941D03*
X791341Y264848D03*
X785529Y270459D03*
X798205Y279146D03*
X797594Y282233D03*
X797444Y271469D03*
X795668Y298801D03*
X793855Y305316D03*
X798493Y301377D03*
X795921Y312662D03*
X787500Y328362D03*
X791726Y328467D03*
X783726D03*
X785674Y342279D03*
X788806Y342236D03*
X791403Y342262D03*
X793951Y342224D03*
X795685Y357498D03*
X798312Y372571D03*
X792488Y377452D03*
X796021Y395924D03*
X797000Y404000D03*
X785923Y419194D03*
X787000Y407500D03*
X796283Y419344D03*
Y431344D03*
X783877Y427344D03*
X796283D03*
X797252Y443344D03*
X796333Y435344D03*
X786203Y447054D03*
X783877Y435444D03*
X797197Y447344D03*
X797252Y459344D03*
Y451344D03*
X797322Y463344D03*
X786825Y459518D03*
X786755Y455524D03*
X797252Y455344D03*
Y471344D03*
X797326Y479344D03*
X786877Y471344D03*
Y475344D03*
X797405Y487464D03*
X797326Y483344D03*
X787092Y490681D03*
X786358Y483566D03*
X787446Y495344D03*
X787279Y499238D03*
X789125Y529425D03*
X794425Y541425D03*
X794059Y553559D03*
X794357Y559996D03*
X791500Y560000D03*
X785000Y563500D03*
X785919Y559660D03*
X791723Y574946D03*
X789135Y617097D03*
X783653Y631671D03*
X787591Y631785D03*
X788537Y734410D03*
X793131Y734310D03*
X784543Y734510D03*
X786800Y756832D03*
X791358Y760178D03*
Y756832D03*
X795858Y776911D03*
X786850Y766871D03*
X786800Y763525D03*
X791308D03*
X786850Y770218D03*
X795858Y780257D03*
Y786950D03*
Y793643D03*
Y783604D03*
X786700Y791970D03*
X795858Y780257D03*
Y786950D03*
Y803682D03*
Y796989D03*
Y807029D03*
Y803682D03*
Y793643D03*
Y796989D03*
Y817068D03*
Y810375D03*
Y823761D03*
Y820415D03*
Y813722D03*
Y817068D03*
Y810375D03*
Y830454D03*
Y833800D03*
X786700Y828781D03*
X795858Y823761D03*
Y830454D03*
Y833800D03*
Y840493D03*
Y847186D03*
Y853879D03*
Y843840D03*
Y850533D03*
Y840493D03*
Y847186D03*
Y860572D03*
Y867265D03*
X786700Y865592D03*
X795858Y857226D03*
Y853879D03*
Y860572D03*
Y877304D03*
Y870611D03*
Y883997D03*
Y880651D03*
Y877304D03*
Y867265D03*
Y870611D03*
Y890690D03*
Y897383D03*
Y894037D03*
Y887344D03*
Y883997D03*
Y890690D03*
Y904076D03*
Y907423D03*
X786700Y902403D03*
X795858Y897383D03*
Y904076D03*
Y907423D03*
Y914115D03*
Y920808D03*
Y927501D03*
Y924155D03*
Y917462D03*
Y914115D03*
Y920808D03*
Y934194D03*
Y940887D03*
X786700Y939214D03*
X795858Y930848D03*
Y927501D03*
Y934194D03*
Y940887D03*
Y950926D03*
Y944234D03*
Y957619D03*
Y954273D03*
Y950926D03*
Y944234D03*
Y964312D03*
Y971005D03*
Y960966D03*
Y967659D03*
Y964312D03*
Y957619D03*
Y971005D03*
Y977698D03*
Y984391D03*
Y981045D03*
Y974352D03*
Y977698D03*
Y984391D03*
Y1001123D03*
Y997777D03*
Y991084D03*
Y994430D03*
Y987737D03*
Y1001123D03*
Y997777D03*
Y991084D03*
Y1004470D03*
Y1031241D03*
Y1037934D03*
Y1044627D03*
Y1041281D03*
Y1034588D03*
Y1031241D03*
Y1037934D03*
Y1044627D03*
Y1058013D03*
Y1051320D03*
Y1054667D03*
Y1047974D03*
Y1058013D03*
Y1051320D03*
Y1074745D03*
Y1071399D03*
Y1061360D03*
Y1074745D03*
Y1068052D03*
Y1064706D03*
Y1081438D03*
Y1088131D03*
Y1091478D03*
X786700Y1086458D03*
X795858Y1078092D03*
Y1081438D03*
Y1088131D03*
Y1098171D03*
Y1104863D03*
Y1101517D03*
Y1098171D03*
Y1104863D03*
Y1091478D03*
Y1111556D03*
Y1118249D03*
Y1114903D03*
Y1108210D03*
Y1111556D03*
Y1118249D03*
Y1134982D03*
Y1124942D03*
Y1128289D03*
X786700Y1123269D03*
X795858Y1134982D03*
Y1124942D03*
Y1128289D03*
Y1148367D03*
Y1141675D03*
Y1145021D03*
Y1138328D03*
Y1148367D03*
Y1141675D03*
Y1155060D03*
Y1161753D03*
Y1165100D03*
X786700Y1160080D03*
X795858Y1151714D03*
Y1155060D03*
Y1161753D03*
Y1165100D03*
Y1171793D03*
Y1178486D03*
Y1175139D03*
Y1171793D03*
Y1178486D03*
Y1185178D03*
Y1191871D03*
Y1181832D03*
Y1188525D03*
Y1185178D03*
Y1191871D03*
Y1208604D03*
Y1198564D03*
Y1201911D03*
X786700Y1196891D03*
X795858Y1208604D03*
Y1198564D03*
Y1201911D03*
Y1215297D03*
Y1221989D03*
Y1218643D03*
Y1211950D03*
Y1215297D03*
Y1221989D03*
Y1228682D03*
Y1235375D03*
Y1238722D03*
X786700Y1233702D03*
X795858Y1225336D03*
Y1228682D03*
Y1235375D03*
Y1238722D03*
Y1245415D03*
Y1252108D03*
Y1248761D03*
Y1245415D03*
Y1252108D03*
Y1255454D03*
X789020Y1292160D03*
X792520D03*
X786030Y1310259D03*
X794030D03*
X796530D03*
X788530D03*
X795421Y1331257D03*
X785014Y1350862D03*
X794273Y1354600D03*
Y1357600D03*
Y1364500D03*
Y1361500D03*
X784669Y1462178D03*
X784261Y1482049D03*
X796955Y1487468D03*
X788710Y1488821D03*
X784277Y1504569D03*
Y1500632D03*
Y1508506D03*
Y1512443D03*
X784261Y1534963D03*
X784277Y1528191D03*
X791823Y1527404D03*
X791867Y1524254D03*
X784850Y1556133D03*
X796850D03*
X790850D03*
X787850D03*
X793850D03*
X784850Y1559133D03*
Y1562133D03*
Y1565133D03*
X796850Y1559133D03*
Y1562133D03*
Y1565133D03*
X787850Y1559133D03*
Y1562133D03*
Y1565133D03*
X793850Y1559133D03*
X790850D03*
X793850Y1562133D03*
X790850D03*
X793850Y1565133D03*
X790850D03*
X784850Y1568133D03*
Y1571133D03*
X787850Y1568133D03*
Y1571133D03*
X793850Y1568133D03*
X790850D03*
X793850Y1571133D03*
X790850D03*
X791077Y1577233D03*
X785577D03*
X791077Y1582363D03*
X796650Y1583347D03*
X785577Y1587493D03*
X791077D03*
X791550Y1597533D03*
X785550Y1594533D03*
X788550D03*
X791550D03*
X785550Y1597533D03*
X788550D03*
X785550Y1600533D03*
X788550D03*
X791550D03*
Y1606533D03*
X788550D03*
X785550D03*
X791550Y1603533D03*
X788550D03*
X785550D03*
X795926Y1731918D03*
X809456Y49379D03*
X806984Y265653D03*
X812867Y278860D03*
X804330Y281380D03*
X801341Y279141D03*
X799935Y286823D03*
X799113Y297733D03*
X803893Y301969D03*
X798621Y312773D03*
X805871Y304812D03*
X806461Y310610D03*
X803264Y330102D03*
X808617D03*
X806117D03*
X808401Y341670D03*
X803410Y341572D03*
X803500Y366000D03*
X811569Y387674D03*
X802660Y381020D03*
X802462Y387756D03*
X807564Y403805D03*
X811224Y395974D03*
X803412Y403978D03*
X813148Y403908D03*
X813175Y422687D03*
X813252Y427060D03*
X810360Y442079D03*
X813208Y435344D03*
X812895Y449802D03*
X802752Y455344D03*
X812983Y463578D03*
X813114Y459344D03*
X812983Y471344D03*
Y480159D03*
X813000Y484862D03*
X801753Y491344D03*
X813187Y498362D03*
X812500Y504000D03*
X813114Y495344D03*
X802250Y500504D03*
X801857Y508031D03*
X805940Y534500D03*
X805341Y578059D03*
X805199Y620347D03*
X804863Y626789D03*
X807450Y756766D03*
X800408D03*
Y760266D03*
X812000Y776911D03*
Y773564D03*
X807451Y763765D03*
X800408Y767266D03*
X807451Y767299D03*
X812000Y776911D03*
X800409Y763765D03*
X807127Y770958D03*
X812000Y783604D03*
Y790297D03*
Y793643D03*
Y780257D03*
X806550Y786950D03*
X801308Y790297D03*
X812000Y783604D03*
Y790297D03*
Y800336D03*
Y807029D03*
Y803682D03*
X806550Y796989D03*
X800258Y795316D03*
X801308Y800336D03*
X812000D03*
Y807029D03*
Y793643D03*
Y813722D03*
Y820415D03*
Y817068D03*
Y810375D03*
Y813722D03*
Y820415D03*
Y837147D03*
Y830454D03*
Y827108D03*
X800258Y832127D03*
X801308Y837147D03*
Y827108D03*
X806550Y833800D03*
Y823761D03*
X812000Y837147D03*
Y830454D03*
Y827108D03*
Y843840D03*
Y850533D03*
Y847186D03*
Y840493D03*
Y843840D03*
Y850533D03*
Y857226D03*
Y863919D03*
Y867265D03*
X806550Y860572D03*
X801308Y863919D03*
X812000Y853879D03*
Y857226D03*
Y863919D03*
Y873958D03*
Y880651D03*
Y877304D03*
X801308Y873958D03*
X806550Y870611D03*
X800258Y868938D03*
X812000Y873958D03*
Y880651D03*
Y867265D03*
Y887344D03*
Y894037D03*
Y890690D03*
Y883997D03*
Y887344D03*
Y894037D03*
Y910769D03*
Y904076D03*
Y900730D03*
X806550Y897383D03*
X801308Y900730D03*
X806550Y907423D03*
X800258Y905750D03*
X801308Y910769D03*
X812000D03*
Y904076D03*
Y900730D03*
Y924155D03*
Y917462D03*
Y920808D03*
Y914115D03*
Y924155D03*
Y917462D03*
Y930848D03*
Y940887D03*
Y937541D03*
X801308D03*
X812000Y927501D03*
X806550Y934194D03*
X812000Y930848D03*
Y940887D03*
Y937541D03*
Y947580D03*
Y954273D03*
Y950926D03*
X800258Y942561D03*
X801308Y947580D03*
X806550Y944234D03*
X812000Y947580D03*
Y954273D03*
Y967659D03*
X806500Y960966D03*
X812000Y957619D03*
Y971005D03*
Y964312D03*
Y960966D03*
X806500D03*
X812000Y967659D03*
Y974352D03*
Y981045D03*
Y987737D03*
Y984391D03*
Y977698D03*
Y974352D03*
Y981045D03*
Y994430D03*
Y1001123D03*
Y997777D03*
Y991084D03*
Y987737D03*
Y994430D03*
Y1001123D03*
Y1004470D03*
Y1027895D03*
D03*
Y1034588D03*
Y1041281D03*
Y1047974D03*
Y1044627D03*
Y1037934D03*
Y1031241D03*
Y1034588D03*
Y1041281D03*
Y1054667D03*
Y1061360D03*
Y1058013D03*
Y1051320D03*
Y1047974D03*
Y1054667D03*
Y1071399D03*
Y1064706D03*
Y1068052D03*
Y1074745D03*
Y1061360D03*
Y1071399D03*
Y1064706D03*
Y1078092D03*
Y1088131D03*
Y1084785D03*
X806550Y1081438D03*
X800258Y1089805D03*
X801308Y1084785D03*
X812000Y1078092D03*
Y1088131D03*
Y1084785D03*
Y1094824D03*
Y1101517D03*
Y1098171D03*
Y1104863D03*
X806550Y1091478D03*
X801308Y1094824D03*
X812000D03*
Y1101517D03*
Y1108210D03*
Y1114903D03*
Y1121596D03*
Y1111556D03*
X806550Y1118249D03*
X812000Y1108210D03*
Y1114903D03*
Y1131635D03*
Y1124942D03*
X806550Y1128289D03*
X800258Y1126616D03*
X801308Y1121596D03*
X812000Y1134982D03*
X801308Y1131635D03*
X812000D03*
Y1124942D03*
Y1121596D03*
Y1138328D03*
Y1145021D03*
Y1151714D03*
Y1148367D03*
Y1141675D03*
Y1138328D03*
Y1145021D03*
Y1161753D03*
Y1158407D03*
X806550Y1165100D03*
X800258Y1163427D03*
X806550Y1155060D03*
X801308Y1158407D03*
X812000Y1151714D03*
Y1161753D03*
Y1158407D03*
Y1168446D03*
Y1175139D03*
Y1181832D03*
Y1178486D03*
Y1171793D03*
X801308Y1168446D03*
X812000D03*
Y1175139D03*
Y1188525D03*
Y1195218D03*
Y1185178D03*
X806550Y1191871D03*
X812000Y1181832D03*
Y1188525D03*
Y1205257D03*
Y1198564D03*
Y1211950D03*
Y1208604D03*
X801308Y1195218D03*
X806550Y1201911D03*
X801308Y1205257D03*
X800258Y1200238D03*
X812000Y1205257D03*
Y1198564D03*
Y1195218D03*
Y1218643D03*
Y1225336D03*
Y1221989D03*
Y1215297D03*
Y1211950D03*
Y1218643D03*
Y1235375D03*
Y1232029D03*
X806550Y1228682D03*
X801308Y1232029D03*
X806550Y1238722D03*
X800258Y1237049D03*
X812000Y1225336D03*
Y1235375D03*
Y1232029D03*
Y1242068D03*
Y1248761D03*
Y1245415D03*
Y1252108D03*
X801308Y1242068D03*
X812000D03*
Y1248761D03*
X799280Y1296009D03*
X802030Y1296259D03*
X804530D03*
X807601Y1299241D03*
X799280Y1298509D03*
X802030Y1310259D03*
X804530D03*
X807601Y1307191D03*
X799280Y1301009D03*
X804099Y1333835D03*
X801171Y1343278D03*
X808469Y1356745D03*
Y1359245D03*
X810246Y1351988D03*
X799071Y1350088D03*
X810986Y1361684D03*
X807866Y1369177D03*
X805366Y1367093D03*
X802866D03*
X807866Y1366677D03*
X814296Y1384045D03*
Y1387445D03*
X811272Y1382752D03*
X811767Y1388154D03*
X808714Y1490376D03*
Y1487376D03*
Y1506784D03*
Y1519784D03*
Y1509784D03*
Y1516784D03*
X802150Y1570633D03*
Y1578633D03*
Y1582833D03*
X813150Y1579410D03*
Y1570633D03*
X802150Y1594633D03*
X810850Y1587733D03*
X810150Y1590633D03*
X813049D03*
X802700Y1587183D03*
X810150Y1602633D03*
Y1598633D03*
X802150Y1606633D03*
X822699Y56712D03*
X819321Y56961D03*
X819115Y115223D03*
X823115D03*
X821119Y134632D03*
X825699Y139062D03*
X824499Y145198D03*
X814571Y145952D03*
X814532Y139851D03*
X822635Y165468D03*
X825332Y166862D03*
X813676Y266065D03*
X816322Y284369D03*
X823067Y273225D03*
X823038Y276301D03*
X819828Y288063D03*
X827621Y302962D03*
X820405Y311830D03*
X822689Y305148D03*
X826915Y311842D03*
X822252Y309973D03*
X818677Y356405D03*
X826765Y356334D03*
X817780Y366905D03*
X823778Y376378D03*
X816991Y395337D03*
X820018Y403710D03*
X816281Y403814D03*
X828286Y401567D03*
X817497Y415344D03*
X827341Y419344D03*
X817497D03*
X827341Y415344D03*
X826665Y423425D03*
X826474Y431344D03*
X817497Y431060D03*
X826474Y435344D03*
X822878Y446425D03*
X816109Y455344D03*
X826912Y475989D03*
X817393Y491594D03*
X817426Y487232D03*
X826472Y483896D03*
X817996Y496219D03*
X828259Y501027D03*
X824500Y514500D03*
X817441Y517941D03*
X824380Y517595D03*
X822559Y530876D03*
X827237Y550771D03*
X817849Y550871D03*
X820620Y550846D03*
X824366Y552444D03*
X827832Y554269D03*
X814489Y558082D03*
X825200Y580300D03*
X815287Y580401D03*
X820617Y641273D03*
X816732Y629198D03*
X815753Y644219D03*
X817900Y649012D03*
X822579Y760169D03*
X822218Y756979D03*
X816500Y756832D03*
X822794Y767511D03*
X825390Y770020D03*
X822794Y777511D03*
X816550Y770218D03*
X822625Y763529D03*
X816500Y763525D03*
X822794Y772511D03*
Y775011D03*
X825061Y764884D03*
X822864Y783262D03*
X822772Y788359D03*
X822790Y785838D03*
X822555Y807409D03*
X822794Y797511D03*
Y800011D03*
Y795011D03*
X816400Y828781D03*
Y865592D03*
Y902403D03*
X823927Y907676D03*
X816400Y939214D03*
X823958Y936140D03*
X826958D03*
X823958Y939140D03*
X826958D03*
X827088Y933387D03*
X824036Y933394D03*
X826953Y930432D03*
X824003Y930319D03*
X816400Y1086458D03*
Y1123269D03*
Y1160080D03*
Y1196891D03*
Y1233702D03*
X828109Y1234504D03*
X826728Y1246315D03*
X824444Y1249420D03*
X826112Y1269546D03*
X828246Y1266501D03*
X814296Y1384045D03*
Y1387445D03*
X824714Y1490376D03*
Y1487376D03*
X816690Y1490376D03*
Y1487376D03*
X824714Y1500376D03*
Y1497376D03*
Y1506784D03*
X816717Y1500388D03*
X816729Y1497364D03*
X816693Y1506784D03*
X824714Y1519784D03*
Y1509784D03*
Y1516784D03*
X816706Y1519820D03*
X816693Y1516784D03*
X816694Y1509796D03*
X824714Y1529784D03*
Y1526784D03*
X816714Y1529784D03*
Y1526784D03*
X823850Y1556133D03*
X826850D03*
X820850Y1565133D03*
Y1562133D03*
Y1559133D03*
X826850Y1565133D03*
X823850D03*
X826850Y1562133D03*
Y1559133D03*
X823850Y1562133D03*
Y1559133D03*
X820850Y1571133D03*
Y1568133D03*
X826850Y1571133D03*
Y1568133D03*
X823850Y1571133D03*
Y1568133D03*
X821977Y1577233D03*
X827577D03*
X821977Y1582363D03*
X816150Y1587284D03*
X821977Y1587493D03*
X827577D03*
X821550Y1594533D03*
X827550Y1597533D03*
Y1594533D03*
X824550Y1597533D03*
Y1594533D03*
X821550Y1597533D03*
Y1600533D03*
X827550D03*
X824550D03*
X815550Y1606533D03*
X818550D03*
X821550Y1603533D03*
X818550D03*
X827550Y1606533D03*
X824550D03*
X821550D03*
X827550Y1603533D03*
X824550D03*
X817974Y1731920D03*
X833421Y-36647D03*
X839699Y-35341D03*
X833406Y-34132D03*
X836674Y-36661D03*
X836659Y-34146D03*
X833391Y-31617D03*
X833376Y-29102D03*
X836644Y-31631D03*
X836629Y-29116D03*
X842320Y-21711D03*
Y-18311D03*
Y-11711D03*
Y-21711D03*
Y-18311D03*
X833407Y-26181D03*
X836660Y-26167D03*
Y-16167D03*
X833407Y-16181D03*
X839700Y-14972D03*
X833422Y-13666D03*
X836675Y-13652D03*
X833412Y-19948D03*
X836674D03*
X836675Y-23652D03*
X833422Y-23666D03*
X839700Y-24972D03*
X842320Y-8311D03*
Y-11711D03*
Y-8311D03*
X833412Y52D03*
X836674D03*
X833412Y-9948D03*
X836674D03*
X836675Y-3652D03*
X833422Y-3666D03*
X839700Y-4972D03*
X833407Y-6181D03*
X836660Y-6167D03*
X842320Y11689D03*
Y8289D03*
Y18289D03*
Y11689D03*
Y8289D03*
X836675Y16348D03*
X833422Y16334D03*
X839700Y15028D03*
X833407Y13819D03*
X836660Y13833D03*
X836674Y10052D03*
X833412D03*
X836675Y6348D03*
X833422Y6334D03*
X839700Y5028D03*
X833407Y3819D03*
X836660Y3833D03*
X842320Y21689D03*
Y18289D03*
Y21689D03*
X836659Y24250D03*
X836674Y26765D03*
X833406Y24236D03*
X839699Y25445D03*
X833421Y26751D03*
X833376Y19206D03*
X833391Y21721D03*
X831456Y49379D03*
X828601Y61752D03*
X836127Y62681D03*
X837792Y85186D03*
X837251Y93221D03*
X834616Y94324D03*
X831115Y115223D03*
X839361Y114862D03*
X829115Y150273D03*
Y147123D03*
X838221Y163862D03*
X835221D03*
X842721Y181362D03*
X830340Y228143D03*
X837501Y229642D03*
X832525Y268579D03*
X836305Y268624D03*
X836163Y279355D03*
X829572Y296511D03*
X840288Y287593D03*
X829167Y288063D03*
X830418Y311865D03*
X837754Y335345D03*
X832686Y331028D03*
X829800Y331013D03*
X840457Y335368D03*
X842257Y350376D03*
X829344Y356224D03*
X833219Y375992D03*
X840357Y382813D03*
X836840Y382003D03*
X841862Y390441D03*
X833097Y393000D03*
X837912Y401545D03*
X834426Y401504D03*
X833000Y409500D03*
X838500D03*
X837847Y405347D03*
X833807Y423257D03*
X841809Y423219D03*
X829106Y439279D03*
X842825Y448739D03*
X828979Y449802D03*
X834106Y439279D03*
X828714Y443552D03*
X828751Y455344D03*
X834251Y459578D03*
X828751Y463578D03*
X834251Y455578D03*
X828751Y459344D03*
X832224Y450328D03*
X831381Y455167D03*
X833751Y463578D03*
X842825Y452739D03*
X828751Y471344D03*
X835425Y477890D03*
X828751Y467568D03*
X838575Y477554D03*
X839200Y467900D03*
X830046Y476031D03*
X838561Y484071D03*
X830743Y500740D03*
X833000Y503500D03*
X831798Y515314D03*
X839061Y555808D03*
X835519Y580056D03*
X831018Y583076D03*
X835059Y660940D03*
X837391Y659820D03*
X831756Y901318D03*
X832347Y1251703D03*
X835554Y1281324D03*
X832274Y1277301D03*
X832342Y1274626D03*
X835682Y1285472D03*
X836670Y1291355D03*
X836587Y1295333D03*
X842500Y1310000D03*
Y1306000D03*
Y1302000D03*
X834017Y1333584D03*
X834071Y1342457D03*
X834017Y1336252D03*
X839188Y1348937D03*
X833853Y1345833D03*
X841203Y1361376D03*
X838670Y1518558D03*
X841310Y1518608D03*
X838630Y1521538D03*
X841270Y1521588D03*
X835850Y1556133D03*
X829850D03*
X832850D03*
X838850D03*
X832850Y1565133D03*
X835850D03*
X832850Y1562133D03*
X835850D03*
X832850Y1559133D03*
X835850D03*
X829850Y1565133D03*
Y1562133D03*
Y1559133D03*
X838850Y1565133D03*
Y1562133D03*
Y1559133D03*
X841150Y1581379D03*
X832850Y1571133D03*
X835850D03*
X832850Y1568133D03*
X835850D03*
X829850Y1571133D03*
Y1568133D03*
X833077Y1577233D03*
Y1582363D03*
X838650Y1583347D03*
X833077Y1587493D03*
X830550Y1597533D03*
X833550D03*
X830550Y1594533D03*
X833550D03*
X830550Y1600533D03*
X833550D03*
X830550Y1603533D03*
X836550Y1606533D03*
Y1603533D03*
X833550D03*
X830550Y1606533D03*
X833550D03*
X839974Y1731920D03*
X844766Y-24648D03*
Y-15374D03*
Y-5374D03*
Y5352D03*
Y15352D03*
Y24626D03*
X853456Y49379D03*
X854108Y91232D03*
X843856Y87711D03*
X854578Y99651D03*
X854221Y135862D03*
Y129362D03*
X854201Y143062D03*
X848745Y160137D03*
X845721Y181362D03*
X849711Y212062D03*
X845221Y216532D03*
X855859Y212425D03*
X855934Y215375D03*
X854707Y229878D03*
X852207D03*
X853800Y265057D03*
X847939Y265092D03*
X853621Y269057D03*
X853829Y262057D03*
X846189Y281419D03*
X854334Y276117D03*
X854225Y280027D03*
Y283527D03*
X857334Y276117D03*
X852780Y291559D03*
X852801Y288562D03*
X853201Y297462D03*
X843504Y287602D03*
X855481Y299692D03*
X856701Y304862D03*
X856397Y339751D03*
Y344669D03*
X846275Y335575D03*
X843308Y335550D03*
X857187Y342210D03*
X848030Y338461D03*
X850155Y335042D03*
X852303Y337488D03*
X852177Y341882D03*
X848425Y378089D03*
X854552Y381000D03*
X849750Y401280D03*
X854190Y404035D03*
X855722Y416606D03*
X846000Y418862D03*
X854239Y412911D03*
X845986Y429413D03*
X857942Y448575D03*
X845100Y440100D03*
X857887Y459847D03*
X848500Y452128D03*
X852240Y470946D03*
X847686Y475915D03*
X846104Y494661D03*
X847518Y490905D03*
X846411Y482128D03*
X852209Y507211D03*
X855497Y507205D03*
X855837Y519713D03*
X849126Y530138D03*
X845126D03*
X845094Y535110D03*
X844741Y543864D03*
X843655Y555683D03*
X847435Y555496D03*
X856647Y616786D03*
X848660Y651127D03*
X854484Y647436D03*
X848999Y644995D03*
X846725Y1269785D03*
X846931Y1291468D03*
X846895Y1295981D03*
X845801Y1287776D03*
X851500Y1302000D03*
X851400Y1305499D03*
X852811Y1313450D03*
X852955Y1320320D03*
X856500Y1321500D03*
X853100Y1331688D03*
X856500Y1330500D03*
X852780Y1338365D03*
X856500Y1339500D03*
Y1348500D03*
X847007Y1521458D03*
X844367Y1521408D03*
Y1518784D03*
X847007Y1518834D03*
X855853Y1521308D03*
X853213Y1521258D03*
X850146Y1521261D03*
Y1518637D03*
X853213Y1518634D03*
X855853Y1518684D03*
X844150Y1578633D03*
Y1570633D03*
Y1582833D03*
X852150Y1574633D03*
X855150Y1579410D03*
Y1570633D03*
X844150Y1594633D03*
X852850Y1587733D03*
X852150Y1590633D03*
X855049D03*
X844700Y1587183D03*
X852150Y1602633D03*
Y1598633D03*
X844150Y1606633D03*
X857550Y1606533D03*
X858630Y60293D03*
X861351Y61672D03*
X863343Y90021D03*
X865912Y89252D03*
X870892Y131868D03*
X871145Y163862D03*
X858528Y262382D03*
X860834Y276817D03*
X863934Y276917D03*
X862044Y290047D03*
X870672Y295485D03*
X870008Y302273D03*
X872508D03*
X860152Y328399D03*
X865132D03*
X861377Y339751D03*
X865132Y333317D03*
X860152D03*
X861377Y344669D03*
X864342Y330858D03*
X860942D03*
X860587Y342210D03*
X860372Y375195D03*
X866168Y374774D03*
X871190Y382230D03*
X862075Y398537D03*
X858925D03*
X872020Y413300D03*
X864826Y411557D03*
X870220Y430424D03*
X870826Y423423D03*
X870064Y427703D03*
X859500Y429362D03*
X859469Y425293D03*
X860328Y475162D03*
X858288Y467048D03*
X860280Y488636D03*
X860299Y491620D03*
X860508Y497772D03*
X860341Y503154D03*
X860658Y515961D03*
X867356Y558714D03*
X867733Y575522D03*
X867590Y642420D03*
X864590D03*
X870590D03*
X866549Y748027D03*
X869406Y753541D03*
X872986Y753451D03*
X868539Y790882D03*
X865466Y790581D03*
Y785581D03*
Y788081D03*
Y783081D03*
Y793081D03*
Y795581D03*
Y798081D03*
X865569Y806045D03*
Y808545D03*
X864700Y836100D03*
X863369Y827461D03*
X863344Y824713D03*
X863372Y833469D03*
Y830718D03*
X867646Y833388D03*
X863671Y839062D03*
X865601Y841219D03*
X864020Y859972D03*
X864106Y863534D03*
X866005Y941554D03*
X863055Y941441D03*
X863010Y947262D03*
X866010D03*
X863010Y950262D03*
X866010D03*
X866140Y944509D03*
X863088Y944516D03*
X862044Y1249687D03*
X866294Y1255903D03*
X859446Y1284288D03*
X871214Y1466542D03*
X858581Y1518568D03*
X858567Y1521416D03*
X865850Y1556133D03*
X871850D03*
X868850D03*
X865850Y1565133D03*
Y1562133D03*
Y1559133D03*
X862850Y1565133D03*
Y1562133D03*
Y1559133D03*
X868850Y1565133D03*
X871850D03*
X868850Y1562133D03*
X871850D03*
X868850Y1559133D03*
X871850D03*
X865850Y1571133D03*
Y1568133D03*
X862850Y1571133D03*
Y1568133D03*
X868850Y1571133D03*
X871850D03*
X868850Y1568133D03*
X871850D03*
X863977Y1577233D03*
Y1582363D03*
X869577Y1577233D03*
X858150Y1587284D03*
X863977Y1587493D03*
X869577D03*
X863550Y1597533D03*
X866550Y1594533D03*
Y1597533D03*
X869550Y1594533D03*
Y1597533D03*
X863550Y1594533D03*
X872550D03*
Y1597533D03*
X866550Y1600533D03*
X869550D03*
X863550D03*
X872550D03*
Y1606533D03*
Y1603533D03*
X863550Y1606533D03*
X866550D03*
X869550D03*
X860550D03*
X869550Y1603533D03*
X866550D03*
X863550D03*
X860550D03*
X861974Y1731920D03*
X875345Y51595D03*
X876133Y73580D03*
Y95580D03*
Y117580D03*
X877462Y139540D03*
X876696Y176862D03*
Y171362D03*
X887521D03*
Y176862D03*
X878328Y183169D03*
X878221Y187449D03*
X887130Y183169D03*
X884986Y198829D03*
X880944Y283347D03*
X884004Y278712D03*
Y274482D03*
Y271332D03*
X880944Y286347D03*
X874244Y287047D03*
X873172Y295485D03*
X875447Y301500D03*
X884740Y316000D03*
X874500Y328000D03*
X877640Y315789D03*
X873884Y447991D03*
Y453383D03*
Y450491D03*
X885916Y653912D03*
X883731Y651690D03*
X883633Y790336D03*
X883776Y786814D03*
X877459Y802356D03*
X875412Y797350D03*
X882582Y1075083D03*
X879582D03*
X876582D03*
X873582D03*
X882582Y1061983D03*
X879582D03*
X876582D03*
Y1071533D03*
Y1068533D03*
Y1065533D03*
X873582D03*
Y1068533D03*
Y1071533D03*
Y1061983D03*
X874617Y1084657D03*
X877817D03*
Y1088057D03*
X874617D03*
X881217Y1084657D03*
Y1088057D03*
X874617Y1100957D03*
X877817D03*
Y1097557D03*
X874617D03*
X881217Y1100957D03*
Y1097557D03*
X886707Y1229920D03*
Y1232920D03*
X881807Y1238920D03*
X881694Y1229763D03*
Y1232763D03*
Y1235763D03*
X876907Y1235586D03*
Y1232586D03*
Y1229586D03*
X886707Y1254742D03*
Y1251742D03*
X881807Y1248920D03*
Y1245920D03*
X881937Y1251857D03*
X877480Y1248844D03*
X881807Y1241920D03*
X886707Y1257742D03*
X885000Y1307500D03*
X877936Y1312336D03*
X877000Y1340241D03*
X875039Y1407246D03*
X886362Y1428973D03*
X884399Y1431507D03*
X879424Y1425001D03*
X883279Y1421726D03*
X884462Y1446974D03*
X876044Y1444317D03*
X883562Y1440356D03*
X887117Y1436735D03*
X877850Y1556133D03*
X874850D03*
X880850D03*
X874850Y1565133D03*
X877850D03*
X880850D03*
X874850Y1562133D03*
X877850D03*
X880850D03*
X874850Y1559133D03*
X877850D03*
X880850D03*
X886150Y1578633D03*
Y1570633D03*
Y1582833D03*
X883150Y1581379D03*
X874850Y1571133D03*
X877850D03*
X874850Y1568133D03*
X877850D03*
X875077Y1577233D03*
Y1582363D03*
X886150Y1594633D03*
X880650Y1583347D03*
X886700Y1587183D03*
X875077Y1587493D03*
X875550Y1597533D03*
Y1594533D03*
X886150Y1606633D03*
X875550Y1600533D03*
Y1606533D03*
X878550D03*
Y1603533D03*
X875550D03*
X883974Y1731920D03*
X898720Y145206D03*
X891621Y207162D03*
X888930Y206823D03*
X891621Y209662D03*
X888930Y209323D03*
X896621Y207162D03*
X894121D03*
Y209662D03*
X896621D03*
X888560Y469527D03*
X892376Y466430D03*
X899000Y481038D03*
X888372Y547518D03*
X902376Y594657D03*
X899678Y601043D03*
X900323Y604377D03*
X900301Y828248D03*
Y831221D03*
X899500Y853000D03*
X897824Y909093D03*
X901000Y909000D03*
X901842Y936863D03*
X889057Y1053133D03*
X898000Y1112336D03*
Y1109736D03*
Y1116544D03*
Y1119144D03*
Y1130160D03*
Y1132760D03*
Y1123352D03*
Y1125952D03*
X889273Y1134470D03*
X891648Y1137843D03*
X900723Y1146553D03*
X902382Y1137558D03*
X891996Y1149707D03*
X902482Y1140558D03*
X897754Y1156119D03*
X888247Y1219520D03*
Y1222520D03*
X891247D03*
X888247Y1225520D03*
X896974Y1232869D03*
Y1235869D03*
X896907Y1238920D03*
X891247Y1225520D03*
X896107Y1254742D03*
Y1251742D03*
X896907Y1245920D03*
Y1248920D03*
Y1241920D03*
X896107Y1257742D03*
X892000Y1307500D03*
X888854Y1337936D03*
X890620Y1342990D03*
X900885Y1435041D03*
X900808Y1437798D03*
X902377Y1456465D03*
X894150Y1574633D03*
X897150Y1579410D03*
Y1570633D03*
X894150Y1590633D03*
X894850Y1587733D03*
X897049Y1590633D03*
X900150Y1587284D03*
X894150Y1598633D03*
X899550Y1606533D03*
X902550Y1603533D03*
Y1606533D03*
X917386Y179500D03*
Y177000D03*
Y169500D03*
Y172000D03*
Y174500D03*
Y167000D03*
X909298Y195925D03*
X908621Y188899D03*
X909161Y203012D03*
X909320Y210098D03*
Y217185D03*
Y224271D03*
Y231358D03*
X910267Y242658D03*
X910093Y246015D03*
X916268Y269859D03*
Y277859D03*
X909023Y294734D03*
X910752Y286141D03*
X913512Y486743D03*
X903340Y505105D03*
X917582Y549564D03*
X906597Y579695D03*
X909747D03*
X911980Y585280D03*
X907035Y590172D03*
X910731Y590251D03*
X905526Y594657D03*
X906597Y628426D03*
X906734Y619373D03*
X910535Y619251D03*
X906706Y614062D03*
X909747Y628426D03*
X915334Y639166D03*
X908823Y655116D03*
X906274Y654921D03*
X906570Y663930D03*
X909320D03*
X907207Y667646D03*
X906345Y742414D03*
X904535Y744639D03*
X906387Y818471D03*
Y821221D03*
Y815721D03*
X906313Y825095D03*
X903149Y825094D03*
X917000Y853000D03*
X903941Y874000D03*
X917622Y887545D03*
X909000Y909000D03*
X905000D03*
X907000Y899777D03*
X913000Y909000D03*
X917000D03*
X904719Y921792D03*
X917000Y918500D03*
X905000D03*
X911500Y931000D03*
X908500Y927500D03*
X909890Y950217D03*
X910000Y954500D03*
X912425Y948500D03*
X907075D03*
X910066Y960332D03*
X909203Y970709D03*
X910000Y957500D03*
X916763Y972343D03*
X908799Y985291D03*
X911041Y979459D03*
X909000Y977491D03*
X916880Y1138969D03*
X906473Y1158574D03*
X915053Y1219520D03*
Y1222520D03*
X912053D03*
Y1219520D03*
X915053Y1225520D03*
X910707Y1229920D03*
Y1232920D03*
X905007Y1238920D03*
X905008Y1229940D03*
Y1232940D03*
Y1235940D03*
X910707Y1254742D03*
Y1251742D03*
X905007Y1248920D03*
Y1245920D03*
X905074Y1252177D03*
X905007Y1241920D03*
X910707Y1257742D03*
X903980Y1268420D03*
X917112Y1266300D03*
X904024Y1272692D03*
X903947Y1276968D03*
X903899Y1281203D03*
X917127Y1275251D03*
X917396Y1271025D03*
X917158Y1279451D03*
X917341Y1283775D03*
X903945Y1285420D03*
X903923Y1289630D03*
X903651Y1293853D03*
X903690Y1298027D03*
X916895Y1292330D03*
X916945Y1296713D03*
X917034Y1288235D03*
X912500Y1310000D03*
X914333Y1322700D03*
X914462Y1329351D03*
X914355Y1340726D03*
X914276Y1347550D03*
X913270Y1440429D03*
X910041Y1440536D03*
X907031Y1457231D03*
X909473Y1448779D03*
X910850Y1556133D03*
X907850D03*
X916850D03*
X913850D03*
X907850Y1559133D03*
Y1562133D03*
X910850Y1559133D03*
Y1562133D03*
X907850Y1565133D03*
X910850D03*
X904850Y1559133D03*
Y1562133D03*
Y1565133D03*
X913850Y1559133D03*
Y1562133D03*
Y1565133D03*
X916850Y1559133D03*
Y1562133D03*
Y1565133D03*
X907850Y1568133D03*
Y1571133D03*
X910850Y1568133D03*
Y1571133D03*
X904850Y1568133D03*
Y1571133D03*
X913850Y1568133D03*
Y1571133D03*
X916850Y1568133D03*
Y1571133D03*
X905977Y1577233D03*
Y1582363D03*
X911577Y1577233D03*
X917077D03*
Y1582363D03*
X905977Y1587493D03*
X911577D03*
X917077D03*
X914550Y1597533D03*
Y1594533D03*
X905550D03*
X911550Y1597533D03*
Y1594533D03*
X908550Y1597533D03*
Y1594533D03*
X905550Y1597533D03*
X917550D03*
Y1594533D03*
X914550Y1600533D03*
X905550D03*
X911550D03*
X908550D03*
X917550D03*
X914550Y1603533D03*
Y1606533D03*
X905550Y1603533D03*
X908550D03*
X911550D03*
Y1606533D03*
X908550D03*
X905550D03*
X917550Y1603533D03*
Y1606533D03*
X915991Y1667328D03*
X905974Y1731920D03*
X920720Y145206D03*
X919886Y167000D03*
Y169500D03*
Y172000D03*
Y174500D03*
Y177000D03*
Y179500D03*
X927134Y189386D03*
X925321Y203399D03*
X932129Y244103D03*
X928224Y264072D03*
X922341Y263875D03*
X923103Y362852D03*
X924724Y372211D03*
X919294Y374503D03*
X921318Y372475D03*
X920018Y362877D03*
X921430Y507156D03*
X921367Y503407D03*
X924430Y507156D03*
X924367Y503407D03*
X922591Y496671D03*
X926730Y540897D03*
X921318Y549357D03*
X930406Y577308D03*
X923747Y584945D03*
X920989Y614132D03*
X925643Y616620D03*
X927127Y619251D03*
X924987Y622523D03*
X923916Y843990D03*
X932000Y850500D03*
X918500Y856925D03*
X930925Y860925D03*
X930575Y864075D03*
X918500Y860075D03*
X920897Y881879D03*
X929603Y879000D03*
Y889000D03*
X931948Y891397D03*
X920000Y895500D03*
X923000D03*
X919916Y908916D03*
X920276Y900554D03*
X925500Y907500D03*
X931877Y918168D03*
X928535Y913454D03*
X920409Y918274D03*
X921000Y921925D03*
X925500Y916500D03*
X929500D03*
X918000Y928000D03*
X926062Y938727D03*
X932500Y941500D03*
X919500D03*
X926004Y952716D03*
X926000Y949500D03*
Y946500D03*
X919272Y989932D03*
Y986782D03*
X925200Y1110443D03*
Y1107843D03*
Y1117443D03*
Y1114843D03*
Y1124443D03*
Y1121843D03*
Y1131443D03*
Y1128843D03*
X921477Y1134647D03*
X925525Y1135172D03*
X919880Y1146569D03*
Y1139969D03*
Y1143369D03*
Y1149769D03*
X922880Y1146569D03*
Y1139969D03*
Y1143369D03*
Y1149769D03*
X919077Y1136521D03*
X923125Y1137046D03*
X919880Y1152769D03*
X920107Y1235920D03*
Y1232920D03*
Y1238920D03*
Y1251742D03*
Y1254742D03*
Y1248920D03*
Y1245920D03*
Y1241920D03*
Y1257742D03*
X928751Y1266347D03*
X928901Y1270408D03*
X928852Y1274591D03*
X928979Y1278713D03*
X928827Y1283048D03*
X928928Y1287193D03*
X928906Y1291676D03*
X928983Y1295957D03*
X924000Y1310000D03*
X924500Y1306000D03*
Y1302000D03*
X918000Y1312500D03*
X920738Y1321363D03*
X927869Y1317417D03*
X918000Y1321500D03*
X925459Y1315352D03*
X925500Y1319000D03*
X922000Y1328000D03*
X923680Y1339520D03*
X918000Y1330500D03*
Y1339500D03*
X922000Y1342000D03*
X925500Y1337000D03*
X919758Y1348990D03*
X922000Y1346000D03*
X922850Y1556133D03*
X919850D03*
X922850Y1559133D03*
Y1562133D03*
Y1565133D03*
X919850Y1559133D03*
Y1562133D03*
Y1565133D03*
X925650Y1581379D03*
X919850Y1568133D03*
Y1571133D03*
X922650Y1583347D03*
X920550Y1603533D03*
Y1606533D03*
X931798Y1660762D03*
X923798D03*
X921289Y1663187D03*
Y1666337D03*
X927798Y1660762D03*
X927974Y1731920D03*
X945721Y173389D03*
X943221D03*
Y176389D03*
X945721D03*
X935551Y173329D03*
X938161Y173389D03*
Y176389D03*
X935591Y176049D03*
X940721Y173389D03*
Y176389D03*
X935497Y195925D03*
X939271Y191419D03*
X935771D03*
X944520Y182094D03*
X935497Y210098D03*
Y203012D03*
Y224272D03*
Y217185D03*
X938570Y233152D03*
X945380Y233962D03*
X935497Y231358D03*
X942763Y272340D03*
X942779Y277731D03*
X939938Y386423D03*
X933390Y386405D03*
X944112Y386593D03*
X941764Y420403D03*
X944264D03*
X933390Y559943D03*
X939613Y562031D03*
X934302Y578318D03*
X941764Y587884D03*
X944264D03*
X935766Y587692D03*
X945006Y593609D03*
X935649Y590751D03*
X939391Y600571D03*
X935783Y634051D03*
X937580Y655946D03*
X946366Y668811D03*
X934539Y664648D03*
X934339Y668533D03*
X941478Y668648D03*
X940391Y859947D03*
X944057Y882886D03*
X934925Y891425D03*
X945075Y891500D03*
X938500Y907500D03*
X940514Y918134D03*
X946500Y915988D03*
X938500Y916500D03*
X934500D03*
X942500Y916340D03*
X933021Y933979D03*
X935368Y939182D03*
X944515Y939850D03*
X939670Y945169D03*
X942924Y982547D03*
X943135Y977129D03*
X940000Y973500D03*
Y986500D03*
Y982500D03*
Y977500D03*
X941000Y1110557D03*
Y1107957D03*
Y1117557D03*
Y1114957D03*
Y1124557D03*
Y1121957D03*
Y1131557D03*
Y1128957D03*
X938507Y1137843D03*
X933234Y1145058D03*
X936393Y1148087D03*
X944820Y1156119D03*
X943101Y1219520D03*
Y1222520D03*
X946101D03*
X943101Y1225520D03*
X946101D03*
X945691Y1229920D03*
Y1232920D03*
X940791Y1238920D03*
X940678Y1229763D03*
Y1232763D03*
Y1235763D03*
X935891Y1235586D03*
Y1232586D03*
Y1229586D03*
X945691Y1254742D03*
Y1251742D03*
X940791Y1248920D03*
Y1245920D03*
X940921Y1251857D03*
X936464Y1248844D03*
X940791Y1241920D03*
X945691Y1257742D03*
X940994Y1265636D03*
X941011Y1269499D03*
X941500Y1278059D03*
X941033Y1282115D03*
X946730Y1293219D03*
Y1290719D03*
X940919Y1290152D03*
X940937Y1294191D03*
X941083Y1286156D03*
X947135Y1287403D03*
X938000Y1309500D03*
Y1301500D03*
Y1304500D03*
X945872Y1304541D03*
Y1301500D03*
X945617Y1309500D03*
X933586Y1325501D03*
X933041Y1315920D03*
X935300Y1317525D03*
X939071Y1448219D03*
X936693Y1462328D03*
X939507Y1462497D03*
X945195Y1459453D03*
X942056Y1459650D03*
X939416Y1459600D03*
Y1456976D03*
X942056Y1457026D03*
X945195Y1456829D03*
X946402Y1491204D03*
X943902D03*
X936402D03*
X938902D03*
X941402D03*
X933778D03*
X946402Y1501204D03*
Y1498704D03*
Y1496204D03*
Y1493704D03*
X943902D03*
Y1496204D03*
Y1498704D03*
Y1501204D03*
X936402Y1493704D03*
Y1496204D03*
Y1498704D03*
Y1501204D03*
X938902Y1493704D03*
Y1496204D03*
Y1498704D03*
Y1501204D03*
X941402Y1493704D03*
Y1496204D03*
Y1498704D03*
Y1501204D03*
X933778Y1493704D03*
Y1496204D03*
Y1498704D03*
Y1501204D03*
X944406Y1532791D03*
X936150Y1582233D03*
Y1578233D03*
Y1590233D03*
Y1586233D03*
X939798Y1660762D03*
X943798D03*
X957421Y157699D03*
X960421D03*
X962243Y179917D03*
X948401Y176499D03*
X950950Y284662D03*
X947821Y386567D03*
X958158Y449020D03*
X958049Y453912D03*
X958101Y457846D03*
X958255Y465811D03*
X959033Y487289D03*
X957380Y515233D03*
X960054Y516982D03*
X962035Y518988D03*
X954757Y593045D03*
X948156Y593912D03*
X955529Y614017D03*
X952497Y614080D03*
X951099Y632206D03*
X954362Y633314D03*
Y630061D03*
X954259Y657371D03*
X958299Y659886D03*
X954361Y660215D03*
X957462Y668700D03*
X951839Y812730D03*
X951895Y808163D03*
X961592Y821737D03*
X949000Y850500D03*
X958051Y859384D03*
X951000Y855425D03*
X958000Y865500D03*
Y862000D03*
X952425Y876575D03*
X949500Y870500D03*
X948060Y891468D03*
X949500Y886500D03*
X953925Y900500D03*
X951169Y910425D03*
X957075Y906500D03*
X960925D03*
X951367Y913648D03*
X954500Y915988D03*
X950500Y916150D03*
X951500Y930925D03*
X948500Y937000D03*
X947748Y1146553D03*
X949407Y1137558D03*
X949507Y1140558D03*
X953498Y1158574D03*
X955958Y1232869D03*
Y1235869D03*
X955891Y1238920D03*
X955091Y1254742D03*
Y1251742D03*
X955891Y1245920D03*
Y1248920D03*
Y1241920D03*
X955000Y1267000D03*
X955091Y1257742D03*
X955000Y1271000D03*
Y1275000D03*
Y1279000D03*
Y1283000D03*
Y1287000D03*
X947650Y1314500D03*
Y1319000D03*
Y1323500D03*
Y1328000D03*
Y1337000D03*
Y1332500D03*
Y1341500D03*
Y1346000D03*
X960313Y1362654D03*
X958306Y1448056D03*
X956693Y1459805D03*
X953630Y1456760D03*
X958383Y1462447D03*
X950902Y1459500D03*
X948262Y1459450D03*
X953616Y1459608D03*
X948262Y1456826D03*
X950902Y1456876D03*
X953902Y1491204D03*
X951402D03*
X948902D03*
X956402D03*
X958902D03*
X961402D03*
X953902Y1501204D03*
Y1498704D03*
Y1496204D03*
Y1493704D03*
X951402Y1501204D03*
Y1498704D03*
Y1496204D03*
Y1493704D03*
X948902Y1501204D03*
Y1498704D03*
Y1496204D03*
Y1493704D03*
X956402D03*
X958902D03*
X961402D03*
X955350Y1532760D03*
X961350D03*
X958350D03*
X953520Y1567570D03*
X950520D03*
X959520D03*
X956520D03*
X953520Y1582570D03*
X950520D03*
Y1579570D03*
X953520D03*
Y1576570D03*
X950520D03*
X953520Y1573570D03*
X950520D03*
Y1570570D03*
X953520D03*
X959520Y1582570D03*
X956520D03*
Y1579570D03*
X959520D03*
Y1576570D03*
X956520D03*
X959520Y1573570D03*
X956520D03*
Y1570570D03*
X959520D03*
X953520Y1588570D03*
X950520D03*
Y1585570D03*
X953520D03*
X959520Y1588570D03*
X956520D03*
Y1585570D03*
X959520D03*
X960518Y1656185D03*
X957758D03*
X949195Y1655145D03*
X957848Y1659375D03*
X960608D03*
X960558Y1662015D03*
X957798D03*
X947798Y1660762D03*
X951798D03*
X949974Y1731920D03*
X964720Y145206D03*
X975689Y156950D03*
Y153950D03*
X975691Y161220D03*
X964743Y179917D03*
X963985Y177154D03*
X962673Y170263D03*
Y167763D03*
X967943Y204813D03*
X971943D03*
X975749Y202049D03*
X977221Y205399D03*
X964807Y205125D03*
X971192Y219589D03*
X968692D03*
X973616Y317648D03*
X973997Y320848D03*
X966278Y556736D03*
X964114Y554704D03*
X976528Y801041D03*
Y803541D03*
Y806041D03*
Y808541D03*
X963500Y854719D03*
X973562Y859767D03*
X963134Y882936D03*
X964075Y900500D03*
X977150Y1052684D03*
X968919Y1116177D03*
Y1118777D03*
Y1109177D03*
Y1111777D03*
X968800Y1130046D03*
Y1132646D03*
X968919Y1123177D03*
Y1125777D03*
X967315Y1135550D03*
X972109Y1135149D03*
X966905Y1146569D03*
X969905D03*
X966905Y1139969D03*
Y1143369D03*
X969905Y1139969D03*
Y1143369D03*
X966905Y1149769D03*
X969905D03*
X963012Y1139511D03*
X964915Y1137424D03*
X969709Y1137023D03*
X966905Y1152769D03*
X966804Y1155658D03*
X969907Y1219520D03*
Y1222520D03*
X966907D03*
Y1219520D03*
X969907Y1225520D03*
X969691Y1229920D03*
Y1232920D03*
X963991Y1238920D03*
X963992Y1229940D03*
Y1232940D03*
Y1235940D03*
X969691Y1254742D03*
Y1251742D03*
X963991Y1248920D03*
Y1245920D03*
X964058Y1252177D03*
X963991Y1241920D03*
X969691Y1257742D03*
X964000Y1267000D03*
X966441Y1278145D03*
X968594Y1288193D03*
X975000Y1307500D03*
X966000Y1300000D03*
X968500D03*
X971000D03*
X972408Y1312557D03*
X967500Y1340241D03*
X973650Y1431424D03*
X969785Y1447987D03*
X967002Y1448013D03*
X964503Y1448097D03*
X975703Y1451367D03*
X967268Y1491204D03*
X969768D03*
X972268D03*
X974768D03*
X977268D03*
X963902D03*
X967268Y1501204D03*
Y1498704D03*
Y1496204D03*
Y1493704D03*
X969768D03*
Y1496204D03*
Y1498704D03*
Y1501204D03*
X972268Y1493704D03*
Y1496204D03*
Y1498704D03*
Y1501204D03*
X974768Y1493704D03*
Y1496204D03*
Y1498704D03*
Y1501204D03*
X977268Y1493704D03*
Y1496204D03*
Y1498704D03*
Y1501204D03*
X963902Y1493704D03*
X963120Y1520080D03*
Y1523080D03*
X967350Y1532760D03*
X964350D03*
X963120Y1526080D03*
X962584Y1550824D03*
X965520Y1567570D03*
X962520D03*
X968520D03*
X965520Y1582570D03*
X962520D03*
Y1579570D03*
X965520D03*
Y1576570D03*
X962520D03*
X965520Y1573570D03*
X962520D03*
Y1570570D03*
X965520D03*
X968520Y1582570D03*
Y1579570D03*
Y1576570D03*
Y1573570D03*
Y1570570D03*
X965520Y1588570D03*
X962520D03*
Y1585570D03*
X965520D03*
X968520Y1588570D03*
Y1585570D03*
X976858Y1656185D03*
X976898Y1662015D03*
X976948Y1659375D03*
X971974Y1731920D03*
X986720Y145206D03*
X981112Y161204D03*
X988593Y189347D03*
X981445Y185389D03*
X985445D03*
X986021Y195099D03*
X979849Y202049D03*
X983879Y202162D03*
X990221Y199699D03*
X987321Y198599D03*
Y202099D03*
X990221Y206699D03*
Y203199D03*
X987321Y205599D03*
X991553Y216809D03*
X980406Y218283D03*
X980377Y215740D03*
X982455Y264781D03*
X978269Y264929D03*
X982455Y275443D03*
X978827Y303412D03*
X989582Y303563D03*
X988460Y354725D03*
X984272Y349293D03*
X980346Y353527D03*
X981019Y349387D03*
X992233Y373679D03*
X989227Y389311D03*
X984605Y408480D03*
X987581Y408332D03*
X988190Y424626D03*
X983358Y449026D03*
X991664Y446372D03*
X992037Y485369D03*
X990292Y494420D03*
X986790Y480140D03*
X987440Y504742D03*
X982806Y498606D03*
X986056Y516014D03*
X991031Y528574D03*
X992125Y1061434D03*
X989125D03*
X986125D03*
X983125D03*
X992125Y1064984D03*
Y1067984D03*
X989125D03*
Y1064984D03*
X992125Y1074534D03*
Y1070984D03*
X989125D03*
Y1074534D03*
X986125D03*
X983125D03*
X986356Y1087508D03*
X983156D03*
Y1084108D03*
X986356D03*
X989556Y1087508D03*
Y1084108D03*
X986356Y1097008D03*
X983156D03*
Y1100408D03*
X986356D03*
X989556Y1097008D03*
Y1100408D03*
X979091Y1235920D03*
Y1232920D03*
Y1238920D03*
Y1251742D03*
Y1254742D03*
Y1248920D03*
Y1245920D03*
Y1241920D03*
Y1257742D03*
X985396Y1268154D03*
X978318Y1263128D03*
X979228Y1297918D03*
X982000Y1307500D03*
X978026Y1459998D03*
X990634Y1491204D03*
X979768D03*
X982268D03*
X984768D03*
X987268D03*
X990634Y1493704D03*
Y1496204D03*
Y1498704D03*
Y1501204D03*
X979768Y1493704D03*
X982268D03*
X984768D03*
X987268D03*
X986768Y1501204D03*
X986486Y1523080D03*
Y1520080D03*
Y1526080D03*
X991280Y1532760D03*
X988280D03*
X988160Y1567710D03*
X991160D03*
X985160D03*
X988160Y1582710D03*
X991160D03*
X985160D03*
Y1579710D03*
X991160D03*
X988160D03*
X991160Y1570710D03*
X988160D03*
Y1573710D03*
X991160D03*
X988160Y1576710D03*
X991160D03*
X985160Y1570710D03*
Y1573710D03*
Y1576710D03*
X988160Y1588710D03*
X991160D03*
X985160D03*
Y1585710D03*
X991160D03*
X988160D03*
X985318Y1656105D03*
X988078D03*
X979618Y1656185D03*
X985358Y1661935D03*
X988118D03*
X985408Y1659295D03*
X988168D03*
X979658Y1662015D03*
X979708Y1659375D03*
X999736Y157943D03*
X1006221Y164799D03*
X1002721D03*
X1005307Y155043D03*
X999580Y154895D03*
X994257D03*
X993306Y174953D03*
X993206Y178053D03*
X1006436Y176843D03*
X999916Y184548D03*
X996416D03*
X992506Y184553D03*
X998206Y196191D03*
X1000706D03*
X999221Y189299D03*
X1002721D03*
X1006161Y189019D03*
X998206Y199735D03*
X1000706D03*
X998206Y206821D03*
X1000706D03*
X998206Y203278D03*
X1000706D03*
X1000611Y215039D03*
X1001196Y223898D03*
X995189Y263340D03*
Y274002D03*
X992915Y280389D03*
X993460Y354725D03*
X998460D03*
X994409Y349813D03*
X1007083Y363461D03*
X997488Y370287D03*
X1007080Y367087D03*
X999320Y394480D03*
X1006763Y396206D03*
X996232Y424440D03*
X1003651Y433426D03*
X998859Y437141D03*
X994900Y446192D03*
X998359Y462675D03*
Y457175D03*
Y479175D03*
Y468175D03*
Y473675D03*
Y484675D03*
X1007077Y484937D03*
X998326Y499675D03*
X995530Y500034D03*
X998056Y518214D03*
Y523874D03*
X1006206Y510304D03*
X999031Y528574D03*
X1004527Y541924D03*
Y553224D03*
X1005270Y625710D03*
X1007587Y761546D03*
Y764946D03*
Y772480D03*
Y775880D03*
Y783482D03*
Y786882D03*
Y794484D03*
Y805418D03*
Y797884D03*
Y808818D03*
Y816352D03*
Y819752D03*
Y827354D03*
Y830754D03*
Y838356D03*
Y841756D03*
X1003090Y1037329D03*
X999894Y1267126D03*
X999303Y1285693D03*
X999350Y1310500D03*
Y1315000D03*
Y1319420D03*
Y1323840D03*
Y1328260D03*
Y1332740D03*
Y1341580D03*
Y1337160D03*
Y1346000D03*
X995500Y1368000D03*
X998000Y1365500D03*
X1000634Y1491204D03*
X998134D03*
X995634D03*
X993134D03*
X1003134D03*
X1005634D03*
X993134Y1496204D03*
Y1493704D03*
X1003134D03*
X1005634D03*
X1000634Y1501204D03*
Y1498704D03*
Y1496204D03*
Y1493704D03*
X998134Y1501204D03*
Y1498704D03*
Y1496204D03*
Y1493704D03*
X995634Y1501204D03*
Y1498704D03*
Y1496204D03*
Y1493704D03*
X993134Y1501204D03*
Y1498704D03*
X994280Y1532760D03*
X997280D03*
X1000280D03*
X994196Y1550840D03*
X994160Y1567710D03*
X997160D03*
X1000160D03*
X994160Y1582710D03*
X997160D03*
Y1579710D03*
X994160D03*
X997160Y1570710D03*
X994160D03*
Y1573710D03*
X997160D03*
X994160Y1576710D03*
X997160D03*
X1000160Y1582710D03*
Y1579710D03*
Y1570710D03*
Y1573710D03*
Y1576710D03*
X994160Y1588710D03*
X997160D03*
Y1585710D03*
X994160D03*
X1000160Y1588710D03*
Y1585710D03*
X1004418Y1656105D03*
X1007178D03*
X1004508Y1659295D03*
X1004458Y1661935D03*
X993974Y1731920D03*
X1021899Y61590D03*
Y127590D03*
X1008720Y145206D03*
X1020661Y146580D03*
X1009721Y164799D03*
X1013221D03*
X1014301Y179699D03*
X1017201D03*
X1019901Y179799D03*
X1011358Y195324D03*
X1011991Y189019D03*
X1014901Y189299D03*
X1017701Y189059D03*
X1020521Y194499D03*
X1008068Y198387D03*
X1019936Y207333D03*
Y210463D03*
X1019803Y218099D03*
X1019531Y230423D03*
X1021220Y243638D03*
X1012220D03*
X1018220D03*
X1015220D03*
X1009220D03*
X1007669Y268884D03*
Y258222D03*
X1014828Y268427D03*
Y258970D03*
X1013396Y280806D03*
X1011423Y282889D03*
X1017870Y294386D03*
X1017835Y291236D03*
X1016764Y350082D03*
X1010252Y363440D03*
X1009618Y396125D03*
X1021425Y404925D03*
X1013365Y433426D03*
X1020748Y425902D03*
X1008789Y488642D03*
Y493655D03*
X1014206Y510304D03*
X1013306Y518146D03*
Y526146D03*
Y528942D03*
X1012211Y547574D03*
X1015061D03*
X1017718Y541201D03*
X1009611Y550074D03*
Y545074D03*
X1015961Y554432D03*
X1021425Y568614D03*
X1012925Y558000D03*
X1011602Y568473D03*
X1016000Y563107D03*
X1019261Y571324D03*
X1007703Y759012D03*
X1007587Y761546D03*
Y767480D03*
Y769980D03*
Y772480D03*
Y775880D03*
Y764946D03*
Y780880D03*
Y778380D03*
Y789484D03*
Y791984D03*
Y783482D03*
Y786882D03*
Y800384D03*
Y802884D03*
Y805418D03*
Y794484D03*
Y797884D03*
Y811352D03*
Y813852D03*
Y822252D03*
Y816352D03*
Y819752D03*
Y808818D03*
Y824752D03*
Y833356D03*
Y835856D03*
Y827354D03*
Y830754D03*
Y844256D03*
Y838356D03*
Y841756D03*
X1010894Y1271743D03*
X1010865Y1275768D03*
X1010944Y1279751D03*
X1021908Y1289124D03*
X1019314Y1289159D03*
X1017069Y1290346D03*
X1013500Y1312500D03*
X1013000Y1306500D03*
X1010650Y1310500D03*
X1016000Y1303000D03*
X1009896Y1301500D03*
X1013500Y1325500D03*
X1013605Y1316050D03*
X1013529Y1318950D03*
X1012500Y1328500D03*
X1011500Y1335000D03*
X1013500Y1337160D03*
Y1344500D03*
X1021500Y1491204D03*
X1019000D03*
X1016500D03*
X1014000D03*
X1008134D03*
X1010634D03*
X1021500Y1501204D03*
Y1498704D03*
Y1496204D03*
Y1493704D03*
X1019000Y1501204D03*
Y1498704D03*
Y1496204D03*
Y1493704D03*
X1016500Y1501204D03*
Y1498704D03*
Y1496204D03*
Y1493704D03*
X1014000D03*
Y1496204D03*
Y1498704D03*
Y1501204D03*
X1008134Y1493704D03*
X1010634D03*
X1010134Y1501204D03*
X1009852Y1523080D03*
Y1520080D03*
Y1526080D03*
X1019440Y1532930D03*
X1016750Y1567710D03*
X1019750D03*
X1016750Y1576710D03*
Y1573710D03*
Y1570710D03*
X1019750Y1576710D03*
Y1573710D03*
Y1570710D03*
Y1579710D03*
X1016750D03*
Y1582710D03*
X1019750D03*
Y1585710D03*
X1016750D03*
Y1588710D03*
X1019750D03*
X1007268Y1659295D03*
X1007218Y1661935D03*
X1015974Y1731920D03*
X1023187Y146580D03*
X1022801Y179799D03*
X1027690Y237902D03*
X1024220Y243638D03*
X1033590Y298311D03*
Y287311D03*
X1029200Y351614D03*
X1022674Y357848D03*
X1028146Y355960D03*
X1027724Y397726D03*
X1030525Y391362D03*
X1029601Y394387D03*
X1034855Y411704D03*
X1024443Y424051D03*
X1034899Y444404D03*
X1025830Y449022D03*
X1027760Y451832D03*
X1023320Y451112D03*
X1035860Y485976D03*
X1027504Y485637D03*
X1024546Y511254D03*
X1032354Y538201D03*
X1022686D03*
X1027520Y552724D03*
X1034412Y567416D03*
X1022461Y558932D03*
X1027579D03*
X1032579Y559934D03*
X1031000Y568500D03*
X1024000Y563000D03*
X1029431Y587342D03*
X1032055Y587260D03*
X1028540Y621000D03*
X1035269Y735474D03*
X1032736Y735320D03*
X1030190Y735023D03*
X1025493Y758819D03*
X1035026Y756009D03*
X1025493Y768719D03*
X1035645Y773582D03*
X1033236Y1279287D03*
X1033184Y1275996D03*
X1036411Y1275658D03*
X1036463Y1278949D03*
X1024000Y1491204D03*
X1026500D03*
X1029000D03*
X1031500D03*
X1034000D03*
X1024000Y1501204D03*
Y1498704D03*
Y1496204D03*
Y1493704D03*
X1026500D03*
X1029000D03*
X1031500D03*
X1034000D03*
X1033500Y1501204D03*
X1033218Y1523080D03*
Y1520080D03*
X1025440Y1532930D03*
X1022440D03*
X1033218Y1526080D03*
X1031440Y1532930D03*
X1028440D03*
X1025796Y1550840D03*
X1022750Y1567710D03*
X1025750D03*
X1031750D03*
X1028750D03*
X1022750Y1576710D03*
X1025750D03*
X1022750Y1573710D03*
X1025750D03*
Y1570710D03*
X1022750D03*
X1025750Y1579710D03*
X1022750D03*
Y1582710D03*
X1025750D03*
X1028750Y1576710D03*
Y1573710D03*
Y1570710D03*
Y1579710D03*
Y1582710D03*
X1031750Y1576710D03*
Y1573710D03*
Y1570710D03*
Y1579710D03*
Y1582710D03*
X1025750Y1585710D03*
X1022750D03*
Y1588710D03*
X1025750D03*
X1028750Y1585710D03*
Y1588710D03*
X1031750Y1585710D03*
Y1588710D03*
X1033798Y1656675D03*
X1033748Y1659315D03*
X1040199Y49379D03*
X1044012Y268659D03*
X1051495Y265133D03*
X1046384Y269814D03*
X1049451Y266747D03*
X1040060Y313528D03*
X1051873Y305482D03*
X1040891Y406586D03*
X1049573D03*
X1045100Y427059D03*
X1047515Y444404D03*
X1045015D03*
X1043377Y452740D03*
X1040836Y510894D03*
X1045254Y521074D03*
X1041254Y523874D03*
X1037212Y510940D03*
X1045254Y516014D03*
X1040097Y529508D03*
X1045254Y534074D03*
Y526074D03*
X1043180Y547027D03*
X1047335Y549574D03*
X1047200Y543090D03*
X1037301Y539685D03*
X1039000Y555000D03*
X1039718Y563268D03*
X1050956Y591090D03*
X1040626Y668441D03*
X1042389Y733426D03*
X1040890Y735717D03*
X1044056Y736188D03*
X1050015Y756765D03*
Y760265D03*
X1040965Y756831D03*
Y760177D03*
X1045465Y776910D03*
X1050015Y767265D03*
Y763765D03*
X1040915Y763524D03*
X1045465Y780256D03*
Y786949D03*
Y793642D03*
X1050915Y790296D03*
X1045465Y783603D03*
Y780256D03*
Y786949D03*
Y803681D03*
Y796988D03*
X1050915Y800335D03*
X1041065Y795315D03*
X1045465Y807028D03*
Y803681D03*
Y793642D03*
Y796988D03*
Y817067D03*
Y810374D03*
Y823760D03*
Y813721D03*
Y820414D03*
Y817067D03*
Y810374D03*
Y830453D03*
Y833799D03*
X1050915Y827107D03*
Y837146D03*
X1041065Y832126D03*
X1045465Y823760D03*
Y830453D03*
Y833799D03*
Y840492D03*
Y847185D03*
Y853878D03*
Y850532D03*
Y843839D03*
Y840492D03*
Y847185D03*
Y860571D03*
Y867264D03*
X1050915Y863918D03*
X1045465Y857225D03*
Y853878D03*
Y860571D03*
Y877303D03*
Y870610D03*
Y883996D03*
X1041065Y868937D03*
X1050915Y873957D03*
X1045465Y880650D03*
Y877303D03*
Y867264D03*
Y870610D03*
Y890689D03*
Y897382D03*
Y887343D03*
Y894036D03*
Y883996D03*
Y890689D03*
Y904075D03*
Y907422D03*
X1050915Y910768D03*
X1041065Y905749D03*
X1050915Y900729D03*
X1045465Y897382D03*
Y904075D03*
Y907422D03*
Y914114D03*
Y920807D03*
Y927500D03*
Y917461D03*
Y924154D03*
Y914114D03*
Y920807D03*
Y934193D03*
Y940886D03*
Y930847D03*
X1050915Y937540D03*
X1045465Y927500D03*
Y934193D03*
Y940886D03*
Y950925D03*
Y944233D03*
Y957618D03*
X1050915Y947579D03*
X1041065Y942560D03*
X1045465Y954272D03*
Y950925D03*
Y944233D03*
Y964311D03*
Y971004D03*
Y967658D03*
Y960965D03*
Y964311D03*
Y957618D03*
Y971004D03*
Y977697D03*
Y984390D03*
Y974351D03*
Y981044D03*
Y977697D03*
Y984390D03*
Y1001122D03*
Y997776D03*
Y991083D03*
Y987736D03*
Y994429D03*
Y1001122D03*
Y997776D03*
Y991083D03*
Y1004469D03*
Y1031240D03*
Y1037933D03*
Y1044626D03*
Y1041280D03*
Y1034587D03*
Y1031240D03*
Y1037933D03*
Y1044626D03*
Y1058012D03*
Y1051319D03*
Y1047973D03*
Y1054666D03*
Y1058012D03*
Y1051319D03*
X1037566Y1047135D03*
X1045465Y1074744D03*
Y1061359D03*
Y1071398D03*
Y1074744D03*
Y1068051D03*
Y1064705D03*
Y1081437D03*
Y1088130D03*
Y1091477D03*
Y1078091D03*
X1050915Y1084784D03*
X1041065Y1089804D03*
X1045465Y1081437D03*
Y1088130D03*
Y1098170D03*
Y1104862D03*
X1050915Y1094823D03*
X1045465Y1101516D03*
Y1098170D03*
Y1104862D03*
Y1091477D03*
Y1111555D03*
Y1118248D03*
Y1108209D03*
Y1114902D03*
Y1111555D03*
Y1118248D03*
Y1134981D03*
Y1124941D03*
Y1128288D03*
X1050915Y1131634D03*
Y1121595D03*
X1041065Y1126615D03*
X1045465Y1134981D03*
Y1124941D03*
Y1128288D03*
Y1148366D03*
Y1141674D03*
Y1138327D03*
Y1145020D03*
Y1148366D03*
Y1141674D03*
Y1155059D03*
Y1161752D03*
Y1165099D03*
X1050915Y1158406D03*
X1045465Y1151713D03*
X1041065Y1163426D03*
X1045465Y1155059D03*
Y1161752D03*
Y1165099D03*
Y1171792D03*
Y1178485D03*
X1050915Y1168445D03*
X1045465Y1175138D03*
Y1171792D03*
Y1178485D03*
Y1185177D03*
Y1191870D03*
Y1188524D03*
Y1181831D03*
Y1185177D03*
Y1191870D03*
Y1208603D03*
Y1198563D03*
Y1201910D03*
X1041065Y1200237D03*
X1050915Y1205256D03*
Y1195217D03*
X1045465Y1208603D03*
Y1198563D03*
Y1201910D03*
Y1215296D03*
Y1221988D03*
Y1211949D03*
Y1218642D03*
Y1215296D03*
Y1221988D03*
Y1228681D03*
Y1235374D03*
Y1238721D03*
X1041065Y1237048D03*
X1045465Y1225335D03*
X1050915Y1232028D03*
X1045465Y1228681D03*
Y1235374D03*
Y1238721D03*
Y1245414D03*
Y1252107D03*
Y1248760D03*
X1050915Y1242067D03*
X1045465Y1245414D03*
Y1252107D03*
X1037895Y1251517D03*
X1045465Y1255453D03*
X1039546Y1275474D03*
X1039598Y1278765D03*
X1042855Y1275552D03*
X1042649Y1279152D03*
X1048684Y1350724D03*
X1051684D03*
X1047366Y1491204D03*
X1044866D03*
X1037366D03*
X1042366D03*
X1039866D03*
X1049866D03*
X1047366Y1498704D03*
Y1496204D03*
Y1493704D03*
X1044866Y1496204D03*
Y1493704D03*
X1037366D03*
Y1496204D03*
Y1498704D03*
X1047366Y1501204D03*
X1044866D03*
Y1498704D03*
X1042366Y1501204D03*
Y1498704D03*
Y1496204D03*
Y1493704D03*
X1039866Y1501204D03*
Y1498704D03*
Y1496204D03*
Y1493704D03*
X1037366Y1501204D03*
X1049866Y1493704D03*
X1051110Y1532850D03*
X1048219Y1567883D03*
X1051219D03*
X1048219Y1576883D03*
Y1573883D03*
Y1570883D03*
X1051219Y1576883D03*
Y1573883D03*
Y1570883D03*
Y1579883D03*
X1048219D03*
Y1582883D03*
X1051219D03*
Y1585883D03*
X1048219D03*
Y1588883D03*
X1051219D03*
X1037974Y1731920D03*
X1062199Y49379D03*
X1066231Y165078D03*
Y167578D03*
X1054355Y258698D03*
X1062704Y270875D03*
X1056941Y259176D03*
X1054613Y261586D03*
X1065552Y271441D03*
X1062923Y295053D03*
X1063356Y318297D03*
X1055934Y385488D03*
X1061456Y406560D03*
X1052505Y406576D03*
X1057798Y427059D03*
Y429618D03*
X1062642Y444859D03*
X1062741Y457959D03*
X1059055Y492537D03*
X1062873Y490180D03*
X1055905Y492537D03*
X1057450Y509242D03*
X1056517Y512787D03*
X1061837Y519703D03*
X1063614Y733409D03*
X1061817Y736362D03*
X1065154Y736282D03*
X1057057Y756765D03*
X1066107Y756831D03*
X1061607Y776910D03*
Y773563D03*
X1057057Y763765D03*
Y767299D03*
Y771099D03*
X1066157Y766870D03*
X1061607Y776910D03*
X1066107Y763524D03*
X1066157Y770217D03*
X1061607Y783603D03*
Y790296D03*
Y793642D03*
X1057207Y791969D03*
X1056157Y786949D03*
X1061607Y780256D03*
Y783603D03*
Y790296D03*
Y800335D03*
Y807028D03*
Y803681D03*
X1056157Y796988D03*
X1061607Y800335D03*
Y807028D03*
Y793642D03*
Y813721D03*
Y820414D03*
Y810374D03*
Y817067D03*
Y813721D03*
Y820414D03*
Y837146D03*
Y830453D03*
Y827107D03*
X1056157Y823760D03*
Y833799D03*
X1057207Y828780D03*
X1061607Y837146D03*
Y830453D03*
Y827107D03*
Y843839D03*
Y850532D03*
Y847185D03*
Y840492D03*
Y843839D03*
Y850532D03*
Y857225D03*
Y863918D03*
Y867264D03*
Y853878D03*
X1056157Y860571D03*
X1057207Y865591D03*
X1061607Y857225D03*
Y863918D03*
Y873957D03*
Y880650D03*
X1056157Y870610D03*
X1061607Y877303D03*
Y873957D03*
Y880650D03*
Y867264D03*
Y887343D03*
Y894036D03*
Y883996D03*
Y890689D03*
Y887343D03*
Y894036D03*
Y910768D03*
Y904075D03*
Y900729D03*
X1056157Y907422D03*
Y897382D03*
X1057207Y902402D03*
X1061607Y910768D03*
Y904075D03*
Y900729D03*
Y924154D03*
Y917461D03*
Y914114D03*
Y920807D03*
Y924154D03*
Y917461D03*
Y930847D03*
Y940886D03*
Y937540D03*
Y927500D03*
X1056157Y934193D03*
X1057207Y939213D03*
X1061607Y930847D03*
Y940886D03*
Y937540D03*
Y947579D03*
Y954272D03*
Y950925D03*
X1056157Y944233D03*
X1061607Y947579D03*
Y954272D03*
X1067107Y960965D03*
X1061607Y967658D03*
Y964311D03*
Y971004D03*
Y957618D03*
Y960965D03*
Y967658D03*
Y974351D03*
Y981044D03*
Y987736D03*
Y977697D03*
Y984390D03*
Y974351D03*
Y981044D03*
Y994429D03*
Y1001122D03*
Y991083D03*
Y997776D03*
Y987736D03*
Y994429D03*
Y1001122D03*
Y1004469D03*
Y1027894D03*
D03*
Y1034587D03*
Y1041280D03*
Y1047973D03*
Y1037933D03*
Y1044626D03*
Y1031240D03*
Y1034587D03*
Y1041280D03*
Y1054666D03*
Y1061359D03*
Y1051319D03*
Y1058012D03*
Y1047973D03*
Y1054666D03*
Y1071398D03*
Y1064705D03*
Y1074744D03*
Y1068051D03*
Y1061359D03*
Y1071398D03*
Y1064705D03*
Y1078091D03*
Y1088130D03*
Y1084784D03*
X1057207Y1086457D03*
X1056157Y1081437D03*
X1061607Y1078091D03*
Y1088130D03*
Y1084784D03*
Y1094823D03*
Y1101516D03*
X1056157Y1091477D03*
X1061607Y1098170D03*
Y1104862D03*
Y1094823D03*
Y1101516D03*
Y1108209D03*
Y1114902D03*
Y1121595D03*
X1056157Y1118248D03*
X1061607Y1111555D03*
Y1108209D03*
Y1114902D03*
Y1131634D03*
Y1124941D03*
Y1134981D03*
X1057207Y1123268D03*
X1056157Y1128288D03*
X1061607Y1131634D03*
Y1124941D03*
Y1121595D03*
Y1138327D03*
Y1145020D03*
Y1151713D03*
Y1141674D03*
Y1148366D03*
Y1138327D03*
Y1145020D03*
Y1161752D03*
Y1158406D03*
X1056157Y1155059D03*
Y1165099D03*
X1057207Y1160079D03*
X1061607Y1151713D03*
Y1161752D03*
Y1158406D03*
Y1168445D03*
Y1175138D03*
Y1181831D03*
Y1171792D03*
Y1178485D03*
Y1168445D03*
Y1175138D03*
Y1188524D03*
Y1195217D03*
X1056157Y1191870D03*
X1061607Y1185177D03*
Y1181831D03*
Y1188524D03*
Y1205256D03*
Y1198563D03*
Y1211949D03*
X1056157Y1201910D03*
X1057207Y1196890D03*
X1061607Y1208603D03*
Y1205256D03*
Y1198563D03*
Y1195217D03*
Y1218642D03*
Y1225335D03*
Y1215296D03*
Y1221988D03*
Y1211949D03*
Y1218642D03*
Y1235374D03*
Y1232028D03*
X1056157Y1238721D03*
X1057207Y1233701D03*
X1056157Y1228681D03*
X1061607Y1225335D03*
Y1235374D03*
Y1232028D03*
Y1242067D03*
Y1248760D03*
Y1245414D03*
Y1252107D03*
Y1242067D03*
Y1248760D03*
X1060721Y1313954D03*
X1055171Y1307203D03*
Y1311203D03*
X1060684Y1350724D03*
X1057684D03*
X1054684D03*
X1058143Y1433809D03*
X1065732Y1491204D03*
X1063232D03*
X1060732D03*
X1052366D03*
X1054866D03*
X1057366D03*
X1065732Y1501204D03*
Y1498704D03*
Y1496204D03*
Y1493704D03*
X1063232Y1501204D03*
Y1498704D03*
Y1496204D03*
Y1493704D03*
X1060732D03*
Y1496204D03*
Y1498704D03*
Y1501204D03*
X1052366Y1493704D03*
X1054866D03*
X1057366D03*
X1056866Y1501204D03*
X1056584Y1523080D03*
Y1520080D03*
X1057110Y1532850D03*
X1054110D03*
X1056584Y1526080D03*
X1063110Y1532850D03*
X1060110D03*
X1057396Y1550840D03*
X1054219Y1567883D03*
X1057219D03*
X1060219D03*
X1063219D03*
X1066219D03*
X1054219Y1576883D03*
X1057219D03*
X1054219Y1573883D03*
X1057219D03*
Y1570883D03*
X1054219D03*
X1057219Y1579883D03*
X1054219D03*
Y1582883D03*
X1057219D03*
X1060219Y1576883D03*
Y1573883D03*
Y1570883D03*
Y1579883D03*
Y1582883D03*
X1063219Y1576883D03*
Y1573883D03*
Y1570883D03*
X1066219Y1576883D03*
Y1573883D03*
Y1570883D03*
Y1579883D03*
X1063219D03*
Y1582883D03*
X1066219D03*
X1057219Y1585883D03*
X1054219D03*
Y1588883D03*
X1057219D03*
X1060219Y1585883D03*
Y1588883D03*
X1066219Y1585883D03*
X1063219D03*
Y1588883D03*
X1066219D03*
X1064221Y1662726D03*
X1061974Y1731920D03*
X1078823Y269400D03*
X1071656Y366726D03*
X1068143Y383688D03*
X1068827Y389734D03*
X1073204Y383417D03*
X1078400Y383226D03*
X1074800Y391262D03*
X1074736Y396929D03*
X1072135Y396908D03*
X1077418Y411322D03*
Y416763D03*
Y421922D03*
X1072673Y428791D03*
X1081133Y461516D03*
X1080453Y457959D03*
X1071239Y479655D03*
X1071470Y475525D03*
X1080640Y467000D03*
X1080574Y471500D03*
X1071667D03*
Y467000D03*
X1080416Y482772D03*
X1080420Y487782D03*
X1081730Y509172D03*
X1081632Y648854D03*
X1078499Y648202D03*
X1068378Y736795D03*
X1079716Y756765D03*
Y760265D03*
X1070666Y756831D03*
Y760177D03*
X1079716Y767265D03*
X1075166Y776910D03*
X1079716Y763765D03*
X1070616Y763524D03*
X1075166Y780256D03*
Y786949D03*
Y793642D03*
X1080616Y790296D03*
X1075166Y783603D03*
Y780256D03*
Y786949D03*
Y803681D03*
Y796988D03*
X1070766Y795315D03*
X1080616Y800335D03*
X1075166Y807028D03*
Y803681D03*
Y793642D03*
Y796988D03*
Y817067D03*
Y810374D03*
Y823760D03*
Y813721D03*
Y820414D03*
Y817067D03*
Y810374D03*
Y830453D03*
Y833799D03*
X1070766Y832126D03*
X1080616Y827107D03*
Y837146D03*
X1075166Y823760D03*
Y830453D03*
Y833799D03*
Y840492D03*
Y847185D03*
Y853878D03*
Y850532D03*
Y843839D03*
Y840492D03*
Y847185D03*
Y860571D03*
Y867264D03*
X1080616Y863918D03*
X1075166Y857225D03*
Y853878D03*
Y860571D03*
Y877303D03*
Y870610D03*
Y883996D03*
X1070766Y868937D03*
X1080616Y873957D03*
X1075166Y880650D03*
Y877303D03*
Y867264D03*
Y870610D03*
Y890689D03*
Y897382D03*
Y887343D03*
Y894036D03*
Y883996D03*
Y890689D03*
Y904075D03*
Y907422D03*
X1080616Y910768D03*
X1070766Y905749D03*
X1080616Y900729D03*
X1075166Y897382D03*
Y904075D03*
Y907422D03*
Y914114D03*
Y920807D03*
Y927500D03*
Y917461D03*
Y924154D03*
Y914114D03*
Y920807D03*
Y934193D03*
Y940886D03*
Y930847D03*
X1080616Y937540D03*
X1075166Y927500D03*
Y934193D03*
Y940886D03*
Y950925D03*
Y944233D03*
Y957618D03*
X1070766Y942560D03*
X1080616Y947579D03*
X1075166Y954272D03*
Y950925D03*
Y944233D03*
Y964311D03*
Y971004D03*
Y967658D03*
Y960965D03*
Y964311D03*
Y957618D03*
Y971004D03*
X1067107Y960965D03*
X1075166Y977697D03*
Y984390D03*
Y974351D03*
Y981044D03*
Y977697D03*
Y984390D03*
Y1001122D03*
Y997776D03*
Y991083D03*
Y987736D03*
Y994429D03*
Y1001122D03*
Y997776D03*
Y991083D03*
Y1004469D03*
Y1031240D03*
Y1037933D03*
Y1044626D03*
Y1034587D03*
Y1041280D03*
Y1031240D03*
Y1037933D03*
Y1044626D03*
Y1058012D03*
Y1051319D03*
Y1047973D03*
Y1054666D03*
Y1058012D03*
Y1051319D03*
Y1074744D03*
Y1061359D03*
Y1071398D03*
Y1074744D03*
Y1068051D03*
Y1064705D03*
Y1081437D03*
Y1088130D03*
Y1091477D03*
Y1078091D03*
X1070766Y1089804D03*
X1080616Y1084784D03*
X1075166Y1081437D03*
Y1088130D03*
Y1098170D03*
Y1104862D03*
X1080616Y1094823D03*
X1075166Y1101516D03*
Y1098170D03*
Y1104862D03*
Y1091477D03*
Y1111555D03*
Y1118248D03*
Y1108209D03*
Y1114902D03*
Y1111555D03*
Y1118248D03*
Y1134981D03*
Y1124941D03*
Y1128288D03*
X1080616Y1131634D03*
Y1121595D03*
X1070766Y1126615D03*
X1075166Y1134981D03*
Y1124941D03*
Y1128288D03*
Y1148366D03*
Y1141674D03*
Y1138327D03*
Y1145020D03*
Y1148366D03*
Y1141674D03*
Y1155059D03*
Y1161752D03*
Y1165099D03*
X1080616Y1158406D03*
X1075166Y1151713D03*
X1070766Y1163426D03*
X1075166Y1155059D03*
Y1161752D03*
Y1165099D03*
Y1171792D03*
Y1178485D03*
X1080616Y1168445D03*
X1075166Y1175138D03*
Y1171792D03*
Y1178485D03*
Y1185177D03*
Y1191870D03*
Y1188524D03*
Y1181831D03*
Y1185177D03*
Y1191870D03*
Y1208603D03*
Y1198563D03*
Y1201910D03*
X1080616Y1205256D03*
X1070766Y1200237D03*
X1080616Y1195217D03*
X1075166Y1208603D03*
Y1198563D03*
Y1201910D03*
Y1215296D03*
Y1221988D03*
Y1211949D03*
Y1218642D03*
Y1215296D03*
Y1221988D03*
Y1228681D03*
Y1235374D03*
Y1238721D03*
X1070766Y1237048D03*
X1080616Y1232028D03*
X1075166Y1225335D03*
Y1228681D03*
Y1235374D03*
Y1238721D03*
Y1245414D03*
Y1252107D03*
Y1248760D03*
X1080616Y1242067D03*
X1075166Y1245414D03*
Y1252107D03*
Y1255453D03*
X1076903Y1300361D03*
Y1302861D03*
X1079403D03*
Y1300361D03*
X1074403Y1302861D03*
Y1300361D03*
X1076903Y1305361D03*
X1079403D03*
X1074403D03*
Y1307861D03*
Y1310361D03*
Y1312861D03*
X1079403Y1307861D03*
Y1310361D03*
Y1312861D03*
X1076903D03*
Y1310361D03*
Y1307861D03*
X1079403Y1315361D03*
X1076903D03*
Y1317861D03*
X1079403D03*
X1074403D03*
Y1315361D03*
X1070949Y1337752D03*
X1067929Y1337702D03*
X1079215Y1357390D03*
X1076615D03*
X1071908Y1361660D03*
X1080889Y1367253D03*
X1076615Y1360497D03*
X1079215D03*
X1078459Y1367253D03*
Y1372853D03*
X1080889D03*
X1069839Y1368999D03*
Y1371540D03*
X1073733Y1388198D03*
X1076601Y1382574D03*
X1071332Y1379914D03*
X1076601Y1380066D03*
X1073612Y1376389D03*
X1081005Y1425458D03*
X1071117Y1445005D03*
X1077031Y1451498D03*
X1070312Y1452028D03*
X1073307Y1451931D03*
X1070732Y1491204D03*
X1068232D03*
X1073232D03*
X1075732D03*
X1078232D03*
X1080732D03*
X1070732Y1501204D03*
Y1498704D03*
Y1496204D03*
Y1493704D03*
X1068232Y1501204D03*
Y1498704D03*
Y1496204D03*
Y1493704D03*
X1073232D03*
X1075732D03*
X1078232D03*
X1080732D03*
X1080232Y1501204D03*
X1068094Y1654099D03*
X1072134Y1647920D03*
X1081011Y1685499D03*
X1078011D03*
X1081011Y1682499D03*
X1078011D03*
X1077172Y1676686D03*
X1077881Y1688252D03*
X1080933Y1688245D03*
X1078016Y1691207D03*
X1080966Y1691320D03*
X1084199Y49379D03*
X1087421Y149716D03*
X1081857Y269856D03*
X1083819Y353094D03*
X1086936Y370532D03*
X1090086Y370417D03*
X1083583Y395195D03*
X1093722Y427960D03*
X1087963Y440605D03*
Y446105D03*
Y462605D03*
Y457105D03*
X1087940Y452110D03*
X1087000Y477500D03*
X1087963Y468105D03*
X1095448Y479426D03*
X1084000Y477500D03*
X1090000D03*
X1087963Y484605D03*
Y494641D03*
Y489641D03*
X1083434Y481500D03*
X1085730Y509362D03*
X1091730D03*
X1088730D03*
X1082622Y520652D03*
X1082438Y524033D03*
X1085438D03*
X1085622Y520652D03*
X1083281Y651601D03*
X1091270Y668286D03*
X1086758Y756765D03*
X1095808Y756831D03*
X1091308Y776910D03*
Y773563D03*
X1086758Y763765D03*
Y767299D03*
Y771099D03*
X1095858Y766870D03*
X1091308Y776910D03*
X1095808Y763524D03*
X1095858Y770217D03*
X1091308Y783603D03*
Y790296D03*
Y793642D03*
X1086908Y791969D03*
X1091308Y780256D03*
X1085858Y786949D03*
X1091308Y783603D03*
Y790296D03*
Y800335D03*
Y807028D03*
Y803681D03*
X1085858Y796988D03*
X1091308Y800335D03*
Y807028D03*
Y793642D03*
Y813721D03*
Y820414D03*
Y810374D03*
Y817067D03*
Y813721D03*
Y820414D03*
Y837146D03*
Y830453D03*
Y827107D03*
X1085858Y823760D03*
Y833799D03*
X1086908Y828780D03*
X1091308Y837146D03*
Y830453D03*
Y827107D03*
Y843839D03*
Y850532D03*
Y840492D03*
Y847185D03*
Y843839D03*
Y850532D03*
Y857225D03*
Y863918D03*
Y867264D03*
Y853878D03*
X1085858Y860571D03*
X1086908Y865591D03*
X1091308Y857225D03*
Y863918D03*
Y873957D03*
Y880650D03*
X1085858Y870610D03*
X1091308Y877303D03*
Y873957D03*
Y880650D03*
Y867264D03*
Y887343D03*
Y894036D03*
Y883996D03*
Y890689D03*
Y887343D03*
Y894036D03*
Y910768D03*
Y904075D03*
Y900729D03*
X1085858Y907422D03*
Y897382D03*
X1086908Y902402D03*
X1091308Y910768D03*
Y904075D03*
Y900729D03*
Y924154D03*
Y917461D03*
Y914114D03*
Y920807D03*
Y924154D03*
Y917461D03*
Y930847D03*
Y940886D03*
Y937540D03*
X1085858Y934193D03*
X1091308Y927500D03*
X1086908Y939213D03*
X1091308Y930847D03*
Y940886D03*
Y937540D03*
Y947579D03*
Y954272D03*
X1085858Y944233D03*
X1091308Y950925D03*
Y947579D03*
Y954272D03*
X1096808Y960965D03*
X1091308Y967658D03*
Y964311D03*
Y971004D03*
Y957618D03*
Y960965D03*
Y967658D03*
Y974351D03*
Y981044D03*
Y987736D03*
Y977697D03*
Y984390D03*
Y974351D03*
Y981044D03*
Y994429D03*
Y1001122D03*
Y991083D03*
Y997776D03*
Y987736D03*
Y994429D03*
Y1001122D03*
Y1004469D03*
Y1027894D03*
D03*
Y1034587D03*
Y1041280D03*
Y1047973D03*
Y1031240D03*
Y1037933D03*
Y1044626D03*
Y1034587D03*
Y1041280D03*
Y1054666D03*
Y1061359D03*
Y1051319D03*
Y1058012D03*
Y1047973D03*
Y1054666D03*
Y1071398D03*
Y1064705D03*
Y1074744D03*
Y1068051D03*
Y1061359D03*
Y1071398D03*
Y1064705D03*
Y1078091D03*
Y1088130D03*
Y1084784D03*
X1086908Y1086457D03*
X1085858Y1081437D03*
X1091308Y1078091D03*
Y1088130D03*
Y1084784D03*
Y1094823D03*
Y1101516D03*
X1085858Y1091477D03*
X1091308Y1098170D03*
Y1104862D03*
Y1094823D03*
Y1101516D03*
Y1108209D03*
Y1114902D03*
Y1121595D03*
X1085858Y1118248D03*
X1091308Y1111555D03*
Y1108209D03*
Y1114902D03*
Y1131634D03*
Y1124941D03*
Y1134981D03*
X1086908Y1123268D03*
X1085858Y1128288D03*
X1091308Y1131634D03*
Y1124941D03*
Y1121595D03*
Y1138327D03*
Y1145020D03*
Y1151713D03*
Y1141674D03*
Y1148366D03*
Y1138327D03*
Y1145020D03*
Y1161752D03*
Y1158406D03*
X1085858Y1155059D03*
Y1165099D03*
X1086908Y1160079D03*
X1091308Y1151713D03*
Y1161752D03*
Y1158406D03*
Y1168445D03*
Y1175138D03*
Y1181831D03*
Y1171792D03*
Y1178485D03*
Y1168445D03*
Y1175138D03*
Y1188524D03*
Y1195217D03*
X1085858Y1191870D03*
X1091308Y1185177D03*
Y1181831D03*
Y1188524D03*
Y1205256D03*
Y1198563D03*
Y1211949D03*
X1085858Y1201910D03*
X1086908Y1196890D03*
X1091308Y1208603D03*
Y1205256D03*
Y1198563D03*
Y1195217D03*
Y1218642D03*
Y1225335D03*
Y1215296D03*
Y1221988D03*
Y1211949D03*
Y1218642D03*
Y1235374D03*
Y1232028D03*
X1085858Y1238721D03*
Y1228681D03*
X1086908Y1233701D03*
X1091308Y1225335D03*
Y1235374D03*
Y1232028D03*
Y1242067D03*
Y1248760D03*
Y1245414D03*
Y1252107D03*
Y1242067D03*
Y1248760D03*
X1090203Y1307861D03*
Y1310361D03*
Y1312861D03*
X1092703D03*
Y1310361D03*
Y1307861D03*
Y1300361D03*
Y1302861D03*
X1090203D03*
Y1300361D03*
X1095203Y1302861D03*
Y1300361D03*
X1092703Y1305361D03*
X1090203D03*
X1095203D03*
Y1307861D03*
Y1310361D03*
Y1312861D03*
X1090203Y1315361D03*
X1092703D03*
Y1317861D03*
X1090203D03*
X1095203D03*
Y1315361D03*
X1095809Y1337824D03*
X1087015Y1357390D03*
X1095629Y1352252D03*
Y1349652D03*
Y1354852D03*
X1089515Y1357390D03*
X1091959Y1357406D03*
X1084415Y1357390D03*
X1081815D03*
X1092905Y1363394D03*
Y1360437D03*
X1083319Y1367253D03*
X1081815Y1360497D03*
X1084415D03*
X1081815Y1363454D03*
X1084415D03*
X1083319Y1372853D03*
X1087059D03*
X1089489D03*
X1091919D03*
X1092889Y1367278D03*
Y1370178D03*
X1083368Y1385268D03*
X1084043Y1382111D03*
X1083293Y1379543D03*
X1094683Y1379188D03*
Y1376288D03*
X1091598Y1491204D03*
X1089098D03*
X1086598D03*
X1084098D03*
X1091598Y1501204D03*
Y1498704D03*
Y1496204D03*
Y1493704D03*
X1089098Y1501204D03*
Y1498704D03*
Y1496204D03*
Y1493704D03*
X1086598Y1501204D03*
Y1498704D03*
Y1496204D03*
Y1493704D03*
X1084098D03*
Y1498704D03*
Y1501204D03*
Y1496204D03*
X1090300Y1532660D03*
X1087300D03*
X1096300D03*
X1093300D03*
X1092934Y1550784D03*
X1094399Y1568043D03*
X1091399D03*
X1085399D03*
X1088399D03*
X1091399Y1580043D03*
X1094399D03*
Y1571043D03*
Y1574043D03*
Y1577043D03*
X1091399Y1571043D03*
Y1574043D03*
Y1577043D03*
X1088399Y1580043D03*
X1085399D03*
X1088399Y1571043D03*
X1085399D03*
Y1574043D03*
X1088399D03*
X1085399Y1577043D03*
X1088399D03*
X1094399Y1583043D03*
X1091399D03*
X1085399D03*
X1088399D03*
X1094399Y1589043D03*
X1091399D03*
Y1586043D03*
X1094399D03*
X1085399Y1589043D03*
X1088399D03*
Y1586043D03*
X1085399D03*
X1096500Y1639000D03*
X1090143Y1643625D03*
X1091026Y1653031D03*
X1090958Y1646528D03*
Y1649928D03*
X1084629Y1673002D03*
X1089030Y1691229D03*
X1092980Y1696029D03*
Y1699179D03*
X1092030Y1715841D03*
X1095489Y1708519D03*
X1081974Y1731920D03*
X1092030Y1725991D03*
Y1720841D03*
X1106199Y49379D03*
X1099500Y318000D03*
X1111001Y361272D03*
X1101942Y395361D03*
X1104443Y646983D03*
X1109416Y756765D03*
Y760265D03*
X1100366Y756831D03*
Y760177D03*
X1109416Y767265D03*
X1104866Y776910D03*
X1109416Y763765D03*
X1100316Y763524D03*
X1104866Y780256D03*
Y786949D03*
Y793642D03*
Y783603D03*
X1110316Y790296D03*
X1104866Y780256D03*
Y786949D03*
Y803681D03*
Y796988D03*
X1110316Y800335D03*
X1100466Y795315D03*
X1104866Y807028D03*
Y803681D03*
Y793642D03*
Y796988D03*
Y817067D03*
Y810374D03*
Y823760D03*
Y813721D03*
Y820414D03*
Y817067D03*
Y810374D03*
Y830453D03*
Y833799D03*
X1110316Y827107D03*
Y837146D03*
X1100466Y832126D03*
X1104866Y823760D03*
Y830453D03*
Y833799D03*
Y840492D03*
Y847185D03*
Y853878D03*
Y850532D03*
Y843839D03*
Y840492D03*
Y847185D03*
Y860571D03*
Y867264D03*
Y857225D03*
X1110316Y863918D03*
X1104866Y853878D03*
Y860571D03*
Y877303D03*
Y870610D03*
Y883996D03*
X1100466Y868937D03*
X1110316Y873957D03*
X1104866Y880650D03*
Y877303D03*
Y867264D03*
Y870610D03*
Y890689D03*
Y897382D03*
Y887343D03*
Y894036D03*
Y883996D03*
Y890689D03*
Y904075D03*
Y907422D03*
X1110316Y910768D03*
X1100466Y905749D03*
X1110316Y900729D03*
X1104866Y897382D03*
Y904075D03*
Y907422D03*
Y914114D03*
Y920807D03*
Y927500D03*
Y917461D03*
Y924154D03*
Y914114D03*
Y920807D03*
Y934193D03*
Y940886D03*
Y930847D03*
X1110316Y937540D03*
X1104866Y927500D03*
Y934193D03*
Y940886D03*
Y950925D03*
Y944233D03*
Y957618D03*
X1110316Y947579D03*
X1100466Y942560D03*
X1104866Y954272D03*
Y950925D03*
Y944233D03*
Y964311D03*
Y971004D03*
Y967658D03*
Y960965D03*
Y964311D03*
Y957618D03*
Y971004D03*
X1096808Y960965D03*
X1104866Y977697D03*
Y984390D03*
Y974351D03*
Y981044D03*
Y977697D03*
Y984390D03*
Y1001122D03*
Y997776D03*
Y991083D03*
Y987736D03*
Y994429D03*
Y1001122D03*
Y997776D03*
Y991083D03*
Y1004469D03*
Y1031240D03*
Y1037933D03*
Y1044626D03*
Y1034587D03*
Y1041280D03*
Y1031240D03*
Y1037933D03*
Y1044626D03*
Y1058012D03*
Y1051319D03*
Y1047973D03*
Y1054666D03*
Y1058012D03*
Y1051319D03*
Y1074744D03*
Y1071398D03*
Y1061359D03*
Y1074744D03*
Y1068051D03*
Y1064705D03*
Y1081437D03*
Y1088130D03*
Y1091477D03*
Y1078091D03*
X1110316Y1084784D03*
X1100466Y1089804D03*
X1104866Y1081437D03*
Y1088130D03*
Y1098170D03*
Y1104862D03*
X1110316Y1094823D03*
X1104866Y1101516D03*
Y1098170D03*
Y1104862D03*
Y1091477D03*
Y1111555D03*
Y1118248D03*
Y1108209D03*
Y1114902D03*
Y1111555D03*
Y1118248D03*
Y1134981D03*
Y1124941D03*
Y1128288D03*
X1110316Y1131634D03*
Y1121595D03*
X1100466Y1126615D03*
X1104866Y1134981D03*
Y1124941D03*
Y1128288D03*
Y1148366D03*
Y1141674D03*
Y1138327D03*
Y1145020D03*
Y1148366D03*
Y1141674D03*
Y1155059D03*
Y1161752D03*
Y1165099D03*
X1110316Y1158406D03*
X1104866Y1151713D03*
X1100466Y1163426D03*
X1104866Y1155059D03*
Y1161752D03*
Y1165099D03*
Y1171792D03*
Y1178485D03*
X1110316Y1168445D03*
X1104866Y1175138D03*
Y1171792D03*
Y1178485D03*
Y1185177D03*
Y1191870D03*
Y1188524D03*
Y1181831D03*
Y1185177D03*
Y1191870D03*
Y1208603D03*
Y1198563D03*
Y1201910D03*
X1110316Y1205256D03*
Y1195217D03*
X1100466Y1200237D03*
X1104866Y1208603D03*
Y1198563D03*
Y1201910D03*
Y1215296D03*
Y1221988D03*
Y1211949D03*
Y1218642D03*
Y1215296D03*
Y1221988D03*
Y1228681D03*
Y1235374D03*
Y1238721D03*
X1100466Y1237048D03*
X1110316Y1232028D03*
X1104866Y1225335D03*
Y1228681D03*
Y1235374D03*
Y1238721D03*
Y1245414D03*
Y1252107D03*
Y1248760D03*
X1110316Y1242067D03*
X1104866Y1245414D03*
Y1252107D03*
Y1255453D03*
X1109503Y1302861D03*
X1107003D03*
Y1300361D03*
X1109503Y1305361D03*
X1107003D03*
Y1307861D03*
Y1310361D03*
Y1312861D03*
X1109503Y1307861D03*
Y1310361D03*
Y1312861D03*
Y1300361D03*
Y1315361D03*
Y1317861D03*
X1107003D03*
Y1315361D03*
X1103529Y1337792D03*
X1109289Y1337752D03*
X1098409Y1337824D03*
X1109215Y1357390D03*
X1098229Y1352252D03*
Y1349652D03*
X1096979Y1357352D03*
X1098229Y1354852D03*
X1104448Y1361680D03*
X1109215Y1360497D03*
X1111059Y1367253D03*
Y1372853D03*
X1102439Y1368999D03*
Y1371540D03*
X1098949Y1373158D03*
X1103888Y1386721D03*
X1102230Y1384770D03*
X1103932Y1379914D03*
X1109201Y1380066D03*
X1106212Y1376389D03*
X1098949Y1378958D03*
X1096849Y1377558D03*
X1098949Y1376058D03*
X1096749Y1374558D03*
X1106700Y1526591D03*
X1097399Y1568043D03*
Y1580043D03*
Y1571043D03*
Y1574043D03*
Y1577043D03*
Y1583043D03*
Y1589043D03*
Y1586043D03*
X1107181Y1615917D03*
X1109811D03*
X1098549Y1625749D03*
X1109000Y1671107D03*
X1105148Y1696029D03*
X1100998Y1715841D03*
X1109521Y1724109D03*
X1100998Y1725991D03*
X1103351Y1737117D03*
X1119676Y54132D03*
X1124834Y56805D03*
X1124270Y404640D03*
X1113943Y452055D03*
X1125077Y511498D03*
X1118435Y625307D03*
X1114467Y640802D03*
X1116540Y651070D03*
X1112190Y651962D03*
X1116458Y756765D03*
X1125508Y756831D03*
X1121008Y776910D03*
Y773563D03*
X1116459Y763765D03*
Y767299D03*
Y771099D03*
X1125558Y766870D03*
X1121008Y776910D03*
X1125508Y763524D03*
X1125558Y770217D03*
X1121008Y783603D03*
Y790296D03*
Y793642D03*
X1116608Y791969D03*
X1121008Y780256D03*
X1115558Y786949D03*
X1121008Y783603D03*
Y790296D03*
Y800335D03*
Y807028D03*
Y803681D03*
X1115558Y796988D03*
X1121008Y800335D03*
Y807028D03*
Y793642D03*
Y813721D03*
Y820414D03*
Y810374D03*
Y817067D03*
Y813721D03*
Y820414D03*
Y837146D03*
Y830453D03*
Y827107D03*
X1115558Y823760D03*
Y833799D03*
X1116608Y828780D03*
X1121008Y837146D03*
Y830453D03*
Y827107D03*
Y843839D03*
Y850532D03*
Y847185D03*
Y840492D03*
Y843839D03*
Y850532D03*
Y857225D03*
Y863918D03*
Y867264D03*
Y853878D03*
X1115558Y860571D03*
X1116608Y865591D03*
X1121008Y857225D03*
Y863918D03*
Y873957D03*
Y880650D03*
X1115558Y870610D03*
X1121008Y877303D03*
Y873957D03*
Y880650D03*
Y867264D03*
Y887343D03*
Y894036D03*
Y883996D03*
Y890689D03*
Y887343D03*
Y894036D03*
Y910768D03*
Y904075D03*
Y900729D03*
X1115558Y907422D03*
Y897382D03*
X1116608Y902402D03*
X1121008Y910768D03*
Y904075D03*
Y900729D03*
Y924154D03*
Y917461D03*
Y914114D03*
Y920807D03*
Y924154D03*
Y917461D03*
Y930847D03*
Y940886D03*
Y937540D03*
X1115558Y934193D03*
X1121008Y927500D03*
X1116608Y939213D03*
X1121008Y930847D03*
Y940886D03*
Y937540D03*
Y947579D03*
Y954272D03*
X1115558Y944233D03*
X1121008Y950925D03*
Y947579D03*
Y954272D03*
X1126508Y960965D03*
X1121008Y967658D03*
Y964311D03*
Y971004D03*
Y957618D03*
Y960965D03*
Y967658D03*
Y974351D03*
Y981044D03*
Y987736D03*
Y977697D03*
Y984390D03*
Y974351D03*
Y981044D03*
Y994429D03*
Y1001122D03*
Y991083D03*
Y997776D03*
Y987736D03*
Y994429D03*
Y1001122D03*
Y1004469D03*
Y1027894D03*
D03*
Y1034587D03*
Y1041280D03*
Y1047973D03*
Y1031240D03*
Y1037933D03*
Y1044626D03*
Y1034587D03*
Y1041280D03*
Y1054666D03*
Y1061359D03*
Y1051319D03*
Y1058012D03*
Y1047973D03*
Y1054666D03*
Y1071398D03*
Y1064705D03*
Y1074744D03*
Y1068051D03*
Y1061359D03*
Y1071398D03*
Y1064705D03*
Y1078091D03*
Y1088130D03*
Y1084784D03*
X1116608Y1086457D03*
X1115558Y1081437D03*
X1121008Y1078091D03*
Y1088130D03*
Y1084784D03*
Y1094823D03*
Y1101516D03*
X1115558Y1091477D03*
X1121008Y1098170D03*
Y1104862D03*
Y1094823D03*
Y1101516D03*
Y1108209D03*
Y1114902D03*
Y1121595D03*
X1115558Y1118248D03*
X1121008Y1111555D03*
Y1108209D03*
Y1114902D03*
Y1131634D03*
Y1124941D03*
Y1134981D03*
X1116608Y1123268D03*
X1115558Y1128288D03*
X1121008Y1131634D03*
Y1124941D03*
Y1121595D03*
Y1138327D03*
Y1145020D03*
Y1151713D03*
Y1141674D03*
Y1148366D03*
Y1138327D03*
Y1145020D03*
Y1161752D03*
Y1158406D03*
X1115558Y1155059D03*
Y1165099D03*
X1116608Y1160079D03*
X1121008Y1151713D03*
Y1161752D03*
Y1158406D03*
Y1168445D03*
Y1175138D03*
Y1181831D03*
Y1171792D03*
Y1178485D03*
Y1168445D03*
Y1175138D03*
Y1188524D03*
Y1195217D03*
X1115558Y1191870D03*
X1121008Y1185177D03*
Y1181831D03*
Y1188524D03*
Y1205256D03*
Y1198563D03*
Y1211949D03*
X1115558Y1201910D03*
X1116608Y1196890D03*
X1121008Y1208603D03*
Y1205256D03*
Y1198563D03*
Y1195217D03*
Y1218642D03*
Y1225335D03*
Y1215296D03*
Y1221988D03*
Y1211949D03*
Y1218642D03*
Y1235374D03*
Y1232028D03*
X1115558Y1238721D03*
Y1228681D03*
X1116608Y1233701D03*
X1121008Y1225335D03*
Y1235374D03*
Y1232028D03*
Y1242067D03*
Y1248760D03*
Y1245414D03*
Y1252107D03*
Y1242067D03*
Y1248760D03*
X1112003Y1302861D03*
Y1300361D03*
Y1305361D03*
X1122803Y1307861D03*
X1125303D03*
Y1310361D03*
Y1312861D03*
X1122803D03*
Y1310361D03*
X1112003Y1312861D03*
Y1310361D03*
Y1307861D03*
X1125303Y1300361D03*
Y1302861D03*
X1122803D03*
Y1300361D03*
X1125303Y1305361D03*
X1122803D03*
X1125303Y1315361D03*
X1122803D03*
X1112003D03*
Y1317861D03*
X1125303D03*
X1122803D03*
X1119615Y1357390D03*
X1122115D03*
X1124559Y1357406D03*
X1117015Y1357390D03*
X1111815D03*
X1114415D03*
X1117015Y1363454D03*
Y1360497D03*
X1115919Y1372853D03*
X1125505Y1363394D03*
Y1360437D03*
X1115919Y1367253D03*
X1113489D03*
X1114415Y1363454D03*
X1111815Y1360497D03*
X1114415D03*
X1113489Y1372853D03*
X1124519D03*
X1119659D03*
X1122089D03*
X1125469Y1367108D03*
Y1370008D03*
X1115968Y1385268D03*
X1116643Y1382111D03*
X1113155Y1380511D03*
X1115893Y1379543D03*
X1124375Y1423488D03*
X1124415Y1426168D03*
Y1428668D03*
Y1431168D03*
Y1433668D03*
X1117946Y1467955D03*
X1117828Y1473091D03*
X1115098Y1468871D03*
Y1472271D03*
X1124875Y1490042D03*
X1125498Y1487292D03*
X1116917Y1506823D03*
X1119912Y1506936D03*
X1116917Y1509898D03*
X1119912Y1509891D03*
Y1515644D03*
X1116917D03*
X1119912Y1512644D03*
X1116917D03*
X1114617Y1526318D03*
X1113887Y1543447D03*
X1119459Y1556343D03*
X1118326Y1594118D03*
X1118004Y1584908D03*
X1118133Y1587998D03*
Y1591398D03*
X1113785Y1601462D03*
X1117263Y1601526D03*
X1115027Y1598788D03*
X1117247Y1604554D03*
X1113847D03*
X1120376Y1641684D03*
X1125487Y1641754D03*
X1124532Y1634915D03*
X1114286Y1630507D03*
X1117136Y1630441D03*
X1125771Y1652189D03*
X1120595Y1652037D03*
X1120200Y1646597D03*
X1113490Y1651862D03*
X1125732Y1666072D03*
X1112500Y1671107D03*
X1125784Y1662705D03*
X1124394Y1658967D03*
X1120595D03*
X1120303Y1682055D03*
X1126000Y1672419D03*
X1114414Y1698859D03*
X1114394Y1695936D03*
X1113948Y1714244D03*
X1119361Y1713734D03*
X1112001Y1718991D03*
X1125351Y1737117D03*
X1128199Y49379D03*
X1126902Y60805D03*
X1139200Y380533D03*
Y385698D03*
X1127471Y404788D03*
X1132340Y468202D03*
Y471702D03*
X1134567Y513870D03*
X1139360Y516031D03*
X1132855Y609373D03*
X1132387Y615658D03*
X1135387D03*
X1139117Y756765D03*
Y760265D03*
X1130067Y756831D03*
Y760177D03*
X1139117Y767265D03*
X1134567Y776910D03*
X1139117Y763765D03*
X1130017Y763524D03*
X1134567Y780256D03*
Y786949D03*
Y793642D03*
X1140017Y790296D03*
X1134567Y783603D03*
Y780256D03*
Y786949D03*
Y803681D03*
Y796988D03*
X1130167Y795315D03*
X1140017Y800335D03*
X1134567Y807028D03*
Y803681D03*
Y793642D03*
Y796988D03*
Y817067D03*
Y810374D03*
Y823760D03*
Y813721D03*
Y820414D03*
Y817067D03*
Y810374D03*
Y830453D03*
Y833799D03*
X1130167Y832126D03*
X1140017Y827107D03*
Y837146D03*
X1134567Y823760D03*
Y830453D03*
Y833799D03*
Y840492D03*
Y847185D03*
Y853878D03*
Y850532D03*
Y843839D03*
Y840492D03*
Y847185D03*
Y860571D03*
Y867264D03*
X1140017Y863918D03*
X1134567Y857225D03*
Y853878D03*
Y860571D03*
Y877303D03*
Y870610D03*
Y883996D03*
X1130167Y868937D03*
X1140017Y873957D03*
X1134567Y880650D03*
Y877303D03*
Y867264D03*
Y870610D03*
Y890689D03*
Y897382D03*
Y887343D03*
Y894036D03*
Y883996D03*
Y890689D03*
Y904075D03*
Y907422D03*
X1130167Y905749D03*
X1140017Y910768D03*
Y900729D03*
X1134567Y897382D03*
Y904075D03*
Y907422D03*
Y914114D03*
Y920807D03*
Y927500D03*
Y917461D03*
Y924154D03*
Y914114D03*
Y920807D03*
Y934193D03*
Y940886D03*
Y930847D03*
X1140017Y937540D03*
X1134567Y927500D03*
Y934193D03*
Y940886D03*
Y950925D03*
Y944233D03*
Y957618D03*
X1130167Y942560D03*
X1140017Y947579D03*
X1134567Y954272D03*
Y950925D03*
Y944233D03*
Y964311D03*
Y971004D03*
Y967658D03*
Y960965D03*
Y964311D03*
Y957618D03*
Y971004D03*
X1126508Y960965D03*
X1134567Y977697D03*
Y984390D03*
Y974351D03*
Y981044D03*
Y977697D03*
Y984390D03*
Y1001122D03*
Y997776D03*
Y991083D03*
Y987736D03*
Y994429D03*
Y1001122D03*
Y997776D03*
Y991083D03*
Y1004469D03*
Y1031240D03*
Y1037933D03*
Y1044626D03*
Y1034587D03*
Y1041280D03*
Y1031240D03*
Y1037933D03*
Y1044626D03*
Y1058012D03*
Y1051319D03*
Y1047973D03*
Y1054666D03*
Y1058012D03*
Y1051319D03*
Y1074744D03*
Y1061359D03*
Y1071398D03*
Y1074744D03*
Y1068051D03*
Y1064705D03*
Y1081437D03*
Y1088130D03*
Y1091477D03*
X1130167Y1089804D03*
X1134567Y1078091D03*
X1140017Y1084784D03*
X1134567Y1081437D03*
Y1088130D03*
Y1098170D03*
Y1104862D03*
X1140017Y1094823D03*
X1134567Y1101516D03*
Y1098170D03*
Y1104862D03*
Y1091477D03*
Y1111555D03*
Y1118248D03*
Y1108209D03*
Y1114902D03*
Y1111555D03*
Y1118248D03*
Y1134981D03*
Y1124941D03*
Y1128288D03*
X1140017Y1131634D03*
X1130167Y1126615D03*
X1140017Y1121595D03*
X1134567Y1134981D03*
Y1124941D03*
Y1128288D03*
Y1148366D03*
Y1141674D03*
Y1138327D03*
Y1145020D03*
Y1148366D03*
Y1141674D03*
Y1155059D03*
Y1161752D03*
Y1165099D03*
X1130167Y1163426D03*
X1134567Y1151713D03*
X1140017Y1158406D03*
X1134567Y1155059D03*
Y1161752D03*
Y1165099D03*
Y1171792D03*
Y1178485D03*
X1140017Y1168445D03*
X1134567Y1175138D03*
Y1171792D03*
Y1178485D03*
Y1185177D03*
Y1191870D03*
Y1188524D03*
Y1181831D03*
Y1185177D03*
Y1191870D03*
Y1208603D03*
Y1198563D03*
Y1201910D03*
X1130167Y1200237D03*
X1140017Y1205256D03*
Y1195217D03*
X1134567Y1208603D03*
Y1198563D03*
Y1201910D03*
Y1215296D03*
Y1221988D03*
Y1211949D03*
Y1218642D03*
Y1215296D03*
Y1221988D03*
Y1228681D03*
Y1235374D03*
Y1238721D03*
X1130167Y1237048D03*
X1140017Y1232028D03*
X1134567Y1225335D03*
Y1228681D03*
Y1235374D03*
Y1238721D03*
Y1245414D03*
Y1252107D03*
Y1248760D03*
X1140017Y1242067D03*
X1134567Y1245414D03*
Y1252107D03*
Y1255453D03*
X1127803Y1302861D03*
Y1300361D03*
Y1305361D03*
Y1307861D03*
Y1310361D03*
Y1312861D03*
X1139703Y1302861D03*
Y1300361D03*
Y1305361D03*
Y1307861D03*
Y1310361D03*
Y1312861D03*
X1127803Y1317861D03*
Y1315361D03*
X1139703Y1317861D03*
Y1315361D03*
X1136219Y1337794D03*
X1133619D03*
X1130829Y1352252D03*
Y1349652D03*
Y1354852D03*
X1128229Y1352252D03*
Y1349652D03*
X1129579Y1357352D03*
X1128229Y1354852D03*
X1137218Y1361660D03*
X1135139Y1368999D03*
Y1371540D03*
X1131549Y1373158D03*
X1136588Y1386721D03*
X1134930Y1384770D03*
X1136632Y1379914D03*
X1138912Y1376389D03*
X1127283Y1379188D03*
X1129449Y1377558D03*
X1127283Y1376288D03*
X1129349Y1374558D03*
X1131549Y1378958D03*
Y1376058D03*
X1129965Y1403877D03*
X1127465D03*
X1129965Y1401377D03*
X1127465D03*
X1132465Y1403877D03*
Y1401377D03*
X1129925Y1398737D03*
X1127425D03*
X1134925D03*
X1132425D03*
X1137425D03*
X1137465Y1401377D03*
X1134965D03*
Y1403877D03*
X1137465D03*
X1137275Y1424138D03*
X1134775D03*
X1132275D03*
X1126875Y1423488D03*
X1129775Y1424138D03*
X1140175Y1423488D03*
X1140215Y1428668D03*
Y1426168D03*
X1134815Y1433668D03*
X1137315D03*
X1140215D03*
Y1431168D03*
X1132315Y1433668D03*
X1137315Y1426818D03*
X1134815D03*
X1137345Y1431058D03*
X1134845D03*
X1132315Y1426818D03*
X1132345Y1431058D03*
X1126915Y1428668D03*
Y1426168D03*
X1129815Y1433668D03*
X1126915D03*
Y1431168D03*
X1129815Y1426818D03*
X1129845Y1431058D03*
X1137846Y1453487D03*
X1131478Y1485427D03*
X1134183Y1483926D03*
X1126951Y1484646D03*
X1140960Y1489434D03*
Y1491934D03*
X1141045Y1534952D03*
Y1537452D03*
Y1544952D03*
Y1542452D03*
Y1539952D03*
X1135043Y1553371D03*
X1135033Y1556112D03*
X1133765Y1572102D03*
X1137523Y1579453D03*
X1136173Y1573638D03*
X1133765Y1568952D03*
X1140655Y1569256D03*
X1137755Y1569543D03*
X1140422Y1595455D03*
X1139037Y1611383D03*
X1131790Y1597984D03*
X1131832Y1607245D03*
X1131824Y1600593D03*
Y1603993D03*
X1140325Y1598697D03*
X1138752Y1624627D03*
X1139037Y1614153D03*
X1139142Y1618859D03*
X1139188Y1621603D03*
X1130772Y1641753D03*
X1130684Y1646949D03*
X1130245Y1652189D03*
X1141084Y1646672D03*
Y1643272D03*
X1137542Y1647925D03*
X1140117Y1671421D03*
X1129230Y1666174D03*
X1134207Y1669230D03*
X1129184Y1662705D03*
X1132406Y1658967D03*
X1137492Y1685240D03*
X1136575Y1676239D03*
X1141356Y1676542D03*
X1133206Y1675383D03*
X1128934Y1688600D03*
X1132176Y1690038D03*
X1150199Y49379D03*
X1155577Y73939D03*
X1142643Y74738D03*
X1150118Y207344D03*
X1155268D03*
Y212344D03*
X1150118D03*
X1155890Y478812D03*
X1150577Y478840D03*
X1147813Y492319D03*
X1144663D03*
Y500319D03*
X1143060Y516476D03*
X1154145Y583339D03*
Y586339D03*
X1146159Y756765D03*
X1155209Y756831D03*
X1150709Y776910D03*
Y773563D03*
X1146160Y763765D03*
Y767299D03*
Y771099D03*
X1150709Y776910D03*
X1155209Y763524D03*
X1155259Y770217D03*
X1150709Y783603D03*
Y790296D03*
Y793642D03*
X1146309Y791969D03*
X1145259Y786949D03*
X1150709Y780256D03*
Y783603D03*
Y790296D03*
Y800335D03*
Y807028D03*
X1145259Y796988D03*
X1150709Y803681D03*
Y800335D03*
Y807028D03*
Y793642D03*
Y813721D03*
Y820414D03*
Y810374D03*
Y817067D03*
Y813721D03*
Y820414D03*
Y837146D03*
Y830453D03*
Y827107D03*
X1146309Y828780D03*
X1145259Y823760D03*
Y833799D03*
X1150709Y837146D03*
Y830453D03*
Y827107D03*
Y843839D03*
Y850532D03*
Y840492D03*
Y847185D03*
Y843839D03*
Y850532D03*
Y857225D03*
Y863918D03*
Y867264D03*
X1146309Y865591D03*
X1145259Y860571D03*
X1150709Y853878D03*
Y857225D03*
Y863918D03*
Y873957D03*
Y880650D03*
X1145259Y870610D03*
X1150709Y877303D03*
Y873957D03*
Y880650D03*
Y867264D03*
Y887343D03*
Y894036D03*
Y883996D03*
Y890689D03*
Y887343D03*
Y894036D03*
Y910768D03*
Y904075D03*
Y900729D03*
X1145259Y907422D03*
X1146309Y902402D03*
X1145259Y897382D03*
X1150709Y910768D03*
Y904075D03*
Y900729D03*
Y924154D03*
Y917461D03*
Y914114D03*
Y920807D03*
Y924154D03*
Y917461D03*
Y930847D03*
Y940886D03*
Y937540D03*
X1145259Y934193D03*
X1146309Y939213D03*
X1150709Y927500D03*
Y930847D03*
Y940886D03*
Y937540D03*
Y947579D03*
Y954272D03*
X1145259Y944233D03*
X1150709Y950925D03*
Y947579D03*
Y954272D03*
X1156209Y960965D03*
X1150709Y967658D03*
Y964311D03*
Y971004D03*
Y957618D03*
Y960965D03*
Y967658D03*
Y974351D03*
Y981044D03*
Y987736D03*
Y977697D03*
Y984390D03*
Y974351D03*
Y981044D03*
Y994429D03*
Y1001122D03*
Y991083D03*
Y997776D03*
Y987736D03*
Y994429D03*
Y1001122D03*
Y1004469D03*
Y1027894D03*
D03*
Y1034587D03*
Y1041280D03*
Y1047973D03*
Y1031240D03*
Y1037933D03*
Y1044626D03*
Y1034587D03*
Y1041280D03*
Y1054666D03*
Y1061359D03*
Y1051319D03*
Y1058012D03*
Y1047973D03*
Y1054666D03*
Y1071398D03*
Y1064705D03*
Y1074744D03*
Y1068051D03*
Y1061359D03*
Y1071398D03*
Y1064705D03*
Y1078091D03*
Y1088130D03*
Y1084784D03*
X1146309Y1086457D03*
X1145259Y1081437D03*
X1150709Y1078091D03*
Y1088130D03*
Y1084784D03*
Y1094823D03*
Y1101516D03*
X1145259Y1091477D03*
X1150709Y1098170D03*
Y1104862D03*
Y1094823D03*
Y1101516D03*
Y1108209D03*
Y1114902D03*
Y1121595D03*
X1145259Y1118248D03*
X1150709Y1111555D03*
Y1108209D03*
Y1114902D03*
Y1131634D03*
Y1124941D03*
Y1134981D03*
X1146309Y1123268D03*
X1145259Y1128288D03*
X1150709Y1131634D03*
Y1124941D03*
Y1121595D03*
Y1138327D03*
Y1145020D03*
Y1151713D03*
Y1141674D03*
Y1148366D03*
Y1138327D03*
Y1145020D03*
Y1161752D03*
Y1158406D03*
X1145259Y1155059D03*
X1146309Y1160079D03*
X1145259Y1165099D03*
X1150709Y1151713D03*
Y1161752D03*
Y1158406D03*
Y1168445D03*
Y1175138D03*
Y1181831D03*
Y1171792D03*
Y1178485D03*
Y1168445D03*
Y1175138D03*
Y1188524D03*
Y1195217D03*
X1145259Y1191870D03*
X1150709Y1185177D03*
Y1181831D03*
Y1188524D03*
Y1205256D03*
Y1198563D03*
Y1211949D03*
X1145259Y1201910D03*
X1146309Y1196890D03*
X1150709Y1208603D03*
Y1205256D03*
Y1198563D03*
Y1195217D03*
Y1218642D03*
Y1225335D03*
Y1215296D03*
Y1221988D03*
Y1211949D03*
Y1218642D03*
Y1235374D03*
Y1232028D03*
X1145259Y1238721D03*
X1146309Y1233701D03*
X1145259Y1228681D03*
X1150709Y1225335D03*
Y1235374D03*
Y1232028D03*
Y1242067D03*
Y1248760D03*
Y1245414D03*
Y1252107D03*
Y1242067D03*
Y1248760D03*
X1142203Y1300361D03*
Y1302861D03*
X1144703D03*
Y1300361D03*
X1142203Y1305361D03*
X1144703D03*
X1155503Y1312861D03*
Y1310361D03*
Y1307861D03*
X1142203D03*
Y1310361D03*
Y1312861D03*
X1144703D03*
Y1310361D03*
Y1307861D03*
X1155503Y1302861D03*
Y1300361D03*
Y1305361D03*
Y1315361D03*
X1142203D03*
X1144703D03*
X1142203Y1317861D03*
X1144703D03*
X1155503D03*
X1154839Y1337834D03*
X1145819D03*
X1143219D03*
X1152315Y1357390D03*
X1154815D03*
X1147115D03*
X1149715D03*
X1141915D03*
X1144515D03*
X1147115Y1360497D03*
X1149715Y1363454D03*
Y1360497D03*
X1147115Y1363454D03*
X1146189Y1372853D03*
X1148619D03*
Y1367253D03*
X1146189D03*
X1141915Y1360497D03*
X1144515D03*
X1143759Y1367253D03*
Y1372853D03*
X1152359D03*
X1154789D03*
X1148668Y1385268D03*
X1141901Y1382574D03*
Y1380066D03*
X1149343Y1382111D03*
X1145855Y1380511D03*
X1148593Y1379543D03*
X1150458Y1433146D03*
X1142675Y1423488D03*
X1145715Y1423555D03*
X1145755Y1426235D03*
Y1428735D03*
Y1431235D03*
Y1433735D03*
X1142715Y1426168D03*
Y1428668D03*
Y1431168D03*
Y1433668D03*
X1144118Y1449628D03*
X1150718Y1462792D03*
X1153724Y1462695D03*
X1154824Y1471134D03*
X1145960Y1491934D03*
X1148460D03*
X1150960D03*
X1153460D03*
X1155960D03*
X1145960Y1489434D03*
X1148460D03*
X1150960D03*
X1153460D03*
X1155960D03*
X1143460D03*
Y1491934D03*
X1153545Y1534952D03*
X1151045D03*
X1148545D03*
X1146045D03*
X1143545D03*
X1153545Y1537452D03*
X1151045D03*
X1148545D03*
X1146045D03*
X1143545D03*
X1151045Y1544952D03*
X1148545D03*
X1146045D03*
X1143545D03*
X1153545D03*
X1143545Y1542452D03*
X1146045D03*
X1148545D03*
X1151045D03*
X1153545D03*
Y1539952D03*
X1151045D03*
X1148545D03*
X1146045D03*
X1143545D03*
X1151384Y1556029D03*
X1155253Y1559176D03*
X1143063Y1580334D03*
X1152186Y1570567D03*
X1149467Y1568988D03*
X1145060Y1588837D03*
X1142917Y1583314D03*
Y1586714D03*
X1141645Y1640017D03*
X1146316Y1649422D03*
X1143127Y1649068D03*
X1155180Y1655534D03*
X1146501Y1655608D03*
Y1652208D03*
X1152198Y1669629D03*
X1144107Y1671118D03*
X1146477Y1658441D03*
X1151707Y1663655D03*
X1154500Y1677000D03*
X1142033Y1682412D03*
X1162086Y76509D03*
X1163113Y481691D03*
X1162144Y487630D03*
X1165589Y569118D03*
X1166131Y580602D03*
X1157038Y583298D03*
Y586298D03*
X1166026Y669006D03*
X1168818Y756765D03*
Y760265D03*
X1159768Y756831D03*
Y760177D03*
X1164268Y776910D03*
X1168818Y767265D03*
Y763765D03*
X1159718Y763524D03*
X1164268Y780256D03*
Y786949D03*
Y793642D03*
Y783603D03*
X1169718Y790296D03*
X1164268Y780256D03*
Y786949D03*
Y803681D03*
Y796988D03*
X1159868Y795315D03*
X1164268Y807028D03*
X1169718Y800335D03*
X1164268Y803681D03*
Y793642D03*
Y796988D03*
Y817067D03*
Y810374D03*
Y823760D03*
Y820414D03*
Y813721D03*
Y817067D03*
Y810374D03*
Y830453D03*
Y833799D03*
X1159868Y832126D03*
X1169718Y837146D03*
Y827107D03*
X1164268Y823760D03*
Y830453D03*
Y833799D03*
Y840492D03*
Y847185D03*
Y853878D03*
Y850532D03*
Y843839D03*
Y840492D03*
Y847185D03*
Y860571D03*
Y867264D03*
Y857225D03*
X1169718Y863918D03*
X1164268Y853878D03*
Y860571D03*
Y877303D03*
Y870610D03*
Y883996D03*
X1159868Y868937D03*
X1164268Y880650D03*
X1169718Y873957D03*
X1164268Y877303D03*
Y867264D03*
Y870610D03*
Y890689D03*
Y897382D03*
Y887343D03*
Y894036D03*
Y883996D03*
Y890689D03*
Y904075D03*
Y907422D03*
X1159868Y905749D03*
X1169718Y900729D03*
Y910768D03*
X1164268Y897382D03*
Y904075D03*
Y907422D03*
Y914114D03*
Y920807D03*
Y927500D03*
Y917461D03*
Y924154D03*
Y914114D03*
Y920807D03*
Y934193D03*
Y940886D03*
X1169718Y937540D03*
X1164268Y930847D03*
Y927500D03*
Y934193D03*
Y940886D03*
Y950925D03*
Y944233D03*
Y957618D03*
X1159868Y942560D03*
X1169718Y947579D03*
X1164268Y954272D03*
Y950925D03*
Y944233D03*
Y964311D03*
Y971004D03*
Y960965D03*
Y967658D03*
Y964311D03*
Y957618D03*
Y971004D03*
X1156209Y960965D03*
X1164268Y977697D03*
Y984390D03*
Y974351D03*
Y981044D03*
Y977697D03*
Y984390D03*
Y1001122D03*
Y997776D03*
Y991083D03*
Y987736D03*
Y994429D03*
Y1001122D03*
Y997776D03*
Y991083D03*
Y1004469D03*
Y1031240D03*
Y1037933D03*
Y1044626D03*
Y1034587D03*
Y1041280D03*
Y1031240D03*
Y1037933D03*
Y1044626D03*
Y1058012D03*
Y1051319D03*
Y1047973D03*
Y1054666D03*
Y1058012D03*
Y1051319D03*
Y1074744D03*
Y1061359D03*
Y1071398D03*
Y1074744D03*
Y1068051D03*
Y1064705D03*
Y1081437D03*
Y1088130D03*
Y1091477D03*
X1159868Y1089804D03*
X1169718Y1084784D03*
X1164268Y1078091D03*
Y1081437D03*
Y1088130D03*
Y1098170D03*
Y1104862D03*
X1169718Y1094823D03*
X1164268Y1101516D03*
Y1098170D03*
Y1104862D03*
Y1091477D03*
Y1111555D03*
Y1118248D03*
Y1108209D03*
Y1114902D03*
Y1111555D03*
Y1118248D03*
Y1134981D03*
Y1124941D03*
Y1128288D03*
X1159868Y1126615D03*
X1169718Y1121595D03*
Y1131634D03*
X1164268Y1134981D03*
Y1124941D03*
Y1128288D03*
Y1148366D03*
Y1141674D03*
Y1138327D03*
Y1145020D03*
Y1148366D03*
Y1141674D03*
Y1155059D03*
Y1161752D03*
Y1165099D03*
X1159868Y1163426D03*
X1169718Y1158406D03*
X1164268Y1151713D03*
Y1155059D03*
Y1161752D03*
Y1165099D03*
Y1171792D03*
Y1178485D03*
X1169718Y1168445D03*
X1164268Y1175138D03*
Y1171792D03*
Y1178485D03*
Y1185177D03*
Y1191870D03*
Y1181831D03*
Y1188524D03*
Y1185177D03*
Y1191870D03*
Y1208603D03*
Y1198563D03*
Y1201910D03*
X1159868Y1200237D03*
X1169718Y1205256D03*
Y1195217D03*
X1164268Y1208603D03*
Y1198563D03*
Y1201910D03*
Y1215296D03*
Y1221988D03*
Y1211949D03*
Y1218642D03*
Y1215296D03*
Y1221988D03*
Y1228681D03*
Y1235374D03*
Y1238721D03*
X1159868Y1237048D03*
X1169718Y1232028D03*
X1164268Y1225335D03*
Y1228681D03*
Y1235374D03*
Y1238721D03*
Y1245414D03*
Y1252107D03*
X1169718Y1242067D03*
X1164268Y1248760D03*
Y1245414D03*
Y1252107D03*
Y1255453D03*
X1158003Y1307861D03*
Y1310361D03*
Y1312861D03*
Y1300361D03*
Y1302861D03*
Y1305361D03*
X1160503Y1302861D03*
Y1300361D03*
Y1305361D03*
Y1307861D03*
Y1310361D03*
Y1312861D03*
X1158003Y1315361D03*
Y1317861D03*
X1160503D03*
Y1315361D03*
X1167509Y1337884D03*
X1164909D03*
X1157439Y1337834D03*
X1160929Y1352252D03*
X1163529D03*
X1160929Y1349652D03*
X1163529D03*
X1162279Y1357352D03*
X1163529Y1354852D03*
X1157259Y1357406D03*
X1170138Y1361800D03*
X1158205Y1363394D03*
Y1360437D03*
X1168039Y1368999D03*
Y1371540D03*
X1157219Y1372853D03*
X1158059Y1367018D03*
Y1369918D03*
X1164249Y1373158D03*
X1169488Y1386721D03*
X1167830Y1384770D03*
X1169532Y1379914D03*
X1164249Y1376058D03*
X1159983Y1376288D03*
X1162049Y1374558D03*
X1164249Y1378958D03*
X1159983Y1379188D03*
X1162149Y1377558D03*
X1160163Y1445627D03*
X1163422Y1445000D03*
X1166350Y1454234D03*
X1160750Y1463250D03*
X1164300Y1463300D03*
X1159283Y1471132D03*
X1158460Y1491934D03*
Y1489434D03*
X1170986Y1516590D03*
Y1513190D03*
Y1519190D03*
Y1510590D03*
X1168386Y1517280D03*
Y1512500D03*
X1170986Y1516590D03*
Y1513190D03*
Y1534990D03*
Y1538390D03*
Y1532490D03*
X1168386Y1534300D03*
X1170986Y1534990D03*
X1168386Y1539080D03*
X1170986Y1540990D03*
X1161311Y1548204D03*
X1170986Y1538390D03*
X1169061Y1543800D03*
X1170061Y1551040D03*
X1164528Y1565578D03*
X1170404Y1556331D03*
Y1559731D03*
X1166873Y1561431D03*
X1157255Y1556000D03*
X1160031Y1591163D03*
X1170539Y1595621D03*
X1168023Y1586251D03*
X1170539Y1588751D03*
X1168023D03*
X1170539Y1586251D03*
Y1583751D03*
Y1600621D03*
Y1598121D03*
X1170339Y1603121D03*
X1162144Y1658042D03*
X1159741Y1669759D03*
X1159703Y1673000D03*
X1159500Y1679000D03*
Y1682500D03*
X1180124Y-35569D03*
X1183149Y-34249D03*
X1183164Y-36764D03*
X1177404Y-21711D03*
Y-18311D03*
Y-11711D03*
Y-21711D03*
Y-18311D03*
X1174958Y-24648D03*
Y-15374D03*
X1183139Y-26179D03*
X1183050Y-20074D03*
X1180099Y-14984D03*
X1183124Y-13664D03*
X1183139Y-16179D03*
X1183124Y-23664D03*
X1180099Y-24984D03*
X1177404Y-8311D03*
Y-11711D03*
Y-8311D03*
X1174958Y-5374D03*
X1183050Y-10074D03*
Y-74D03*
X1183139Y-6179D03*
X1183124Y-3664D03*
X1180099Y-4984D03*
X1177404Y11689D03*
Y8289D03*
Y18289D03*
Y11689D03*
Y8289D03*
X1174958Y5352D03*
Y15352D03*
X1180099Y15016D03*
X1183124Y16336D03*
X1183139Y13821D03*
X1183050Y9926D03*
X1180099Y5016D03*
X1183124Y6336D03*
X1183139Y3821D03*
X1177404Y21689D03*
Y18289D03*
Y21689D03*
X1174958Y24626D03*
X1183140Y24187D03*
X1183125Y26702D03*
X1180100Y25382D03*
X1184194Y57015D03*
Y61515D03*
X1176972Y86788D03*
X1177429Y89556D03*
Y93556D03*
X1175181Y447841D03*
Y442341D03*
X1185952Y444202D03*
Y436202D03*
X1178340Y442234D03*
X1176000Y436500D03*
X1180000Y436000D03*
X1185707Y460202D03*
X1175181Y458841D03*
Y464341D03*
Y453341D03*
X1185952Y452202D03*
X1178340Y458734D03*
X1178254Y453142D03*
X1178340Y461615D03*
X1185707Y470392D03*
X1175181Y469841D03*
X1178340Y467165D03*
X1175181Y481691D03*
X1185117Y571807D03*
X1181445Y592868D03*
X1183811Y640682D03*
X1182713Y733815D03*
X1175860Y756765D03*
X1184910Y756831D03*
X1180410Y776910D03*
Y773563D03*
X1175860Y763765D03*
Y767299D03*
Y771099D03*
X1180410Y776910D03*
X1184910Y763524D03*
X1184960Y770217D03*
X1180410Y783603D03*
Y790296D03*
Y793642D03*
X1176010Y791969D03*
X1180410Y780256D03*
X1174960Y786949D03*
X1180410Y783603D03*
Y790296D03*
Y800335D03*
Y807028D03*
Y803681D03*
X1174960Y796988D03*
X1180410Y800335D03*
Y807028D03*
Y793642D03*
Y813721D03*
Y820414D03*
Y817067D03*
Y810374D03*
Y813721D03*
Y820414D03*
Y837146D03*
Y830453D03*
Y827107D03*
X1176010Y828780D03*
X1174960Y833799D03*
Y823760D03*
X1180410Y837146D03*
Y830453D03*
Y827107D03*
Y843839D03*
Y850532D03*
Y847185D03*
Y840492D03*
Y843839D03*
Y850532D03*
Y857225D03*
Y863918D03*
Y867264D03*
X1176010Y865591D03*
X1180410Y853878D03*
X1174960Y860571D03*
X1180410Y857225D03*
Y863918D03*
Y873957D03*
Y880650D03*
Y877303D03*
X1174960Y870610D03*
X1180410Y873957D03*
Y880650D03*
Y867264D03*
Y887343D03*
Y894036D03*
Y890689D03*
Y883996D03*
Y887343D03*
Y894036D03*
Y910768D03*
Y904075D03*
Y900729D03*
X1176010Y902402D03*
X1174960Y897382D03*
Y907422D03*
X1180410Y910768D03*
Y904075D03*
Y900729D03*
Y924154D03*
Y917461D03*
Y914114D03*
Y920807D03*
Y924154D03*
Y917461D03*
Y930847D03*
Y940886D03*
Y937540D03*
X1176010Y939213D03*
X1174960Y934193D03*
X1180410Y927500D03*
Y930847D03*
Y940886D03*
Y937540D03*
Y947579D03*
Y954272D03*
X1174960Y944233D03*
X1180410Y950925D03*
Y947579D03*
Y954272D03*
X1185910Y960965D03*
X1180410Y967658D03*
Y957618D03*
Y964311D03*
Y971004D03*
Y960965D03*
Y967658D03*
Y974351D03*
Y981044D03*
Y987736D03*
Y977697D03*
Y984390D03*
Y974351D03*
Y981044D03*
Y994429D03*
Y1001122D03*
Y991083D03*
Y997776D03*
Y987736D03*
Y994429D03*
Y1001122D03*
Y1004469D03*
Y1027894D03*
D03*
Y1034587D03*
Y1041280D03*
Y1047973D03*
Y1031240D03*
Y1037933D03*
Y1044626D03*
Y1034587D03*
Y1041280D03*
Y1054666D03*
Y1061359D03*
Y1051319D03*
Y1058012D03*
Y1047973D03*
Y1054666D03*
Y1071398D03*
Y1064705D03*
Y1068051D03*
Y1074744D03*
Y1061359D03*
Y1071398D03*
Y1064705D03*
Y1078091D03*
Y1088130D03*
Y1084784D03*
X1176010Y1086457D03*
X1174960Y1081437D03*
X1180410Y1078091D03*
Y1088130D03*
Y1084784D03*
Y1094823D03*
Y1101516D03*
X1174960Y1091477D03*
X1180410Y1098170D03*
Y1104862D03*
Y1094823D03*
Y1101516D03*
Y1108209D03*
Y1114902D03*
Y1121595D03*
X1174960Y1118248D03*
X1180410Y1111555D03*
Y1108209D03*
Y1114902D03*
Y1131634D03*
Y1124941D03*
X1176010Y1123268D03*
X1174960Y1128288D03*
X1180410Y1134981D03*
Y1131634D03*
Y1124941D03*
Y1121595D03*
Y1138327D03*
Y1145020D03*
Y1151713D03*
Y1141674D03*
Y1148366D03*
Y1138327D03*
Y1145020D03*
Y1161752D03*
Y1158406D03*
X1176010Y1160079D03*
X1174960Y1155059D03*
Y1165099D03*
X1180410Y1151713D03*
Y1161752D03*
Y1158406D03*
Y1168445D03*
Y1175138D03*
Y1181831D03*
Y1171792D03*
Y1178485D03*
Y1168445D03*
Y1175138D03*
Y1188524D03*
Y1195217D03*
X1174960Y1191870D03*
X1180410Y1185177D03*
Y1181831D03*
Y1188524D03*
Y1205256D03*
Y1198563D03*
Y1211949D03*
X1176010Y1196890D03*
X1174960Y1201910D03*
X1180410Y1208603D03*
Y1205256D03*
Y1198563D03*
Y1195217D03*
Y1218642D03*
Y1225335D03*
Y1215296D03*
Y1221988D03*
Y1211949D03*
Y1218642D03*
Y1235374D03*
Y1232028D03*
X1176010Y1233701D03*
X1174960Y1238721D03*
Y1228681D03*
X1180410Y1225335D03*
Y1235374D03*
Y1232028D03*
Y1242067D03*
Y1248760D03*
Y1245414D03*
Y1252107D03*
Y1242067D03*
Y1248760D03*
X1172603Y1302861D03*
Y1300361D03*
Y1305361D03*
Y1307861D03*
Y1310361D03*
Y1312861D03*
X1175103Y1300361D03*
Y1302861D03*
X1177603D03*
Y1300361D03*
X1175103Y1305361D03*
X1177603D03*
X1175103Y1307861D03*
Y1310361D03*
Y1312861D03*
X1177603D03*
Y1310361D03*
Y1307861D03*
X1175103Y1315361D03*
X1177603D03*
X1172603Y1317861D03*
Y1315361D03*
X1175103Y1317861D03*
X1177603D03*
X1182615Y1357390D03*
X1185215D03*
X1177415D03*
X1174815D03*
X1180015D03*
X1182615Y1363454D03*
Y1360497D03*
X1180015Y1363454D03*
X1174815Y1360497D03*
X1177415D03*
X1180015D03*
X1176659Y1367253D03*
Y1372853D03*
X1179089D03*
X1181519D03*
Y1367253D03*
X1179089D03*
X1185259Y1372853D03*
X1181568Y1385268D03*
X1174801Y1382574D03*
Y1380066D03*
X1182243Y1382111D03*
X1178755Y1380511D03*
X1181493Y1379543D03*
X1171812Y1376389D03*
X1185000Y1396500D03*
Y1401000D03*
X1184100Y1410000D03*
X1185000Y1405500D03*
X1178400Y1433000D03*
X1184900Y1428500D03*
X1183000Y1422900D03*
X1184175Y1435600D03*
X1176500Y1457071D03*
X1180200Y1457100D03*
X1183924Y1485895D03*
X1187324D03*
X1181324D03*
X1183234Y1483295D03*
Y1488495D03*
X1181314Y1492995D03*
X1176534D03*
X1183924Y1485895D03*
X1180624Y1495595D03*
X1177224D03*
X1183224D03*
X1174624D03*
X1181314Y1498195D03*
X1176534D03*
X1180624Y1495595D03*
X1177224D03*
X1173586Y1517280D03*
Y1512500D03*
Y1534300D03*
X1180047Y1533247D03*
X1173586Y1539080D03*
X1181361Y1543800D03*
Y1547420D03*
Y1551040D03*
X1181853Y1561731D03*
X1172523Y1562350D03*
X1172603Y1554561D03*
X1178039Y1595621D03*
X1175539D03*
X1173039D03*
X1180923Y1588751D03*
Y1586251D03*
X1173039Y1588751D03*
X1175539D03*
X1178039D03*
Y1586251D03*
X1175539D03*
X1173039D03*
X1178039Y1583751D03*
X1175539D03*
X1173039D03*
X1178039Y1600621D03*
X1175539D03*
X1173039D03*
X1178039Y1598121D03*
X1175539D03*
X1173039D03*
X1175339Y1603121D03*
X1172839D03*
X1177839D03*
X1179187Y1666429D03*
X1175454Y1668046D03*
X1184362Y1670254D03*
X1181385Y1670312D03*
X1175726Y1686726D03*
X1186402Y-34263D03*
X1186417Y-36778D03*
X1186448Y-31442D03*
X1186433Y-28927D03*
X1186392Y-26193D03*
X1186312Y-20074D03*
X1186377Y-13678D03*
X1186392Y-16193D03*
X1186377Y-23678D03*
X1186312Y-10074D03*
Y-74D03*
X1186392Y-6193D03*
X1186377Y-3678D03*
Y16322D03*
X1186392Y13807D03*
X1186312Y9926D03*
X1186377Y6322D03*
X1186392Y3807D03*
X1186423Y19143D03*
X1186408Y21658D03*
X1186393Y24173D03*
X1186378Y26688D03*
X1194199Y49379D03*
X1191488Y91125D03*
X1188472Y80165D03*
X1195488Y93550D03*
X1190587Y99694D03*
X1199756Y128748D03*
X1200037Y164987D03*
X1189727D03*
Y160987D03*
Y177187D03*
X1200037D03*
X1200012Y181187D03*
Y185187D03*
X1186821Y185430D03*
Y181930D03*
X1195767Y460202D03*
Y470392D03*
Y465272D03*
X1189540Y481691D03*
X1191087Y573809D03*
X1188267Y571807D03*
X1188192Y589263D03*
X1191646Y589567D03*
X1195729Y591022D03*
X1199392Y590500D03*
X1200923Y601734D03*
Y606134D03*
X1199539Y638492D03*
X1197039D03*
X1194539D03*
X1192039D03*
X1195108Y668148D03*
X1198456Y668138D03*
X1198519Y756765D03*
Y760265D03*
X1189469Y760177D03*
Y756831D03*
X1193969Y776910D03*
X1198519Y767265D03*
Y763765D03*
X1188805Y766870D03*
X1189419Y763524D03*
X1193969Y783603D03*
X1199419Y790296D03*
X1189569Y795315D03*
X1193969Y807028D03*
X1199419Y800335D03*
X1193969Y820414D03*
Y813721D03*
X1189569Y832126D03*
X1199419Y837146D03*
Y827107D03*
X1193969Y850532D03*
Y843839D03*
Y857225D03*
X1199419Y863918D03*
X1189569Y868937D03*
X1193969Y880650D03*
X1199419Y873957D03*
X1193969Y887343D03*
Y894036D03*
X1189569Y905749D03*
X1199419Y900729D03*
Y910768D03*
X1193969Y917461D03*
Y924154D03*
X1199419Y937540D03*
X1193969Y930847D03*
Y954272D03*
X1189569Y942560D03*
X1199419Y947579D03*
X1193969Y960965D03*
Y967658D03*
X1185910Y960965D03*
X1193969Y974351D03*
Y981044D03*
Y987736D03*
Y994429D03*
Y1004469D03*
Y1034587D03*
Y1041280D03*
Y1047973D03*
Y1054666D03*
Y1061359D03*
Y1071398D03*
X1189569Y1089804D03*
X1199419Y1084784D03*
X1193969Y1078091D03*
X1199419Y1094823D03*
X1193969Y1101516D03*
Y1108209D03*
Y1114902D03*
X1189569Y1126615D03*
X1199419Y1121595D03*
Y1131634D03*
X1193969Y1138327D03*
Y1145020D03*
X1189569Y1163426D03*
X1199419Y1158406D03*
X1193969Y1151713D03*
X1199419Y1168445D03*
X1193969Y1175138D03*
Y1181831D03*
Y1188524D03*
X1189569Y1200237D03*
X1199419Y1195217D03*
Y1205256D03*
X1193969Y1211949D03*
Y1218642D03*
X1189569Y1237048D03*
X1193969Y1225335D03*
X1199419Y1232028D03*
X1193969Y1248760D03*
X1199419Y1242067D03*
X1193969Y1255453D03*
X1190903Y1307861D03*
Y1310361D03*
Y1312861D03*
X1188403D03*
Y1310361D03*
Y1307861D03*
Y1302861D03*
Y1300361D03*
Y1305361D03*
X1190903Y1300361D03*
Y1302861D03*
X1193403D03*
Y1300361D03*
X1190903Y1305361D03*
X1193403D03*
Y1307861D03*
Y1310361D03*
Y1312861D03*
X1196159Y1326549D03*
X1193659Y1326589D03*
Y1324049D03*
X1196259D03*
X1193659Y1321549D03*
X1196259D03*
X1190903Y1315361D03*
X1188403D03*
Y1317861D03*
X1190903D03*
X1193403D03*
Y1315361D03*
X1199899Y1338065D03*
X1193829Y1352252D03*
X1196429D03*
X1193829Y1349652D03*
X1196429D03*
X1193829Y1354852D03*
X1190159Y1357406D03*
X1195179Y1357352D03*
X1196429Y1354852D03*
X1187715Y1357390D03*
X1191105Y1363394D03*
Y1360437D03*
X1200839Y1368999D03*
Y1371540D03*
X1190119Y1372853D03*
X1191049Y1367188D03*
Y1370088D03*
X1187689Y1372853D03*
X1197149Y1373158D03*
X1200690Y1384572D03*
X1192883Y1379188D03*
X1195049Y1377558D03*
X1197149Y1378958D03*
X1192883Y1376288D03*
X1194949Y1374558D03*
X1197149Y1376058D03*
X1194000Y1401000D03*
Y1418000D03*
X1187925Y1417000D03*
X1194000Y1414500D03*
X1194366Y1405500D03*
X1193929Y1410000D03*
X1191000Y1425900D03*
X1194000Y1428500D03*
Y1433000D03*
X1198800Y1421500D03*
X1194000Y1424000D03*
X1188000Y1419800D03*
X1187925Y1440400D03*
X1194000Y1437500D03*
Y1447500D03*
X1189924Y1485895D03*
X1188014Y1483295D03*
Y1488495D03*
X1187324Y1485895D03*
X1200724Y1505295D03*
X1197324D03*
X1194724D03*
X1196634Y1502695D03*
Y1507895D03*
X1200724Y1505295D03*
X1197324D03*
X1196127Y1577997D03*
Y1581397D03*
X1200851Y1577997D03*
Y1581397D03*
X1196127Y1577997D03*
Y1581397D03*
X1200824Y1593498D03*
X1196127Y1583797D03*
X1188960Y1609135D03*
X1186455Y1608390D03*
Y1602590D03*
Y1605490D03*
X1199439Y1625380D03*
X1196039D03*
X1195261Y1622884D03*
X1200217D03*
X1195050Y1620040D03*
X1196039Y1625380D03*
X1199439D03*
X1190174Y1615418D03*
X1202069Y1635380D03*
X1195261Y1627876D03*
X1200217D03*
X1202069Y1647292D03*
X1196039Y1657292D03*
X1199439D03*
X1200217Y1654796D03*
X1195261D03*
X1200217Y1659788D03*
X1195261D03*
X1192903Y1666276D03*
X1190616Y1670641D03*
X1196039Y1657292D03*
X1199439D03*
X1190314Y1661630D03*
X1192612Y1680410D03*
X1199299Y1675517D03*
X1197746Y1680914D03*
X1199272Y1683025D03*
X1199612Y1700334D03*
Y1691366D03*
X1189462Y1700334D03*
X1194478Y1699936D03*
X1189407Y1717518D03*
X1191351Y1737117D03*
X1215581Y91346D03*
X1202711Y87651D03*
X1205929Y86872D03*
X1215581Y94846D03*
X1208431Y133866D03*
X1214094Y258633D03*
X1214156Y292066D03*
X1205625Y313758D03*
X1210698Y313671D03*
X1207447Y341381D03*
X1202508Y341424D03*
X1214856Y421018D03*
X1212700Y475712D03*
X1206590Y481403D03*
X1203269Y481237D03*
X1212051Y559827D03*
X1205900Y582443D03*
X1208400Y591631D03*
X1206191Y588400D03*
X1205679Y594148D03*
X1201440Y668138D03*
X1207177Y668115D03*
X1209796D03*
X1205561Y756765D03*
X1214600Y759562D03*
X1210111Y773563D03*
X1205561Y763765D03*
X1205630Y766600D03*
X1205448Y769914D03*
X1214661Y766870D03*
X1214611Y763524D03*
X1214841Y772277D03*
X1205711Y791969D03*
X1210111Y780256D03*
X1204661Y786949D03*
X1210111Y803681D03*
X1204661Y796988D03*
X1210111Y817067D03*
Y810374D03*
X1205711Y828780D03*
X1204661Y833799D03*
Y823760D03*
X1210111Y847185D03*
Y840492D03*
X1205711Y865591D03*
X1210111Y853878D03*
X1204661Y860571D03*
X1210111Y877303D03*
X1204661Y870610D03*
X1210111Y890689D03*
Y883996D03*
X1205711Y902402D03*
X1204661Y897382D03*
Y907422D03*
X1210111Y914114D03*
Y920807D03*
X1205711Y939213D03*
X1204661Y934193D03*
X1210111Y927500D03*
X1204661Y944233D03*
X1210111Y950925D03*
Y957618D03*
Y964311D03*
Y971004D03*
Y960965D03*
X1203682D03*
X1210111Y977697D03*
Y984390D03*
Y991083D03*
Y997776D03*
Y1004469D03*
Y1031240D03*
Y1037933D03*
Y1044626D03*
Y1051319D03*
Y1058012D03*
Y1068051D03*
Y1074744D03*
X1205711Y1086457D03*
X1204661Y1081437D03*
Y1091477D03*
X1210111Y1098170D03*
Y1104862D03*
X1204661Y1118248D03*
X1210111Y1111555D03*
X1205711Y1123268D03*
X1204661Y1128288D03*
X1210111Y1134981D03*
Y1141674D03*
Y1148366D03*
X1205711Y1160079D03*
X1204661Y1155059D03*
Y1165099D03*
X1210111Y1171792D03*
Y1178485D03*
X1204661Y1191870D03*
X1210111Y1185177D03*
X1205711Y1196890D03*
X1204661Y1201910D03*
X1210111Y1208603D03*
Y1215296D03*
Y1221988D03*
X1205711Y1233701D03*
X1204661Y1228681D03*
Y1238721D03*
X1210111Y1245414D03*
Y1252107D03*
X1207903Y1300361D03*
Y1302861D03*
X1210403D03*
Y1300361D03*
X1207903Y1305361D03*
X1210403D03*
X1207903Y1307861D03*
Y1310361D03*
Y1312861D03*
X1210403D03*
Y1310361D03*
Y1307861D03*
X1205403Y1302861D03*
Y1300361D03*
Y1305361D03*
Y1307861D03*
Y1310361D03*
Y1312861D03*
X1205189Y1321492D03*
Y1323992D03*
X1202689Y1321492D03*
Y1324032D03*
X1207903Y1315361D03*
X1210403D03*
X1205403Y1317861D03*
Y1315361D03*
X1207903Y1317861D03*
X1210403D03*
X1211299Y1338105D03*
X1202399D03*
X1215415Y1357390D03*
X1212815D03*
X1210215D03*
X1207615D03*
X1202988Y1361490D03*
X1215415Y1363454D03*
Y1360497D03*
X1212815Y1363454D03*
Y1360497D03*
X1210215D03*
X1207615D03*
X1214319Y1372853D03*
X1211889D03*
X1209459D03*
Y1367253D03*
X1214319D03*
X1211889D03*
X1214368Y1385268D03*
X1202288Y1386721D03*
X1202332Y1379914D03*
X1207601Y1380066D03*
X1215043Y1382111D03*
X1214293Y1379543D03*
X1207601Y1382574D03*
X1204612Y1376389D03*
X1202484Y1402467D03*
X1211000Y1392125D03*
X1211075Y1395200D03*
X1213355Y1412564D03*
Y1427564D03*
Y1420064D03*
X1210100Y1436500D03*
X1213000Y1435000D03*
X1214900Y1439800D03*
X1214124Y1485895D03*
X1210724D03*
X1203334Y1492995D03*
X1208114D03*
X1210034Y1483295D03*
X1214814D03*
X1208124Y1485895D03*
X1210034Y1488495D03*
X1214814D03*
X1214124Y1485895D03*
X1210724D03*
X1207424Y1495595D03*
X1204024D03*
X1203324Y1505295D03*
X1210024Y1495595D03*
X1201424D03*
X1203334Y1498195D03*
X1208114D03*
X1201414Y1502695D03*
Y1507895D03*
X1207424Y1495595D03*
X1204024D03*
X1205576Y1577997D03*
X1210300D03*
X1215025D03*
X1205576Y1581397D03*
X1210300D03*
X1215025D03*
X1200851Y1577997D03*
X1205576D03*
X1210300D03*
X1215025D03*
X1200851Y1581397D03*
X1205576D03*
X1210300D03*
X1215025D03*
X1200851Y1583797D03*
X1205576Y1583897D03*
X1210300Y1583697D03*
X1215025Y1583897D03*
X1208099Y1625380D03*
X1211499D03*
X1207321Y1622884D03*
X1212277D03*
X1208099Y1625380D03*
X1211499D03*
X1214129Y1635380D03*
X1205469D03*
X1217529D03*
X1201291Y1637876D03*
Y1632884D03*
X1206247D03*
Y1637876D03*
X1213351D03*
Y1632884D03*
X1207321Y1627876D03*
X1212277D03*
X1202069Y1635380D03*
X1214129D03*
X1205469D03*
X1214129Y1647292D03*
X1217529D03*
X1205469D03*
X1208099Y1657292D03*
X1211499D03*
X1207321Y1654796D03*
X1206247Y1649788D03*
X1201291D03*
X1212277Y1654796D03*
X1213351Y1649788D03*
X1206247Y1644796D03*
X1201291D03*
X1213351D03*
X1202069Y1647292D03*
X1214129D03*
X1205469D03*
X1207321Y1659788D03*
X1212277D03*
X1208099Y1657292D03*
X1211499D03*
X1207954Y1680419D03*
X1213072Y1682899D03*
X1202697Y1673059D03*
X1205604Y1685400D03*
Y1682200D03*
Y1679000D03*
Y1675800D03*
X1204804Y1691375D03*
X1214954Y1700343D03*
X1209879Y1700359D03*
X1214954Y1691375D03*
X1204804Y1700343D03*
X1204447Y1707143D03*
X1207770Y1706861D03*
Y1731011D03*
Y1720861D03*
X1213351Y1737117D03*
X1205638Y1732766D03*
X1216199Y49379D03*
X1230312Y88635D03*
X1220931Y131307D03*
X1215931Y141530D03*
X1218431D03*
X1222094Y258633D03*
X1230094D03*
X1226094Y297066D03*
X1230156Y292066D03*
X1222094Y286948D03*
Y297066D03*
X1230094Y314216D03*
X1226094Y305216D03*
X1222094Y314216D03*
X1219325Y438151D03*
X1216300Y475682D03*
X1228372Y688501D03*
X1221203Y1312861D03*
Y1310361D03*
Y1307861D03*
X1223703D03*
Y1310361D03*
Y1312861D03*
Y1300361D03*
Y1302861D03*
Y1305361D03*
X1221203Y1302861D03*
Y1300361D03*
Y1305361D03*
Y1315361D03*
X1223703D03*
Y1317861D03*
X1221203D03*
X1219463Y1338122D03*
X1229809Y1338105D03*
X1226629Y1352252D03*
X1229229D03*
X1226629Y1349652D03*
X1229229D03*
X1222959Y1357406D03*
X1227979Y1357352D03*
X1226629Y1354852D03*
X1229229D03*
X1220515Y1357390D03*
X1218015D03*
X1223905Y1363394D03*
Y1360437D03*
X1222919Y1372853D03*
X1220489D03*
X1223889Y1367188D03*
Y1370088D03*
X1218059Y1372853D03*
X1229949Y1373158D03*
X1225683Y1379188D03*
X1227849Y1377558D03*
X1225683Y1376288D03*
X1227749Y1374558D03*
X1229949Y1378958D03*
Y1376058D03*
X1227000Y1401300D03*
X1228355Y1412564D03*
X1220855D03*
X1227000Y1404500D03*
X1228355Y1427564D03*
Y1420064D03*
X1220855Y1427564D03*
X1229661Y1442000D03*
X1226200Y1444300D03*
X1222700Y1446300D03*
X1230134Y1492995D03*
X1216724Y1485895D03*
X1230824Y1495595D03*
X1227524Y1505295D03*
X1224124D03*
X1228224Y1495595D03*
X1230124Y1505295D03*
X1221524D03*
X1230134Y1498195D03*
X1228214Y1502695D03*
X1223434D03*
Y1507895D03*
X1228214D03*
X1227524Y1505295D03*
X1224124D03*
X1230824Y1495595D03*
X1219749Y1577997D03*
X1224474D03*
X1229198D03*
X1219749Y1581397D03*
X1224474D03*
X1229198D03*
X1219749Y1577997D03*
X1224474D03*
X1229198D03*
X1219749Y1581397D03*
X1224474D03*
X1229198D03*
X1219749Y1583897D03*
X1224474Y1583697D03*
X1229198Y1583797D03*
X1232219Y1625380D03*
X1220159D03*
X1223559D03*
X1219381Y1622884D03*
X1224337D03*
X1220159Y1625380D03*
X1223559D03*
X1226189Y1635380D03*
X1229589D03*
X1218307Y1637876D03*
Y1632884D03*
X1230367Y1637876D03*
X1225411D03*
X1230367Y1632884D03*
X1225411D03*
X1219381Y1627876D03*
X1224337D03*
X1226189Y1635380D03*
X1217529D03*
X1229589D03*
Y1647292D03*
X1226189D03*
X1220159Y1657292D03*
X1223559D03*
X1232219D03*
X1224337Y1654796D03*
X1219381D03*
X1218307Y1649788D03*
X1225411D03*
X1230367D03*
X1218307Y1644796D03*
X1225411D03*
X1230367D03*
X1226189Y1647292D03*
X1217529D03*
X1229589D03*
X1224337Y1659788D03*
X1219381D03*
X1220159Y1657292D03*
X1223559D03*
X1216875Y1705826D03*
X1219738Y1717011D03*
X1216738D03*
Y1720861D03*
X1219738Y1731011D03*
X1216738D03*
X1245840Y-28311D03*
Y-31711D03*
X1236844Y-34348D03*
X1236829Y-36863D03*
X1236798Y-31476D03*
X1236813Y-28961D03*
X1240097Y-34334D03*
X1243122Y-35654D03*
X1240082Y-36849D03*
X1245840Y-18311D03*
Y-21711D03*
X1236877Y-26227D03*
X1236932Y-19948D03*
X1236942Y-13666D03*
X1236927Y-16181D03*
X1236892Y-23712D03*
X1240130Y-26213D03*
X1240194Y-19948D03*
X1240195Y-13652D03*
X1243220Y-14972D03*
X1240180Y-16167D03*
X1240145Y-23698D03*
X1243170Y-25018D03*
X1245840Y1689D03*
Y-1711D03*
X1236932Y-9948D03*
Y52D03*
X1236942Y-3666D03*
X1236927Y-6181D03*
X1240194Y-9948D03*
Y52D03*
X1240195Y-3652D03*
X1243220Y-4972D03*
X1240180Y-6167D03*
X1245840Y11689D03*
Y8289D03*
X1236927Y13819D03*
X1236942Y16334D03*
X1236932Y10052D03*
X1236942Y6334D03*
X1236927Y3819D03*
X1240180Y13833D03*
X1243220Y15028D03*
X1240195Y16348D03*
X1240194Y10052D03*
X1240195Y6348D03*
X1243220Y5028D03*
X1240180Y3833D03*
X1236911Y21721D03*
X1236896Y19206D03*
X1236941Y26751D03*
X1236926Y24236D03*
X1243219Y25445D03*
X1240194Y26765D03*
X1240179Y24250D03*
X1238199Y49379D03*
X1235546Y75293D03*
X1238769Y75320D03*
X1232812Y88635D03*
X1239218Y132739D03*
Y123739D03*
X1233668Y132739D03*
Y128239D03*
X1238094Y258633D03*
Y280573D03*
X1233345Y300157D03*
X1234000Y385500D03*
X1242429Y431255D03*
Y427255D03*
Y447255D03*
Y435255D03*
X1236879Y449755D03*
X1242429Y439255D03*
X1232081Y460580D03*
X1236100Y773844D03*
X1233084Y772582D03*
X1235215Y777213D03*
X1231397Y769667D03*
X1243207Y779428D03*
X1241057Y782278D03*
X1244986Y787578D03*
X1244127Y784598D03*
X1238257Y779728D03*
X1243294Y1269197D03*
Y1266697D03*
Y1261697D03*
Y1264197D03*
X1243308Y1271754D03*
X1245606Y1314351D03*
Y1311244D03*
X1240899Y1315460D03*
X1238830Y1322853D03*
Y1325394D03*
X1240240Y1339578D03*
X1232409Y1338105D03*
X1240323Y1333768D03*
X1245592Y1333920D03*
Y1336428D03*
X1242603Y1330243D03*
X1244300Y1403500D03*
X1239242Y1418462D03*
X1242500Y1430075D03*
X1238731Y1422362D03*
X1237100Y1442500D03*
X1242500Y1437075D03*
X1239550Y1437050D03*
X1240924Y1485895D03*
X1237524D03*
X1243524D03*
X1234924D03*
X1241614Y1483295D03*
X1236834D03*
X1241614Y1488495D03*
X1236834D03*
X1234914Y1492995D03*
X1240924Y1485895D03*
X1237524D03*
X1234224Y1495595D03*
X1236824D03*
X1234914Y1498195D03*
X1234224Y1495595D03*
X1243372Y1577997D03*
X1233923D03*
X1238647D03*
X1243372Y1581397D03*
X1233923D03*
X1238647D03*
X1243372Y1577997D03*
X1233923D03*
X1238647D03*
X1243372Y1581397D03*
X1233923D03*
X1238647D03*
X1233923Y1583897D03*
X1238647D03*
X1243372D03*
X1244279Y1625380D03*
X1247679D03*
X1235619D03*
X1231441Y1622884D03*
X1236397D03*
X1243501D03*
X1232219Y1625380D03*
X1244279D03*
X1235619D03*
X1238249Y1635380D03*
X1241649D03*
X1237471Y1637876D03*
Y1632884D03*
X1242427Y1637876D03*
Y1632884D03*
X1236397Y1627876D03*
X1231441D03*
X1243501D03*
X1238249Y1635380D03*
X1241649D03*
X1238249Y1647292D03*
X1241649D03*
X1244279Y1657292D03*
X1235619D03*
X1247679D03*
X1231441Y1654796D03*
X1236397D03*
X1237471Y1649788D03*
X1243501Y1654796D03*
X1242427Y1649788D03*
X1237471Y1644796D03*
X1242427D03*
X1238249Y1647292D03*
X1241649D03*
X1231441Y1659788D03*
X1236397D03*
X1243501D03*
X1232219Y1657292D03*
X1244279D03*
X1235619D03*
X1235351Y1737117D03*
X1245840Y-28311D03*
Y-31711D03*
X1248286Y-34648D03*
X1245840Y-18311D03*
Y-21711D03*
X1248286Y-15374D03*
Y-25374D03*
X1245840Y1689D03*
Y-1711D03*
X1248286Y-4648D03*
X1245840Y11689D03*
Y8289D03*
X1248286Y5352D03*
Y14626D03*
X1260199Y49379D03*
X1252561Y72675D03*
X1253152Y84895D03*
X1255661Y90470D03*
X1253152Y95525D03*
X1259472Y92864D03*
X1252693Y124739D03*
X1255185Y140053D03*
Y142553D03*
X1255175Y137553D03*
X1249431Y137739D03*
X1246094Y258633D03*
X1254094D03*
X1246094Y280573D03*
X1254094Y286948D03*
X1245825Y305275D03*
X1250285Y303307D03*
X1259659Y389456D03*
X1260227Y407128D03*
Y415128D03*
X1245752Y470733D03*
X1250975Y474945D03*
X1246490Y483302D03*
X1248130Y783354D03*
X1251177Y784488D03*
X1246748Y785752D03*
X1254981Y787578D03*
X1256447Y798828D03*
X1259297Y798784D03*
X1251177Y794878D03*
X1257527Y808938D03*
X1260427Y809008D03*
X1259194Y1251697D03*
Y1246697D03*
Y1254197D03*
Y1249197D03*
X1248294Y1259197D03*
Y1256697D03*
X1245794Y1259197D03*
X1259194Y1269215D03*
Y1261715D03*
Y1264215D03*
Y1266715D03*
X1245894Y1269215D03*
X1248394D03*
X1245894Y1261715D03*
Y1264215D03*
Y1266715D03*
X1248394D03*
Y1264215D03*
Y1261715D03*
X1259194Y1256697D03*
Y1259197D03*
X1248308Y1271754D03*
X1245808D03*
X1259108D03*
X1257450Y1291721D03*
X1260050D03*
X1249650D03*
X1247050D03*
X1258506Y1311244D03*
X1256006D03*
X1253406Y1314351D03*
X1250806D03*
X1253406Y1311244D03*
X1250806D03*
X1248206Y1314351D03*
Y1311244D03*
X1252310Y1321107D03*
X1249880D03*
X1252310Y1326707D03*
X1253406Y1317308D03*
X1250806D03*
X1247450Y1326707D03*
Y1321107D03*
X1249880Y1326707D03*
X1256050D03*
X1258480D03*
X1258121Y1342686D03*
X1252359Y1339122D03*
X1253034Y1335965D03*
X1249546Y1334365D03*
X1252284Y1333397D03*
X1249600Y1403425D03*
X1252315Y1417085D03*
X1254905Y1417026D03*
X1257594Y1417000D03*
X1253100Y1413500D03*
X1256224Y1430075D03*
X1256600Y1434500D03*
X1256934Y1492995D03*
X1261024Y1495595D03*
X1254324Y1505295D03*
X1250924D03*
X1257624Y1495595D03*
X1256924Y1505295D03*
X1255024Y1495595D03*
X1248324Y1505295D03*
X1256934Y1498195D03*
X1255014Y1502695D03*
X1250234D03*
X1255014Y1507895D03*
X1250234D03*
X1254324Y1505295D03*
X1250924D03*
X1257624Y1495595D03*
X1248096Y1577997D03*
X1252820D03*
X1257544D03*
X1248096Y1581397D03*
X1252820D03*
X1257544D03*
X1262269Y1577997D03*
Y1581397D03*
X1248096Y1577997D03*
X1252820D03*
X1257544D03*
X1248096Y1581397D03*
X1252820D03*
X1257544D03*
X1248096Y1583897D03*
X1252820Y1583697D03*
X1257544Y1583897D03*
X1259739Y1625380D03*
X1256339D03*
X1248457Y1622884D03*
X1255561D03*
X1256339Y1625380D03*
X1247679D03*
X1259739D03*
X1250309Y1635380D03*
X1253709D03*
X1262369D03*
X1254487Y1637876D03*
Y1632884D03*
X1249531Y1637876D03*
Y1632884D03*
X1248457Y1627876D03*
X1255561D03*
X1250309Y1635380D03*
X1253709D03*
X1262369Y1647292D03*
X1250309D03*
X1253709D03*
X1256339Y1657292D03*
X1259739D03*
X1248457Y1654796D03*
X1254487Y1649788D03*
X1249531D03*
X1255561Y1654796D03*
X1254487Y1644796D03*
X1249531D03*
X1250309Y1647292D03*
X1253709D03*
X1248657Y1659588D03*
X1255561Y1659788D03*
X1256339Y1657292D03*
X1247679D03*
X1259739D03*
X1257351Y1737117D03*
X1263472Y92864D03*
X1266146Y121022D03*
X1263582Y164051D03*
Y160051D03*
Y180551D03*
Y176051D03*
Y172051D03*
Y168051D03*
X1267037Y175030D03*
X1263582Y185051D03*
X1268941Y206017D03*
X1269360Y219632D03*
X1261969Y219505D03*
X1262094Y258633D03*
X1270094D03*
Y286948D03*
X1262156Y292066D03*
X1268174Y395125D03*
X1270483Y433148D03*
Y435648D03*
X1265227Y454372D03*
X1262457Y798814D03*
X1266677Y802988D03*
X1266568Y809078D03*
X1275177Y808963D03*
X1263647Y809118D03*
X1271177Y808963D03*
X1261694Y1251697D03*
X1264194D03*
Y1246697D03*
X1261694D03*
Y1254197D03*
X1264194D03*
X1261694Y1249197D03*
X1264194D03*
X1261694Y1269215D03*
Y1266715D03*
Y1264215D03*
Y1261715D03*
X1264194Y1269197D03*
Y1256697D03*
Y1259197D03*
Y1261697D03*
X1261694Y1256697D03*
Y1259197D03*
X1264194Y1264197D03*
Y1266697D03*
X1264108Y1271754D03*
X1261608D03*
X1270670Y1291624D03*
X1268070D03*
X1261896Y1314291D03*
X1260950Y1311260D03*
X1267220Y1306106D03*
Y1308706D03*
Y1303506D03*
X1265970Y1311206D03*
X1264620Y1303506D03*
Y1306106D03*
Y1308706D03*
X1273869Y1315300D03*
X1261896Y1317248D03*
X1271726Y1322825D03*
Y1325366D03*
X1260910Y1326707D03*
X1262050Y1320878D03*
Y1323778D03*
X1267940Y1327012D03*
X1265740Y1328412D03*
X1273175Y1340547D03*
X1271517Y1338596D03*
X1273219Y1333740D03*
X1275499Y1330215D03*
X1267940Y1332812D03*
Y1329912D03*
X1265840Y1331412D03*
X1263674Y1330142D03*
Y1333042D03*
X1271042Y1418748D03*
X1266996Y1423617D03*
X1262310Y1428303D03*
X1267724Y1485895D03*
X1264324D03*
X1270324D03*
X1275124D03*
X1261724D03*
X1263634Y1483295D03*
X1268414D03*
X1263634Y1488495D03*
X1268414D03*
X1261714Y1492995D03*
X1267724Y1485895D03*
X1264324D03*
X1263624Y1495595D03*
X1261714Y1498195D03*
X1261024Y1495595D03*
X1275195Y1552250D03*
X1266993Y1577997D03*
Y1581397D03*
X1262269Y1577997D03*
X1266993D03*
X1262269Y1581397D03*
X1266993D03*
X1275170Y1579519D03*
X1262269Y1583897D03*
X1266993Y1583797D03*
X1269310Y1583170D03*
X1268399Y1625380D03*
X1271799D03*
X1267621Y1622884D03*
X1260517D03*
X1272577D03*
X1268399Y1625380D03*
X1271799D03*
X1274429Y1635380D03*
X1265769D03*
X1261591Y1637876D03*
X1266547D03*
X1261591Y1632884D03*
X1266547D03*
X1273651Y1637876D03*
Y1632790D03*
X1267621Y1627876D03*
X1260517D03*
X1272577D03*
X1262369Y1635380D03*
X1274429D03*
X1265769D03*
X1274429Y1647292D03*
X1265769D03*
X1268399Y1657292D03*
X1271799D03*
X1260517Y1654796D03*
X1267621D03*
X1266547Y1649788D03*
X1261591D03*
X1272577Y1654796D03*
X1273651Y1649788D03*
X1266547Y1644796D03*
X1261591D03*
X1273651D03*
X1262369Y1647292D03*
X1274429D03*
X1265769D03*
X1260517Y1659788D03*
X1267621D03*
X1272577D03*
X1268399Y1657292D03*
X1271799D03*
X1282199Y49379D03*
X1278111Y150030D03*
X1285391Y142553D03*
X1278050Y152912D03*
X1278137Y166051D03*
X1278211Y161030D03*
Y156030D03*
X1278137Y180565D03*
Y176051D03*
X1277732Y236594D03*
Y246594D03*
Y241594D03*
Y251594D03*
X1286094Y258633D03*
X1278094D03*
X1286094Y286948D03*
X1278156Y292066D03*
X1278094Y287948D03*
X1277598Y404428D03*
X1290127Y401125D03*
X1282165Y408987D03*
X1288202Y405741D03*
X1290127Y410635D03*
X1289352Y418550D03*
X1278677Y808988D03*
X1281190Y1254112D03*
X1276190D03*
X1278690D03*
X1281190Y1249112D03*
Y1251612D03*
X1276190D03*
X1278690D03*
X1276190Y1249112D03*
X1278690D03*
X1281190Y1246612D03*
X1276190D03*
X1278690D03*
X1276190Y1269112D03*
Y1266612D03*
X1281190Y1259112D03*
Y1256612D03*
X1276190D03*
Y1259112D03*
Y1261612D03*
Y1264112D03*
X1278690Y1256612D03*
Y1259112D03*
X1278790Y1269130D03*
X1281290D03*
X1278790Y1261630D03*
Y1264130D03*
Y1266630D03*
X1281290D03*
Y1264130D03*
Y1261630D03*
X1281204Y1271669D03*
X1278704D03*
X1276204D03*
X1288902Y1311216D03*
X1286302Y1314323D03*
X1283702D03*
X1286302Y1311216D03*
X1283702D03*
X1278502Y1314323D03*
X1281102D03*
Y1311216D03*
X1278502D03*
X1285206Y1326679D03*
X1286302Y1317280D03*
X1283702D03*
X1285206Y1321079D03*
X1282776D03*
Y1326679D03*
X1280346Y1321079D03*
Y1326679D03*
X1288946D03*
X1285255Y1339094D03*
X1278488Y1333892D03*
X1285930Y1335937D03*
X1282442Y1334337D03*
X1285180Y1333369D03*
X1278488Y1336400D03*
X1287600Y1423100D03*
Y1427600D03*
X1276500Y1432000D03*
X1277724Y1485895D03*
X1281124D03*
X1283724D03*
X1277034Y1483295D03*
X1281814D03*
X1277034Y1488495D03*
X1281814D03*
X1277724Y1485895D03*
X1281124D03*
X1288494Y1517082D03*
Y1513682D03*
Y1511082D03*
Y1519682D03*
X1285894Y1512992D03*
Y1517772D03*
X1288494Y1517082D03*
Y1513682D03*
Y1530482D03*
Y1527082D03*
Y1533082D03*
Y1524482D03*
X1285894Y1531172D03*
Y1526392D03*
X1288494Y1530482D03*
Y1527082D03*
X1283958Y1542654D03*
X1287961Y1542469D03*
X1287372Y1552845D03*
X1287647Y1545220D03*
Y1549120D03*
X1277017Y1544953D03*
Y1547453D03*
Y1549953D03*
X1281470Y1552845D03*
X1281347Y1549120D03*
Y1545220D03*
X1284497Y1549120D03*
Y1545220D03*
X1284510Y1556953D03*
X1278593Y1564073D03*
X1281093D03*
X1283593D03*
X1284510Y1554436D03*
X1277702D03*
X1278012Y1581563D03*
X1287945Y1569763D03*
X1285445D03*
X1289919Y1582295D03*
Y1574795D03*
Y1579795D03*
Y1577295D03*
X1287419Y1582295D03*
Y1579795D03*
X1284919D03*
Y1582295D03*
X1282419D03*
Y1579795D03*
X1280459Y1625380D03*
X1283859D03*
X1279681Y1622884D03*
X1284637D03*
X1280459Y1625380D03*
X1283859D03*
X1286489Y1635380D03*
X1277829D03*
X1289889D03*
X1278607Y1637876D03*
Y1632790D03*
X1285711Y1637876D03*
Y1632884D03*
X1279681Y1627876D03*
X1284637D03*
X1286489Y1635380D03*
X1277829D03*
X1289889D03*
Y1647292D03*
X1286489D03*
X1277829D03*
X1280459Y1657292D03*
X1283859D03*
X1279681Y1654796D03*
X1278607Y1649788D03*
X1284637Y1654796D03*
X1285711Y1649788D03*
X1278607Y1644796D03*
X1285711D03*
X1286489Y1647292D03*
X1277829D03*
X1289889D03*
X1279681Y1659788D03*
X1284637D03*
X1280459Y1657292D03*
X1283859D03*
X1279351Y1737117D03*
X1304199Y49379D03*
X1296200Y66911D03*
X1304705Y79807D03*
X1300668Y133739D03*
Y129739D03*
X1305091Y123680D03*
Y127830D03*
Y131750D03*
X1292082Y166051D03*
Y162051D03*
X1301582Y166051D03*
X1301743Y162055D03*
X1292082Y171551D03*
X1301582D03*
X1292082Y184051D03*
X1301582D03*
X1302094Y258633D03*
X1294094D03*
X1302094Y298066D03*
Y286948D03*
X1294156Y292066D03*
X1302069Y303184D03*
X1299026Y389355D03*
X1302226D03*
X1295519Y389561D03*
X1304347Y523237D03*
X1299076Y530023D03*
X1303266Y533713D03*
Y530413D03*
X1302160Y524916D03*
X1304566Y525743D03*
X1301642Y537299D03*
X1295532Y539513D03*
X1293581Y542716D03*
X1301666Y555413D03*
X1294938Y561331D03*
X1297487Y590607D03*
X1300200Y590600D03*
X1300400Y599413D03*
X1297400D03*
X1298000Y657500D03*
X1303250Y655149D03*
X1295000Y655200D03*
X1292297Y657206D03*
X1305100Y662100D03*
X1301900Y660699D03*
X1294590Y1254112D03*
X1297090D03*
X1292090D03*
Y1249112D03*
X1294590D03*
X1297090D03*
X1292090Y1251612D03*
X1294590D03*
X1297090D03*
X1292090Y1246612D03*
X1297090D03*
X1294590D03*
X1292090Y1269130D03*
X1294590D03*
X1292090Y1261630D03*
Y1264130D03*
Y1266630D03*
X1294590D03*
Y1264130D03*
Y1261630D03*
X1297090Y1269112D03*
Y1256612D03*
Y1259112D03*
Y1261612D03*
X1294590Y1256612D03*
Y1259112D03*
X1297090Y1264112D03*
Y1266612D03*
X1292090Y1256612D03*
Y1259112D03*
X1297004Y1271669D03*
X1292004D03*
X1294504D03*
X1302890Y1291759D03*
X1298350Y1291721D03*
X1295750D03*
X1300116Y1306078D03*
Y1303478D03*
Y1308678D03*
X1298866Y1311178D03*
X1294792Y1314263D03*
X1297516Y1306078D03*
Y1303478D03*
Y1308678D03*
X1291402Y1311216D03*
X1293846Y1311232D03*
X1294792Y1317220D03*
X1304630Y1322768D03*
Y1325309D03*
X1293806Y1326679D03*
X1291376D03*
X1294956Y1320934D03*
Y1323834D03*
X1300836Y1326984D03*
X1298636Y1328384D03*
X1304421Y1338539D03*
X1296570Y1330114D03*
Y1333014D03*
X1298736Y1331384D03*
X1300836Y1329884D03*
Y1332784D03*
X1302365Y1418702D03*
X1292522Y1421596D03*
X1303943Y1430729D03*
X1291700Y1431700D03*
X1304596Y1492995D03*
X1305286Y1495595D03*
X1302686D03*
X1304596Y1498195D03*
X1305286Y1495595D03*
X1299048Y1516590D03*
Y1513190D03*
Y1519190D03*
Y1510590D03*
X1296448Y1517280D03*
Y1512500D03*
X1301648Y1517280D03*
Y1512500D03*
X1291094Y1512992D03*
Y1517772D03*
X1299048Y1516590D03*
Y1513190D03*
Y1534990D03*
Y1538390D03*
Y1532490D03*
X1296448Y1534300D03*
X1301648D03*
X1291094Y1531172D03*
Y1526392D03*
X1299048Y1534990D03*
X1297490Y1526910D03*
X1297620Y1529534D03*
X1296448Y1539080D03*
X1301648D03*
X1299048Y1540990D03*
Y1538390D03*
X1291897Y1545076D03*
X1290461Y1542469D03*
X1291897Y1547576D03*
X1299466Y1562402D03*
Y1564902D03*
X1291819Y1563595D03*
X1294319D03*
X1292673Y1559750D03*
X1300560Y1554261D03*
X1302915Y1563596D03*
X1298466Y1556331D03*
Y1559731D03*
X1299492Y1572106D03*
Y1569606D03*
X1292419Y1582295D03*
Y1579795D03*
Y1574795D03*
Y1577295D03*
X1294919D03*
Y1574795D03*
X1294387Y1571682D03*
X1291887D03*
X1301789Y1574795D03*
X1304289D03*
X1301789Y1577295D03*
X1304289D03*
Y1579795D03*
X1301789D03*
X1304289Y1582295D03*
X1301789D03*
X1299289Y1574795D03*
Y1582295D03*
Y1579795D03*
Y1577295D03*
X1295877Y1581199D03*
X1298382Y1584844D03*
X1295877Y1584099D03*
X1293459Y1584844D03*
X1304579Y1625380D03*
X1292519D03*
X1295919D03*
X1291741Y1622884D03*
X1296697D03*
X1303801D03*
X1292519Y1625380D03*
X1304579D03*
X1295919D03*
X1298549Y1635380D03*
X1301949D03*
X1290667Y1637876D03*
Y1632884D03*
X1297771Y1637876D03*
Y1632884D03*
X1302727Y1637876D03*
Y1632884D03*
X1296697Y1627876D03*
X1291741D03*
X1303801D03*
X1298549Y1635380D03*
X1301949D03*
X1298549Y1647292D03*
X1301949D03*
X1292519Y1657292D03*
X1304579D03*
X1295919D03*
X1291741Y1654796D03*
X1296697D03*
X1297771Y1649788D03*
X1290667D03*
X1303801Y1654796D03*
X1302727Y1649788D03*
X1297771Y1644796D03*
X1290667D03*
X1302727D03*
X1298549Y1647292D03*
X1301949D03*
X1291741Y1659788D03*
X1296697D03*
X1303801D03*
X1292519Y1657292D03*
X1304579D03*
X1295919D03*
X1301351Y1737117D03*
X1309185Y74748D03*
X1320020Y66979D03*
X1308110Y66911D03*
X1306449Y92185D03*
X1307857Y103353D03*
X1313951Y104739D03*
X1311045D03*
X1307857Y111353D03*
X1313011Y135820D03*
Y139845D03*
X1306431Y152830D03*
X1306300Y203917D03*
X1318094Y258633D03*
X1310094D03*
X1310156Y292066D03*
X1305426Y389355D03*
X1308926Y524111D03*
X1306815Y522726D03*
X1307117Y525897D03*
X1307766Y563013D03*
X1308700Y590300D03*
X1317266Y589522D03*
Y592522D03*
X1308700Y587800D03*
X1317266Y597213D03*
X1310544Y613100D03*
X1313544Y610100D03*
X1310544D03*
X1313544Y607100D03*
X1310544D03*
X1313544Y604100D03*
X1310544D03*
X1307544Y610100D03*
Y613100D03*
Y604100D03*
Y607100D03*
X1317266Y600213D03*
X1309166Y601713D03*
X1308776Y599181D03*
X1313544Y613100D03*
X1310544Y616100D03*
X1313544D03*
X1307544D03*
X1308800Y619200D03*
Y622200D03*
Y625200D03*
X1318300D03*
Y622200D03*
Y619200D03*
Y640000D03*
Y643000D03*
Y649000D03*
Y646000D03*
X1307700Y664600D03*
X1309600Y667700D03*
X1315657Y1196132D03*
D03*
Y1199532D03*
D03*
X1313109Y1195398D03*
Y1200898D03*
X1315657Y1199532D03*
Y1196132D03*
X1311715Y1221042D03*
X1318776Y1219566D03*
X1311594Y1251612D03*
X1309094D03*
X1311594Y1254112D03*
X1309094D03*
X1311594Y1246612D03*
X1309094D03*
X1311594Y1249112D03*
X1309094D03*
X1314094Y1246612D03*
Y1251612D03*
Y1249112D03*
Y1254112D03*
X1309090Y1269169D03*
Y1266669D03*
Y1261669D03*
Y1264169D03*
X1314194Y1269130D03*
Y1266630D03*
Y1264130D03*
Y1261630D03*
X1311694Y1269130D03*
Y1261630D03*
Y1264130D03*
Y1266630D03*
X1311594Y1259112D03*
Y1256612D03*
X1309094Y1259112D03*
Y1256612D03*
X1314094D03*
Y1259112D03*
X1309090Y1271669D03*
X1311590D03*
X1314090D03*
X1305600Y1291759D03*
X1316606Y1314266D03*
Y1311159D03*
X1314006Y1314266D03*
Y1311159D03*
X1319206Y1314266D03*
Y1311159D03*
X1311406Y1314266D03*
Y1311159D03*
X1306799Y1315440D03*
X1315680Y1326622D03*
X1318110D03*
X1316606Y1317223D03*
X1319206D03*
X1318110Y1321022D03*
X1315680D03*
X1313250D03*
Y1326622D03*
X1318159Y1339037D03*
X1306079Y1340490D03*
X1306123Y1333683D03*
X1311392Y1333835D03*
X1318834Y1335880D03*
X1315346Y1334280D03*
X1318084Y1333312D03*
X1311392Y1336343D03*
X1308403Y1330158D03*
X1318363Y1411404D03*
X1314580Y1425240D03*
X1310580D03*
X1318580D03*
X1315386Y1485895D03*
X1311986D03*
X1317986D03*
X1309386D03*
X1311296Y1483295D03*
X1316076D03*
X1311296Y1488495D03*
X1316076D03*
X1309376Y1492995D03*
X1315386Y1485895D03*
X1311986D03*
X1308686Y1495595D03*
X1311286D03*
X1309376Y1498195D03*
X1308686Y1495595D03*
X1308290Y1533380D03*
X1309423Y1543800D03*
Y1547420D03*
Y1551040D03*
X1309915Y1561731D03*
X1306789Y1574795D03*
Y1582295D03*
Y1579795D03*
Y1577295D03*
X1310914Y1577299D03*
X1320039Y1625380D03*
X1316639D03*
X1307979D03*
X1308757Y1622884D03*
X1315861D03*
X1316639Y1625380D03*
X1320039D03*
X1307979D03*
X1310609Y1635380D03*
X1314009D03*
X1309831Y1637876D03*
Y1632884D03*
X1314787Y1637876D03*
Y1632884D03*
X1308757Y1627876D03*
X1315861D03*
X1310609Y1635380D03*
X1314009D03*
X1310609Y1647292D03*
X1314009D03*
X1316639Y1657292D03*
X1320039D03*
X1307979D03*
X1308757Y1654796D03*
X1309831Y1649788D03*
X1315861Y1654796D03*
X1314787Y1649788D03*
X1309831Y1644796D03*
X1314787D03*
X1310609Y1647292D03*
X1314009D03*
X1308757Y1659788D03*
X1315861D03*
X1316639Y1657292D03*
X1320039D03*
X1307979D03*
X1326199Y49379D03*
X1331930Y66945D03*
X1333399Y98084D03*
X1334094Y258633D03*
X1326094D03*
X1334156Y292066D03*
X1326094Y286948D03*
X1328427Y349452D03*
X1330758Y521749D03*
Y528649D03*
X1330773Y531776D03*
X1330758Y535449D03*
X1329673Y552509D03*
X1332673D03*
X1326673Y544909D03*
X1329673Y545909D03*
Y549309D03*
X1330658Y542949D03*
X1332673Y545909D03*
Y549309D03*
X1329673Y558709D03*
Y555709D03*
X1332673D03*
X1325366Y589522D03*
Y592522D03*
Y597213D03*
Y600213D03*
X1321300Y619200D03*
Y622200D03*
Y625200D03*
X1333878Y637721D03*
X1321300Y643000D03*
Y640000D03*
Y649000D03*
Y646000D03*
X1326636Y656800D03*
X1322420Y656867D03*
X1332812Y856383D03*
X1330277Y857388D03*
X1325543Y871161D03*
X1329244D03*
X1334301Y867765D03*
X1328992Y1209788D03*
X1327029Y1206788D03*
X1331202Y1206478D03*
X1323169Y1208995D03*
X1329477Y1222158D03*
X1331202Y1211488D03*
X1326433Y1214334D03*
X1333977Y1222158D03*
X1325137Y1210653D03*
X1324901Y1216419D03*
X1322141Y1217365D03*
X1327494Y1246612D03*
Y1251612D03*
Y1249112D03*
Y1254112D03*
X1324994Y1246612D03*
Y1251612D03*
Y1249112D03*
Y1254112D03*
X1329994Y1246612D03*
Y1251612D03*
Y1249112D03*
Y1254112D03*
X1324994Y1269130D03*
Y1261630D03*
Y1264130D03*
Y1266630D03*
X1327494Y1269130D03*
Y1266630D03*
Y1264130D03*
Y1261630D03*
Y1259112D03*
Y1256612D03*
X1324994Y1259112D03*
Y1256612D03*
X1329994Y1259112D03*
Y1256612D03*
Y1266612D03*
Y1264112D03*
Y1261612D03*
Y1269112D03*
X1327490Y1271669D03*
X1324990D03*
X1329990D03*
X1332680Y1291861D03*
X1330080D03*
X1333020Y1308621D03*
X1331770Y1311121D03*
X1333020Y1306021D03*
Y1303421D03*
X1330420Y1306021D03*
Y1303421D03*
Y1308621D03*
X1327696Y1314206D03*
X1321806Y1311159D03*
X1324306D03*
X1326750Y1311175D03*
X1327696Y1317163D03*
X1326710Y1326622D03*
X1324280D03*
X1321850D03*
X1327876Y1320934D03*
Y1323834D03*
X1333740Y1326927D03*
X1331540Y1328327D03*
X1333740Y1329827D03*
Y1332727D03*
X1331640Y1331327D03*
X1329474Y1330057D03*
Y1332957D03*
X1322539Y1411278D03*
X1322499Y1413788D03*
X1325499D03*
X1325539Y1411278D03*
Y1416446D03*
X1322539D03*
X1328539Y1411278D03*
X1328499Y1413788D03*
X1328539Y1416446D03*
X1331509Y1416486D03*
X1334509D03*
X1331509Y1408818D03*
X1334509Y1411318D03*
X1334469Y1413828D03*
X1334509Y1408818D03*
X1331469Y1413828D03*
X1331509Y1411318D03*
X1334580Y1425240D03*
X1330580D03*
X1326580D03*
X1322580D03*
X1325579Y1418976D03*
X1322579D03*
X1325609Y1421496D03*
X1322609D03*
X1328579Y1418976D03*
X1328609Y1421496D03*
X1331579Y1421536D03*
X1331549Y1419016D03*
X1334579Y1421536D03*
X1334549Y1419016D03*
X1331396Y1492995D03*
X1335486Y1495595D03*
X1328786Y1505295D03*
X1325386D03*
X1332086Y1495595D03*
X1331386Y1505295D03*
X1322786D03*
X1329486Y1495595D03*
X1331396Y1498195D03*
X1324696Y1502695D03*
X1329476D03*
X1324696Y1507895D03*
X1329476D03*
X1328786Y1505295D03*
X1325386D03*
X1332086Y1495595D03*
X1324189Y1577997D03*
X1328913D03*
X1333638D03*
X1324189Y1581397D03*
X1328913D03*
X1333638D03*
X1324189Y1577997D03*
X1328913D03*
X1333638D03*
X1324189Y1581397D03*
X1328913D03*
X1333638D03*
X1328913Y1583797D03*
X1333638Y1583897D03*
X1324189Y1583797D03*
X1328699Y1625380D03*
X1332099D03*
X1327921Y1622884D03*
X1320817D03*
X1332877D03*
X1328699Y1625380D03*
X1332099D03*
X1322669Y1635380D03*
X1334729D03*
X1326069D03*
X1321891Y1637876D03*
X1326847D03*
X1321891Y1632884D03*
X1326847D03*
X1333951Y1637876D03*
Y1632884D03*
X1327921Y1627876D03*
X1320817D03*
X1332877D03*
X1322669Y1635380D03*
X1334729D03*
X1326069D03*
X1334729Y1647292D03*
X1322669D03*
X1326069D03*
X1328699Y1657292D03*
X1332099D03*
X1320817Y1654796D03*
X1327921D03*
X1326847Y1649788D03*
X1321891D03*
X1332877Y1654796D03*
X1333951Y1649788D03*
X1326847Y1644796D03*
X1321891D03*
X1333951D03*
X1322669Y1647292D03*
X1334729D03*
X1326069D03*
X1320817Y1659788D03*
X1327921D03*
X1332877D03*
X1328699Y1657292D03*
X1332099D03*
X1323351Y1737117D03*
X1348199Y49379D03*
X1343840Y66911D03*
X1341399Y98084D03*
X1348199D03*
X1335260Y236594D03*
Y246594D03*
Y241594D03*
Y251594D03*
X1342094Y258633D03*
Y286948D03*
X1336558Y637721D03*
X1339238D03*
X1344438D03*
X1341838D03*
X1340257Y677765D03*
Y675111D03*
X1336812Y856383D03*
X1339347Y857388D03*
X1341301Y867765D03*
X1337801D03*
X1341301Y871265D03*
X1344801D03*
X1348301D03*
X1337975Y1177999D03*
X1340948Y1177681D03*
X1338142Y1181642D03*
X1342507Y1187848D03*
X1340948Y1181681D03*
X1342036Y1206429D03*
D03*
Y1203029D03*
D03*
X1339488Y1202295D03*
X1340483Y1209006D03*
X1349012Y1204971D03*
X1342036Y1206429D03*
Y1203029D03*
X1346063Y1217729D03*
D03*
Y1214329D03*
D03*
X1336861Y1222119D03*
X1348611Y1212963D03*
Y1218463D03*
X1346063Y1217729D03*
Y1214329D03*
X1341590Y1254169D03*
Y1251669D03*
Y1249169D03*
Y1246669D03*
X1344090Y1254169D03*
Y1251669D03*
Y1249169D03*
Y1246669D03*
X1346590Y1254169D03*
Y1249169D03*
Y1251669D03*
Y1246669D03*
X1341690Y1269269D03*
Y1264269D03*
Y1266769D03*
Y1261769D03*
X1341590Y1256669D03*
Y1259169D03*
X1344190Y1269187D03*
X1346690D03*
X1344190Y1261687D03*
Y1264187D03*
Y1266687D03*
X1346690D03*
Y1264187D03*
Y1261687D03*
X1344090Y1256669D03*
Y1259169D03*
X1346590D03*
Y1256669D03*
X1341690Y1271769D03*
X1346690D03*
X1344190D03*
X1338440Y1291949D03*
X1335670Y1291899D03*
X1346806Y1311359D03*
X1349406D03*
X1346806Y1314466D03*
X1349406D03*
X1344206Y1311359D03*
Y1314466D03*
X1339429Y1315570D03*
X1348480Y1326822D03*
X1349406Y1317423D03*
X1346050Y1321222D03*
Y1326822D03*
X1348480Y1321222D03*
X1337430Y1322968D03*
Y1325509D03*
X1338879Y1340690D03*
X1337221Y1338739D03*
X1338923Y1333883D03*
X1344192Y1334035D03*
X1348146Y1334480D03*
X1344192Y1336543D03*
X1341203Y1330358D03*
X1340556Y1383674D03*
Y1386674D03*
X1337556D03*
Y1383674D03*
X1346556Y1386674D03*
Y1383674D03*
X1343556Y1386674D03*
Y1383674D03*
X1349556D03*
Y1386674D03*
X1337555Y1389658D03*
X1343712Y1389804D03*
X1348712D03*
X1346212D03*
X1341212D03*
X1348823Y1409626D03*
X1348853Y1413866D03*
X1346323Y1409626D03*
X1346353Y1413866D03*
X1343823Y1409626D03*
X1343853Y1413866D03*
X1346509Y1416486D03*
X1349509D03*
X1343509D03*
X1341323Y1409626D03*
X1341353Y1413866D03*
X1337509Y1416486D03*
Y1411318D03*
X1337469Y1413828D03*
X1337509Y1408818D03*
X1340509Y1416486D03*
X1346580Y1425240D03*
X1342580D03*
X1338580D03*
X1349579Y1421536D03*
X1349549Y1419016D03*
X1346579Y1421536D03*
X1346549Y1419016D03*
X1343549D03*
X1343579Y1421536D03*
X1337579D03*
X1337549Y1419016D03*
X1340579Y1421536D03*
X1340549Y1419016D03*
X1342186Y1485895D03*
X1338786D03*
X1336176Y1492995D03*
X1338096Y1483295D03*
X1342876D03*
X1336186Y1485895D03*
X1344786D03*
X1338096Y1488495D03*
X1342876D03*
X1342186Y1485895D03*
X1338786D03*
X1349586Y1505295D03*
X1338086Y1495595D03*
X1336176Y1498195D03*
X1335486Y1495595D03*
X1338362Y1577997D03*
X1343087D03*
X1347811D03*
X1338362Y1581397D03*
X1343087D03*
X1347811D03*
X1338362Y1577997D03*
X1343087D03*
X1347811D03*
X1338362Y1581397D03*
X1343087D03*
X1347811D03*
X1343087Y1583897D03*
X1347811D03*
X1338362Y1583697D03*
X1340759Y1625380D03*
X1344159D03*
X1339981Y1622884D03*
X1344937D03*
X1340759Y1625380D03*
X1344159D03*
X1346789Y1635380D03*
X1338129D03*
X1350189D03*
X1338907Y1637876D03*
Y1632884D03*
X1346011Y1637876D03*
Y1632884D03*
X1339981Y1627876D03*
X1344937D03*
X1346789Y1635380D03*
X1338129D03*
X1350189Y1647292D03*
X1346789D03*
X1338129D03*
X1340759Y1657292D03*
X1344159D03*
X1339981Y1654796D03*
X1338907Y1649788D03*
X1344937Y1654796D03*
X1346011Y1649788D03*
X1338907Y1644796D03*
X1346011D03*
X1346789Y1647292D03*
X1338129D03*
X1339981Y1659788D03*
X1344937D03*
X1340759Y1657292D03*
X1344159D03*
X1345351Y1737117D03*
X1355750Y66886D03*
X1360109Y98050D03*
X1352199D03*
X1360629Y120380D03*
X1358094Y258633D03*
X1350094D03*
X1350156Y292066D03*
X1358094Y286948D03*
X1363857Y626579D03*
X1361427D03*
X1354397Y623374D03*
Y626274D03*
X1356597Y624874D03*
X1358663Y623144D03*
X1356497Y621874D03*
X1354397Y620474D03*
X1358663Y620244D03*
X1363831Y642042D03*
X1361387Y642026D03*
X1356367Y642080D03*
X1352527Y638278D03*
X1360944Y638999D03*
Y636042D03*
X1360964Y629514D03*
Y632414D03*
X1357717Y647180D03*
Y649780D03*
X1355117D03*
Y647180D03*
X1357717Y644580D03*
X1355117D03*
X1364317Y661368D03*
X1357057Y661328D03*
X1354257Y675765D03*
X1358461Y684151D03*
Y686651D03*
X1360961Y684073D03*
Y686573D03*
X1363461D03*
Y684073D03*
X1363435Y681573D03*
X1358435D03*
X1360935D03*
X1358461Y694151D03*
X1363461D03*
X1360961D03*
X1358461Y689151D03*
Y691651D03*
X1363461Y696651D03*
X1360961D03*
X1363461Y699151D03*
X1360961Y691573D03*
X1363461D03*
X1360961Y689073D03*
X1363461D03*
X1362523Y1015473D03*
Y1022559D03*
Y1019016D03*
X1355222Y1200561D03*
X1364239Y1207949D03*
X1350809Y1202323D03*
X1361285Y1206718D03*
X1355641Y1210674D03*
X1362810Y1211071D03*
X1357490Y1254169D03*
Y1249169D03*
Y1251669D03*
Y1246669D03*
X1359990Y1254169D03*
X1362490D03*
X1359990Y1249169D03*
X1362490D03*
X1359990Y1251669D03*
X1362490D03*
Y1246669D03*
X1359990D03*
Y1269187D03*
Y1266687D03*
Y1264187D03*
Y1261687D03*
X1357490Y1269187D03*
Y1261687D03*
Y1264187D03*
Y1266687D03*
Y1256669D03*
Y1259169D03*
X1362490Y1269269D03*
Y1261769D03*
Y1266769D03*
Y1264269D03*
Y1256669D03*
Y1259169D03*
X1359990Y1256669D03*
Y1259169D03*
X1357490Y1271769D03*
X1362490D03*
X1359990D03*
X1364490Y1293694D03*
X1361830Y1291809D03*
X1360496Y1314406D03*
X1363220Y1308821D03*
X1364570Y1311321D03*
X1363220Y1306221D03*
Y1303621D03*
X1359550Y1311375D03*
X1352006Y1311359D03*
X1357106D03*
X1354606D03*
X1352006Y1314466D03*
X1360496Y1317363D03*
X1350910Y1326822D03*
X1352006Y1317423D03*
X1350910Y1321222D03*
X1359510Y1326822D03*
X1360724Y1321184D03*
Y1324084D03*
X1357080Y1326822D03*
X1354650D03*
X1364340Y1328527D03*
X1350959Y1339237D03*
X1351634Y1336080D03*
X1350884Y1333512D03*
X1364440Y1337527D03*
Y1331527D03*
Y1334527D03*
X1362274Y1330257D03*
Y1333157D03*
Y1336057D03*
X1352226Y1386804D03*
Y1383804D03*
X1352225Y1389788D03*
X1358509Y1416486D03*
Y1413818D03*
Y1411318D03*
Y1408818D03*
X1352509Y1416486D03*
Y1411318D03*
Y1413818D03*
Y1408818D03*
X1355509Y1416486D03*
Y1411318D03*
Y1413818D03*
Y1408818D03*
X1362580Y1425240D03*
X1358580D03*
X1354580D03*
X1350580D03*
X1352579Y1421536D03*
X1352549Y1419016D03*
X1355549D03*
X1365586Y1485895D03*
X1362986D03*
X1364896Y1483295D03*
Y1488495D03*
X1358196Y1492995D03*
X1362976D03*
X1362286Y1495595D03*
X1355586Y1505295D03*
X1352186D03*
X1358886Y1495595D03*
X1364886D03*
X1356286D03*
X1358186Y1505295D03*
X1358196Y1498195D03*
X1362976D03*
X1356276Y1502695D03*
X1351496D03*
X1356276Y1507895D03*
X1351496D03*
X1355586Y1505295D03*
X1362286Y1495595D03*
X1352186Y1505295D03*
X1358886Y1495595D03*
X1352536Y1577997D03*
X1357260D03*
X1361985D03*
X1352536Y1581397D03*
X1357260D03*
X1361985D03*
X1366709Y1577997D03*
Y1581397D03*
X1352536Y1577997D03*
X1357260D03*
X1361985D03*
X1352536Y1581397D03*
X1357260D03*
X1361985D03*
X1357260Y1583797D03*
X1361985Y1583897D03*
X1352536Y1583697D03*
X1364879Y1625380D03*
X1352819D03*
X1356219D03*
X1352041Y1622884D03*
X1356997D03*
X1364101D03*
X1352819Y1625380D03*
X1356219D03*
X1358849Y1635380D03*
X1362249D03*
X1350967Y1637876D03*
Y1632884D03*
X1358071Y1637876D03*
Y1632884D03*
X1363027Y1637876D03*
Y1632884D03*
X1356997Y1627876D03*
X1352041D03*
X1364101D03*
X1358849Y1635380D03*
X1350189D03*
X1362249D03*
Y1647292D03*
X1358849D03*
X1352819Y1657292D03*
X1356219D03*
X1364879D03*
X1352041Y1654796D03*
X1356997D03*
X1358071Y1649788D03*
X1350967D03*
X1364101Y1654796D03*
X1363027Y1649788D03*
X1358071Y1644796D03*
X1350967D03*
X1363027D03*
X1358849Y1647292D03*
X1350189D03*
X1362249D03*
X1352041Y1659788D03*
X1356997D03*
X1364101D03*
X1352819Y1657292D03*
X1356219D03*
X1370199Y49379D03*
X1367950Y66886D03*
X1368109Y98000D03*
X1366094Y258633D03*
X1366156Y292066D03*
X1377862Y485552D03*
X1373862D03*
X1377862Y511052D03*
X1374887Y626579D03*
X1372457D03*
X1370027D03*
X1369978Y614164D03*
X1376757Y619497D03*
X1369303Y617321D03*
X1372791Y618921D03*
X1370053Y619889D03*
X1376745Y616858D03*
X1379734Y623043D03*
X1366287Y626579D03*
X1366331Y642042D03*
X1376731Y638935D03*
Y642042D03*
X1371531Y638935D03*
Y642042D03*
Y635978D03*
X1374887Y632179D03*
X1374131Y638935D03*
Y642042D03*
X1368931Y638935D03*
Y642042D03*
Y635978D03*
X1370027Y632179D03*
X1372457D03*
X1371847Y661328D03*
X1376761Y686573D03*
Y684073D03*
X1374261D03*
Y686573D03*
X1374245Y681573D03*
X1376745D03*
X1376761Y694151D03*
X1374261D03*
X1376761Y696651D03*
X1374261D03*
X1376761Y699151D03*
X1374261D03*
X1376761Y701651D03*
X1374261D03*
X1376761Y691573D03*
Y689073D03*
X1374261Y691573D03*
Y689073D03*
X1376761Y706651D03*
Y704151D03*
X1374261Y706651D03*
Y704151D03*
X1366123Y1015473D03*
X1373603D03*
X1377483D03*
X1370003D03*
X1373603Y1019016D03*
Y1022559D03*
X1366123D03*
Y1019016D03*
X1377483Y1022559D03*
Y1019016D03*
X1370003Y1022559D03*
Y1019016D03*
X1370685Y1223032D03*
D03*
Y1226432D03*
D03*
X1368137Y1222298D03*
X1370685Y1223032D03*
X1368137Y1227798D03*
X1370685Y1226432D03*
X1374476Y1266143D03*
X1376976D03*
X1379476D03*
X1374476Y1268643D03*
X1376976D03*
X1379476D03*
X1374476Y1273643D03*
Y1271143D03*
X1374576Y1283743D03*
Y1281243D03*
X1374476Y1276143D03*
Y1278643D03*
X1376976Y1273643D03*
Y1271143D03*
X1379476Y1273643D03*
Y1271143D03*
X1377076Y1281161D03*
Y1283661D03*
X1379576D03*
Y1281161D03*
X1376976Y1276143D03*
Y1278643D03*
X1379476D03*
Y1276143D03*
X1379576Y1288661D03*
X1377076Y1286161D03*
X1379576D03*
X1377076Y1288661D03*
X1379576Y1291243D03*
X1377076D03*
X1374576Y1288743D03*
Y1286243D03*
Y1291243D03*
X1368305Y1307340D03*
X1365820Y1308821D03*
X1368305Y1309840D03*
X1365820Y1306221D03*
Y1303621D03*
X1372149Y1334890D03*
X1379388Y1330690D03*
Y1333797D03*
X1378632Y1340553D03*
X1376788Y1330690D03*
Y1333797D03*
X1370012Y1342299D03*
X1378632Y1346153D03*
X1371422Y1359024D03*
X1368922D03*
X1371505Y1353214D03*
X1376774Y1353366D03*
X1370012Y1344840D03*
X1376774Y1355874D03*
X1373785Y1349689D03*
X1379101Y1418621D03*
X1368299Y1425240D03*
X1372164Y1423810D03*
X1375341Y1421268D03*
X1368986Y1485895D03*
X1371586D03*
X1369676Y1483295D03*
Y1488495D03*
X1368986Y1485895D03*
X1365586D03*
X1378986Y1505295D03*
X1376386D03*
X1378296Y1502695D03*
Y1507895D03*
X1378986Y1505295D03*
X1371434Y1577997D03*
X1376158D03*
X1371434Y1581397D03*
X1376158D03*
X1380882Y1577997D03*
Y1581397D03*
X1371434Y1577997D03*
X1376158D03*
X1366709D03*
X1371434Y1581397D03*
X1376158D03*
X1366709D03*
X1376158Y1583897D03*
X1366709D03*
X1371434D03*
X1380339Y1625380D03*
X1376939D03*
X1368279D03*
X1369057Y1622884D03*
X1376161D03*
X1364879Y1625380D03*
X1376939D03*
X1368279D03*
X1370909Y1635380D03*
X1374309D03*
X1370131Y1637876D03*
Y1632790D03*
X1375087Y1637876D03*
Y1632790D03*
X1369057Y1627876D03*
X1376161D03*
X1370909Y1635380D03*
X1374309D03*
X1370909Y1647292D03*
X1374309D03*
X1376939Y1657292D03*
X1368279D03*
X1380339D03*
X1369057Y1654796D03*
X1370131Y1649788D03*
X1376161Y1654796D03*
X1375087Y1649788D03*
X1370131Y1644796D03*
X1375087D03*
X1370909Y1647292D03*
X1374309D03*
X1369057Y1659788D03*
X1376161D03*
X1364879Y1657292D03*
X1376939D03*
X1368279D03*
X1367351Y1737117D03*
X1379804Y1733118D03*
X1392199Y49379D03*
X1381457Y485550D03*
X1382014Y619518D03*
X1383507Y627892D03*
X1381457Y637865D03*
X1383507Y630433D03*
X1387097Y656274D03*
X1389297Y657774D03*
X1391363Y656044D03*
X1387097Y653374D03*
X1389197Y654774D03*
X1391363Y653144D03*
X1380306Y664816D03*
X1380256Y667466D03*
X1393664Y671949D03*
Y668992D03*
X1394127Y659479D03*
X1387097Y659174D03*
X1393664Y662384D03*
Y665284D03*
X1390417Y677480D03*
X1389067Y674980D03*
X1387817Y677480D03*
X1394087Y674926D03*
X1390417Y680080D03*
X1387817D03*
X1390417Y682680D03*
X1387817D03*
X1388757Y693397D03*
Y690897D03*
X1393343Y716971D03*
X1390807Y717053D03*
X1390817Y714471D03*
X1393317D03*
X1393343Y719471D03*
X1390807Y719553D03*
X1393367Y727023D03*
Y729523D03*
X1393343Y724471D03*
Y721971D03*
X1390807Y722053D03*
Y724553D03*
X1390853Y727053D03*
X1381083Y1015473D03*
X1391460Y1009764D03*
Y1006024D03*
Y1013504D03*
X1381083Y1022559D03*
Y1019016D03*
X1391460Y1020985D03*
Y1024725D03*
Y1028465D03*
Y1017244D03*
Y1032205D03*
X1390376Y1268643D03*
X1392876D03*
Y1283661D03*
Y1281161D03*
X1390376D03*
Y1283661D03*
Y1273643D03*
Y1271143D03*
Y1276143D03*
Y1278643D03*
X1392876Y1273643D03*
Y1271143D03*
Y1276143D03*
Y1278643D03*
Y1288661D03*
Y1286161D03*
X1390376Y1288661D03*
Y1286161D03*
Y1291243D03*
X1392876D03*
X1389688Y1330690D03*
X1392132Y1330706D03*
X1393078Y1333737D03*
Y1336694D03*
X1383492Y1340553D03*
X1381062D03*
X1381988Y1336754D03*
X1384588D03*
X1387188Y1330690D03*
X1381988D03*
Y1333797D03*
X1384588Y1330690D03*
Y1333797D03*
X1393306Y1340515D03*
Y1343415D03*
X1383541Y1358568D03*
X1381062Y1346153D03*
X1383492D03*
X1384216Y1355411D03*
X1380728Y1353811D03*
X1383466Y1352843D03*
X1392092Y1346153D03*
X1389662D03*
X1387232D03*
X1383284Y1415973D03*
X1387308Y1413643D03*
X1392021Y1410360D03*
X1392386Y1485895D03*
X1395786D03*
X1389786D03*
X1391696Y1483295D03*
Y1488495D03*
X1384996Y1492995D03*
X1389776D03*
X1392386Y1485895D03*
X1382386Y1505295D03*
X1389086Y1495595D03*
X1385686D03*
X1384986Y1505295D03*
X1391686Y1495595D03*
X1383086D03*
X1384996Y1498195D03*
X1389776D03*
X1383076Y1502695D03*
Y1507895D03*
X1382386Y1505295D03*
X1389086Y1495595D03*
X1385686D03*
X1385606Y1577997D03*
X1390331D03*
X1385606Y1581397D03*
X1390331D03*
X1395055Y1577997D03*
Y1581397D03*
X1380882Y1577997D03*
X1385606D03*
X1390331D03*
X1380882Y1581397D03*
X1385606D03*
X1390331D03*
Y1583897D03*
X1380882Y1583697D03*
X1385606Y1583897D03*
X1381117Y1622884D03*
X1380339Y1625380D03*
X1382969Y1635380D03*
X1386369D03*
X1382191Y1637876D03*
X1387147D03*
X1382191Y1632884D03*
X1387147D03*
X1381117Y1627876D03*
X1382969Y1635380D03*
X1386369D03*
X1382969Y1647292D03*
X1386369D03*
X1381117Y1654796D03*
X1382191Y1649788D03*
X1387147D03*
X1382191Y1644796D03*
X1387147D03*
X1382969Y1647292D03*
X1386369D03*
X1392068Y1667907D03*
X1381918D03*
X1381117Y1659788D03*
X1380339Y1657292D03*
X1383800Y1685398D03*
X1392068Y1676875D03*
X1381918D03*
X1388918Y1687878D03*
X1391750Y1697747D03*
X1382045Y1712038D03*
Y1708038D03*
Y1704038D03*
X1390045Y1712038D03*
X1384604Y1728318D03*
X1387620Y1721418D03*
X1385061D03*
X1389351Y1737117D03*
X1393179Y1733118D03*
X1404917Y109037D03*
X1403207Y118938D03*
X1404917Y116911D03*
X1395302Y251136D03*
Y256136D03*
X1403500Y458377D03*
X1406500Y458362D03*
X1400500Y458377D03*
X1402452Y642825D03*
X1402678Y647064D03*
X1409445Y652266D03*
X1402003Y650221D03*
X1405491Y651821D03*
X1402753Y652789D03*
X1409445Y649758D03*
X1404231Y671835D03*
X1406831D03*
X1409431D03*
X1404231Y668878D03*
X1407587Y665079D03*
X1405157Y659479D03*
X1407587D03*
X1401631Y671835D03*
Y668878D03*
X1402727Y659479D03*
Y665079D03*
X1405157D03*
X1398987Y659479D03*
X1396557D03*
X1404231Y674942D03*
X1409431D03*
X1406831D03*
X1396531D03*
X1399031D03*
X1401631D03*
X1409143Y716971D03*
X1395843D03*
X1406643D03*
X1409127Y714471D03*
X1395817D03*
X1406627D03*
X1409143Y719471D03*
X1395843D03*
X1406643D03*
X1395867Y732023D03*
Y727023D03*
Y729523D03*
X1406667Y727023D03*
X1409167Y732023D03*
Y729523D03*
X1406667Y732023D03*
Y729523D03*
X1409167Y727023D03*
X1409143Y724471D03*
Y721971D03*
X1395843Y724471D03*
Y721971D03*
X1406643Y724471D03*
Y721971D03*
X1409167Y739523D03*
Y734523D03*
Y737023D03*
X1406667Y734523D03*
Y737023D03*
Y739523D03*
X1395060Y1009764D03*
Y1006024D03*
X1403693Y1009399D03*
X1407433D03*
X1399953D03*
X1395060Y1013504D03*
X1404615Y1014744D03*
X1401015D03*
X1399953Y1005799D03*
X1403693D03*
X1407433D03*
X1399953Y1028830D03*
X1407433D03*
X1404615Y1023012D03*
X1395060Y1020985D03*
Y1024725D03*
Y1028465D03*
Y1017244D03*
X1404615Y1018878D03*
X1403693Y1028830D03*
X1401015Y1023012D03*
Y1018878D03*
X1407433Y1032430D03*
X1403693D03*
X1395060Y1032205D03*
X1399953Y1032430D03*
X1395376Y1268643D03*
X1406608Y1282606D03*
X1395376Y1273643D03*
Y1271143D03*
Y1281243D03*
Y1283743D03*
Y1276143D03*
Y1278643D03*
Y1288743D03*
Y1286243D03*
Y1291243D03*
X1405716Y1310618D03*
X1401740Y1311980D03*
X1399240D03*
X1408690Y1324803D03*
X1396302Y1328152D03*
Y1325552D03*
X1398902Y1328152D03*
Y1325552D03*
X1396302Y1322952D03*
X1398902D03*
X1401406Y1334918D03*
X1397652Y1330652D03*
X1399122Y1352258D03*
X1394856Y1352488D03*
X1399122Y1346458D03*
Y1349358D03*
X1396922Y1347858D03*
X1394856Y1349588D03*
X1397022Y1350858D03*
X1398375Y1403688D03*
X1401764Y1399928D03*
X1405207Y1395480D03*
X1408543Y1391826D03*
X1395463Y1406918D03*
X1405811Y1430021D03*
X1409186Y1485895D03*
X1405786D03*
X1398386D03*
X1403186D03*
X1405096Y1483295D03*
X1396476D03*
X1405096Y1488495D03*
X1396476D03*
X1395786Y1485895D03*
X1409186D03*
X1405786D03*
X1409456Y1537872D03*
X1409532Y1552845D03*
X1409409Y1549120D03*
Y1545220D03*
X1403257Y1552250D03*
X1405079Y1549953D03*
Y1544953D03*
Y1547453D03*
X1406655Y1564073D03*
X1409155D03*
X1405764Y1554436D03*
X1406074Y1581563D03*
X1397955Y1582178D03*
X1395055Y1577997D03*
Y1581397D03*
Y1583797D03*
X1397030Y1594060D03*
X1406666Y1616332D03*
X1398058Y1619683D03*
X1409660Y1619853D03*
X1396783Y1617170D03*
X1399940Y1637127D03*
X1405058Y1639607D03*
X1397367Y1639951D03*
X1408023Y1638705D03*
X1398058Y1628651D03*
X1408208D03*
X1402425Y1649532D03*
X1406814Y1652439D03*
X1399599Y1657583D03*
X1398883Y1680341D03*
X1414199Y49379D03*
X1414619Y244450D03*
X1410750Y244583D03*
X1414000Y460362D03*
X1419335Y533958D03*
X1414714Y653008D03*
X1412434Y655943D03*
X1416207Y663333D03*
Y660792D03*
X1421797Y687354D03*
X1423963Y685724D03*
X1419697Y685954D03*
X1416241Y700281D03*
X1416291Y697631D03*
X1421897Y690354D03*
X1423963Y688624D03*
X1419697Y688854D03*
Y691754D03*
X1420417Y712660D03*
Y715260D03*
Y710060D03*
X1423017Y712660D03*
Y715260D03*
Y710060D03*
X1421667Y707560D03*
X1422757Y726097D03*
Y723597D03*
X1423417Y747051D03*
X1423407Y757133D03*
Y749633D03*
Y752133D03*
Y754633D03*
X1416301Y966740D03*
Y970340D03*
Y981740D03*
Y974240D03*
Y977840D03*
Y985340D03*
X1418101Y997765D03*
Y993765D03*
X1418176Y989765D03*
X1414576D03*
X1414501Y993765D03*
Y997765D03*
X1418653Y1009399D03*
X1418101Y1001765D03*
X1422394Y1009399D03*
X1414913D03*
X1411173D03*
X1423316Y1014744D03*
X1414458D03*
X1410858D03*
X1418653Y1005799D03*
X1414913D03*
X1411173D03*
X1414501Y1001765D03*
X1419716Y1014744D03*
X1422394Y1005799D03*
X1414458Y1023012D03*
X1418653Y1028830D03*
X1411173D03*
X1414913D03*
X1423316Y1023012D03*
Y1018878D03*
X1422394Y1028830D03*
X1414458Y1018878D03*
X1410858Y1023012D03*
X1419716D03*
X1410858Y1018878D03*
X1419716D03*
X1415426Y1042765D03*
Y1038765D03*
X1422394Y1032430D03*
X1419026Y1038765D03*
Y1042765D03*
X1414913Y1032430D03*
X1418653D03*
X1411173D03*
X1417301Y1055140D03*
Y1051540D03*
X1418982Y1175144D03*
X1414165Y1289564D03*
X1414172Y1286188D03*
X1424561Y1305566D03*
X1420690Y1324803D03*
X1417690D03*
X1414690D03*
X1411690D03*
X1424163Y1373240D03*
X1411508Y1388384D03*
X1414950Y1384942D03*
X1417491Y1381183D03*
X1420774Y1377106D03*
X1411786Y1485895D03*
X1409876Y1483295D03*
Y1488495D03*
X1416556Y1513682D03*
Y1517082D03*
Y1511082D03*
Y1519682D03*
X1419156Y1512992D03*
Y1517772D03*
X1413956Y1512992D03*
Y1517772D03*
X1416556Y1513682D03*
Y1517082D03*
Y1530482D03*
Y1527082D03*
Y1533082D03*
Y1524482D03*
X1419156Y1531172D03*
Y1526392D03*
X1413956Y1531172D03*
Y1526392D03*
X1423735Y1536715D03*
X1416556Y1530482D03*
Y1527082D03*
X1412020Y1542654D03*
X1415434Y1552845D03*
X1415709Y1545220D03*
Y1549120D03*
X1418523Y1542469D03*
X1419959Y1545076D03*
Y1547576D03*
X1416023Y1542469D03*
X1412559Y1549120D03*
Y1545220D03*
X1420735Y1559750D03*
X1412572Y1556953D03*
X1411655Y1564073D03*
X1412572Y1554436D03*
X1417981Y1568680D03*
X1423531Y1574795D03*
Y1582295D03*
Y1579795D03*
Y1577295D03*
X1424621Y1571911D03*
Y1569411D03*
X1421232Y1606126D03*
X1422914Y1601663D03*
X1412467Y1602234D03*
X1419914Y1602777D03*
X1418740Y1622902D03*
X1422154Y1626270D03*
X1423722Y1616780D03*
X1419622Y1616000D03*
X1422266Y1628947D03*
X1411113Y1637767D03*
X1413199Y1643920D03*
X1416357Y1644027D03*
X1420042Y1649716D03*
X1410315Y1646967D03*
X1424315D03*
X1411351Y1737117D03*
X1436263Y-28311D03*
Y-31711D03*
Y-28311D03*
Y-31711D03*
X1433817Y-34648D03*
X1438983Y-35569D03*
X1436263Y-18311D03*
Y-21711D03*
Y-18311D03*
Y-21711D03*
X1433817Y-25374D03*
Y-15374D03*
X1438883Y-15050D03*
Y-25050D03*
X1436263Y1689D03*
Y-1711D03*
Y1689D03*
Y-1711D03*
X1433817Y-4648D03*
X1438883Y-5050D03*
X1436263Y11689D03*
Y8289D03*
Y11689D03*
Y8289D03*
X1433817Y5352D03*
Y14626D03*
X1438883Y14950D03*
Y4950D03*
X1438959Y25382D03*
X1436199Y49379D03*
X1427973Y60409D03*
X1434262Y52892D03*
X1438262D03*
X1434513Y106950D03*
X1439049Y107443D03*
X1429169Y107313D03*
X1438312Y152166D03*
X1431300Y538800D03*
X1435400Y536200D03*
X1431400Y533400D03*
X1435400Y530800D03*
X1439232Y596291D03*
X1435278Y679644D03*
X1436257Y676265D03*
X1434603Y682801D03*
X1438091Y684401D03*
X1435353Y685369D03*
X1436831Y701458D03*
X1435327Y692059D03*
X1437757D03*
X1434231Y701458D03*
X1435327Y697659D03*
X1437757D03*
X1426264Y701572D03*
X1431617Y692359D03*
X1429187D03*
X1426757D03*
X1426264Y694954D03*
Y697854D03*
X1436831Y704415D03*
Y707522D03*
X1439431Y704415D03*
Y707522D03*
X1431631D03*
X1429131D03*
X1426687Y707506D03*
X1434231Y704415D03*
Y707522D03*
X1426264Y704529D03*
X1439227Y747051D03*
X1425917D03*
X1428417D03*
X1428407Y762133D03*
Y759633D03*
X1425907D03*
X1439257Y762133D03*
Y759633D03*
X1425943Y757051D03*
X1428443D03*
X1425943Y749551D03*
Y752051D03*
Y754551D03*
X1428443D03*
Y752051D03*
Y749551D03*
X1439243Y757051D03*
Y749551D03*
Y752051D03*
Y754551D03*
X1439257Y764633D03*
Y769633D03*
Y767133D03*
X1438507Y1006024D03*
X1433614Y1009399D03*
X1426134D03*
X1429874D03*
X1438507Y1009764D03*
Y1013504D03*
X1433552Y1014744D03*
X1429952D03*
X1433614Y1005799D03*
X1426134D03*
X1429874D03*
X1438507Y1024725D03*
Y1020985D03*
X1429874Y1028830D03*
X1438507Y1017244D03*
X1433552Y1018878D03*
X1438507Y1028465D03*
X1433552Y1023012D03*
X1426134Y1028830D03*
X1433614D03*
X1429952Y1023012D03*
Y1018878D03*
X1438507Y1032205D03*
X1426134Y1032430D03*
X1433614D03*
X1429874D03*
X1425437Y1308184D03*
X1426202Y1310752D03*
X1427314Y1313482D03*
X1428458Y1316481D03*
X1429517Y1319447D03*
X1430312Y1322412D03*
X1431106Y1325219D03*
X1426441Y1369427D03*
X1428559Y1365296D03*
X1430465Y1361060D03*
X1441398Y1495595D03*
X1438798D03*
X1435160Y1516590D03*
Y1513190D03*
Y1519190D03*
Y1510590D03*
X1432560Y1517280D03*
Y1512500D03*
X1437760Y1517280D03*
Y1512500D03*
X1435160Y1516590D03*
Y1513190D03*
Y1534990D03*
Y1538390D03*
Y1532490D03*
X1432560Y1534300D03*
X1437760D03*
X1435160Y1534990D03*
X1432560Y1539080D03*
X1437760D03*
X1435160Y1540990D03*
Y1538390D03*
X1434235Y1550240D03*
X1433235Y1543800D03*
X1430735D03*
X1431735Y1550240D03*
X1435578Y1564902D03*
Y1562402D03*
X1430431Y1563595D03*
X1427931D03*
X1424971Y1566764D03*
Y1564264D03*
X1436940Y1554277D03*
X1434578Y1556331D03*
Y1559731D03*
X1430213Y1553652D03*
X1427713D03*
X1435604Y1572106D03*
Y1569606D03*
X1426031Y1582295D03*
X1431031Y1574795D03*
Y1577295D03*
X1426031Y1579795D03*
Y1577295D03*
Y1574795D03*
X1428531D03*
Y1577295D03*
Y1579795D03*
Y1582295D03*
X1430431Y1570595D03*
X1427931D03*
X1437901Y1579795D03*
Y1577295D03*
Y1574795D03*
Y1582295D03*
X1435401D03*
Y1579795D03*
Y1577295D03*
Y1574795D03*
X1431989Y1581199D03*
X1434494Y1584844D03*
X1431989Y1584099D03*
X1429571Y1584844D03*
X1430244Y1609966D03*
X1430075Y1613904D03*
X1434316Y1616909D03*
X1437594Y1616845D03*
X1426899Y1616990D03*
X1425390Y1635496D03*
X1433327Y1643287D03*
X1433979Y1655655D03*
X1433911Y1649037D03*
X1436311Y1665948D03*
X1435904Y1694335D03*
X1433351Y1737117D03*
X1445292Y-28927D03*
X1445307Y-31442D03*
X1442023Y-36764D03*
X1442008Y-34249D03*
X1445276Y-36778D03*
X1445261Y-34263D03*
X1441908Y-26370D03*
X1445161Y-26356D03*
X1441909Y-19948D03*
X1445171D03*
X1441908Y-16370D03*
X1441923Y-13855D03*
X1445161Y-16356D03*
X1445176Y-13841D03*
X1441923Y-23855D03*
X1445176Y-23841D03*
X1441909Y-9948D03*
X1445171D03*
X1441909Y52D03*
X1445171D03*
X1441908Y-6370D03*
X1441923Y-3855D03*
X1445161Y-6356D03*
X1445176Y-3841D03*
X1441908Y3630D03*
X1445161Y3644D03*
X1441909Y10052D03*
X1445171D03*
X1441908Y13630D03*
X1441923Y16145D03*
X1445161Y13644D03*
X1445176Y16159D03*
X1441923Y6145D03*
X1445176Y6159D03*
X1445237Y26688D03*
X1445252Y24173D03*
X1441984Y26702D03*
X1441999Y24187D03*
X1445267Y21658D03*
X1445282Y19143D03*
X1441141Y53699D03*
X1446869Y105129D03*
X1445985Y116953D03*
X1451353Y116158D03*
X1443049Y107443D03*
X1448549Y114643D03*
X1446040Y120218D03*
X1452040Y113018D03*
X1440871Y130118D03*
X1453667Y152166D03*
X1441390Y163944D03*
X1440871Y152166D03*
X1444769Y163842D03*
X1442993Y176204D03*
X1444769Y174217D03*
X1453974Y174414D03*
X1439769Y174217D03*
Y182217D03*
X1449769D03*
X1443551Y539318D03*
Y535318D03*
X1441053Y560535D03*
X1452708Y610954D03*
Y607954D03*
X1449708Y610954D03*
X1446708D03*
Y607954D03*
X1449708D03*
X1440708Y610954D03*
X1443708D03*
X1440708Y607954D03*
X1443708D03*
X1452708Y613954D03*
X1446708Y616954D03*
Y619954D03*
X1440708D03*
Y616954D03*
X1443708D03*
Y619954D03*
X1449708Y613954D03*
X1446708D03*
X1440708D03*
X1443708D03*
X1446708Y622954D03*
X1440708D03*
X1443708D03*
X1452938Y617364D03*
X1450438D03*
X1452898Y621844D03*
X1450398D03*
X1448996Y645270D03*
Y647770D03*
X1451496Y645270D03*
X1453996D03*
Y647770D03*
X1451496D03*
X1449046Y650370D03*
X1454046D03*
X1451546D03*
X1446426D03*
X1443926D03*
X1443876Y645270D03*
Y647770D03*
X1446376Y645270D03*
Y647770D03*
X1447314Y684998D03*
X1442091Y684846D03*
X1442045Y682338D03*
X1440187Y697659D03*
Y692059D03*
X1448807Y695913D03*
Y693372D03*
X1445034Y688523D03*
X1442031Y704415D03*
Y707522D03*
X1452615Y705531D03*
X1453335Y729637D03*
Y732237D03*
Y734837D03*
X1453757Y743597D03*
Y746097D03*
X1441727Y747051D03*
X1444257Y757133D03*
Y759633D03*
Y762133D03*
X1441757Y759633D03*
Y762133D03*
X1441743Y757051D03*
Y754551D03*
Y752051D03*
Y749551D03*
X1444257Y772133D03*
Y764633D03*
Y769633D03*
Y767133D03*
X1441757Y772133D03*
Y764633D03*
Y769633D03*
Y767133D03*
X1453345Y1015473D03*
X1442107Y1013504D03*
Y1009764D03*
Y1006024D03*
X1453345Y1019016D03*
Y1022559D03*
X1442107Y1020985D03*
Y1024725D03*
Y1028465D03*
Y1017244D03*
Y1032205D03*
X1451498Y1485895D03*
X1448098D03*
X1454098D03*
X1445498D03*
X1447408Y1483295D03*
X1452188D03*
X1447408Y1488495D03*
X1452188D03*
X1445488Y1492995D03*
X1440708D03*
X1451498Y1485895D03*
X1448098D03*
X1444798Y1495595D03*
X1447398D03*
X1445488Y1498195D03*
X1440708D03*
X1444798Y1495595D03*
X1441398D03*
X1444200Y1533240D03*
X1445535Y1551040D03*
Y1547420D03*
Y1543800D03*
X1439850Y1541470D03*
X1446027Y1561731D03*
X1448505Y1579725D03*
X1440401Y1574795D03*
Y1582295D03*
Y1579795D03*
Y1577295D03*
X1442901Y1582295D03*
Y1579795D03*
Y1577295D03*
Y1574795D03*
X1448061Y1593055D03*
X1445500Y1611500D03*
X1448500Y1601000D03*
X1451000D03*
X1446000Y1600500D03*
X1450500Y1614500D03*
Y1624000D03*
X1445500Y1614500D03*
X1441000D03*
X1440027Y1667945D03*
X1442579Y1673303D03*
X1447579D03*
X1452579D03*
X1453950Y1681450D03*
X1453553Y1686892D03*
X1445079Y1686678D03*
X1449070Y1686722D03*
X1448000Y1676000D03*
X1458199Y49379D03*
X1462405Y61563D03*
X1464830Y59054D03*
X1454549Y107443D03*
X1461242Y128242D03*
X1463017Y136368D03*
X1455667Y125733D03*
X1463017Y139518D03*
X1459177Y163796D03*
X1456226Y152166D03*
X1459682Y450372D03*
X1466609Y458608D03*
X1468395Y487582D03*
X1465395D03*
X1465832Y535330D03*
Y530656D03*
X1464257Y552977D03*
X1463647Y544977D03*
X1456282Y568977D03*
X1464257Y564977D03*
Y560977D03*
Y557498D03*
X1462497Y555021D03*
X1464257Y568977D03*
X1456282Y572977D03*
Y576977D03*
Y580977D03*
X1464257Y572977D03*
Y580977D03*
Y576977D03*
X1467708Y610954D03*
Y607954D03*
X1464708Y610954D03*
Y607954D03*
X1458708Y610954D03*
X1455708D03*
X1461708D03*
Y607954D03*
X1455708D03*
X1458708D03*
X1467708Y616954D03*
Y619954D03*
Y613954D03*
X1461708Y616954D03*
Y619954D03*
X1464708Y616954D03*
Y619954D03*
Y613954D03*
X1458708D03*
X1455708D03*
X1461708D03*
X1467708Y622954D03*
X1461708D03*
X1464708D03*
X1455438Y617364D03*
X1457938D03*
X1455398Y621844D03*
X1457898D03*
X1456496Y645270D03*
X1459396D03*
X1456496Y647770D03*
X1459396D03*
X1456546Y650370D03*
X1459446D03*
X1468257Y696265D03*
X1468196Y699221D03*
X1467521Y702378D03*
X1454715Y700931D03*
X1468245Y711636D03*
Y717236D03*
X1468271Y704946D03*
X1462045Y711826D03*
X1464475D03*
X1459615D03*
X1456881Y708201D03*
Y705301D03*
X1454715Y706931D03*
Y703931D03*
X1454815Y709931D03*
X1458777Y714194D03*
Y717094D03*
X1467149Y721035D03*
X1458599Y721045D03*
Y724002D03*
X1455935Y729637D03*
Y732237D03*
X1454585Y727137D03*
X1459605Y727083D03*
X1462049Y727099D03*
X1464549D03*
X1467149Y723992D03*
Y727099D03*
X1455935Y734837D03*
X1456335Y771710D03*
Y766628D03*
X1458861Y776628D03*
X1461361D03*
X1458861Y769128D03*
Y771628D03*
Y774128D03*
X1461361D03*
Y771628D03*
Y769128D03*
X1461335Y766628D03*
X1458835D03*
X1456335Y776710D03*
Y774210D03*
Y769210D03*
X1461371Y791696D03*
Y789196D03*
X1458871Y779196D03*
X1461371D03*
X1458871Y784196D03*
Y781696D03*
Y786696D03*
X1461371Y784196D03*
Y786696D03*
Y781696D03*
X1456371Y779210D03*
Y781710D03*
Y784210D03*
X1460926Y1015473D03*
X1467926D03*
X1456945D03*
X1464526D03*
X1460926Y1019016D03*
Y1022559D03*
X1467926Y1019016D03*
Y1022559D03*
X1456945Y1019016D03*
Y1022559D03*
X1464526Y1019016D03*
Y1022559D03*
X1467508Y1492995D03*
X1468198Y1495595D03*
X1464898Y1505295D03*
X1461498D03*
X1467498D03*
X1458898D03*
X1465598Y1495595D03*
X1467508Y1498195D03*
X1460808Y1502695D03*
X1465588D03*
X1460808Y1507895D03*
X1465588D03*
X1464898Y1505295D03*
X1461498D03*
X1468198Y1495595D03*
X1460301Y1577997D03*
X1465025D03*
X1460301Y1581397D03*
X1465025D03*
X1469750Y1577997D03*
Y1581397D03*
X1460301Y1577997D03*
X1465025D03*
X1460301Y1581397D03*
X1465025D03*
Y1583797D03*
X1460301D03*
X1460213Y1625380D03*
X1463613D03*
X1464391Y1622884D03*
X1459435D03*
X1460213Y1625380D03*
X1463613D03*
X1466243Y1635380D03*
X1469643D03*
X1465465Y1637876D03*
Y1632884D03*
X1459435Y1627876D03*
X1464391D03*
X1455579Y1636114D03*
X1466243Y1635380D03*
X1469643Y1647292D03*
X1466243D03*
X1460213Y1657292D03*
X1463613D03*
X1464391Y1654796D03*
X1465465Y1649788D03*
Y1644796D03*
X1459435Y1654796D03*
X1466243Y1647292D03*
X1464391Y1659788D03*
X1466500Y1666000D03*
X1469034Y1667794D03*
X1459435Y1659788D03*
X1460213Y1657292D03*
X1463613D03*
X1468102Y1670817D03*
X1458795Y1687083D03*
X1456852Y1673320D03*
X1466599Y1679401D03*
X1466260Y1675155D03*
X1460457Y1685160D03*
X1457940Y1675710D03*
X1463038Y1687060D03*
X1466111Y1685098D03*
X1480199Y49379D03*
X1483820Y122713D03*
Y132405D03*
X1471395Y487582D03*
X1473947Y492169D03*
X1475257Y530656D03*
X1482257Y552977D03*
X1478257Y543977D03*
X1481257Y544977D03*
X1482044Y542517D03*
X1472257Y551241D03*
X1482257Y560477D03*
Y567977D03*
X1472757Y561264D03*
X1472257Y564977D03*
X1478258Y588108D03*
Y584142D03*
X1481934Y699670D03*
X1480300Y697750D03*
X1474963Y701915D03*
X1473105Y717236D03*
X1470675Y711636D03*
X1473105D03*
X1470675Y717236D03*
X1480232Y704575D03*
X1475009Y704488D03*
X1481725Y715490D03*
X1471009Y703978D03*
X1481725Y712949D03*
X1477952Y708100D03*
X1469749Y721035D03*
Y723992D03*
X1474949D03*
X1472349D03*
Y727099D03*
X1469749D03*
X1474949D03*
X1481665Y745809D03*
X1477171Y774196D03*
Y771696D03*
Y769196D03*
Y776696D03*
X1474661Y776628D03*
Y774128D03*
Y771628D03*
Y769128D03*
X1472161Y776628D03*
Y769128D03*
Y771628D03*
Y774128D03*
X1472145Y766628D03*
X1474645D03*
X1477145D03*
X1477171Y791696D03*
X1474671D03*
X1472171D03*
X1477171Y786696D03*
X1474671D03*
X1477171Y781696D03*
X1474671D03*
X1472171Y789196D03*
Y779196D03*
Y784196D03*
Y786696D03*
Y781696D03*
X1477171Y789196D03*
X1474671D03*
X1477171Y779196D03*
X1474671D03*
X1477171Y784196D03*
X1474671D03*
X1477177Y803488D03*
X1481177D03*
X1469950Y813232D03*
X1473728Y813552D03*
X1478177Y817013D03*
X1484177Y812988D03*
X1474177Y816872D03*
X1471526Y1015473D03*
Y1019016D03*
Y1022559D03*
X1478298Y1485895D03*
X1474898D03*
X1472288Y1492995D03*
X1474208Y1483295D03*
X1478988D03*
X1472298Y1485895D03*
X1480898D03*
X1474208Y1488495D03*
X1478988D03*
X1478298Y1485895D03*
X1474898D03*
X1471598Y1495595D03*
X1474198D03*
X1472288Y1498195D03*
X1471598Y1495595D03*
X1474474Y1577997D03*
X1479199D03*
X1483923D03*
X1474474Y1581397D03*
X1479199D03*
X1483923D03*
X1469750Y1577997D03*
X1474474D03*
X1479199D03*
X1483923D03*
X1469750Y1581397D03*
X1474474D03*
X1479199D03*
X1483923D03*
X1479199Y1583897D03*
X1483923D03*
X1469750D03*
X1474474Y1583697D03*
X1484333Y1625380D03*
X1472273D03*
X1475673D03*
X1476451Y1622884D03*
X1471495D03*
X1483555D03*
X1472273Y1625380D03*
X1475673D03*
X1478303Y1635380D03*
X1481703D03*
X1470421Y1632884D03*
Y1637876D03*
X1482481D03*
X1477525D03*
X1482481Y1632884D03*
X1477525D03*
X1471495Y1627876D03*
X1483555D03*
X1476451D03*
X1478303Y1635380D03*
X1469643D03*
X1481703D03*
Y1647292D03*
X1478303D03*
X1472273Y1657292D03*
X1475673D03*
X1484333D03*
X1471495Y1654796D03*
X1470421Y1649788D03*
X1476451Y1654796D03*
X1483555D03*
X1482481Y1649788D03*
X1477525D03*
X1470421Y1644796D03*
X1477525D03*
X1482481D03*
X1478303Y1647292D03*
X1469643D03*
X1481703D03*
X1471495Y1659788D03*
X1476451D03*
X1483555D03*
X1471616Y1670098D03*
X1472273Y1657292D03*
X1475673D03*
X1479375Y1685984D03*
X1482798Y1685982D03*
X1469588Y1673342D03*
X1470500Y1685500D03*
X1494891Y121171D03*
X1488647Y134562D03*
X1495539Y131237D03*
X1492237Y123842D03*
X1484395Y487582D03*
X1489757Y552977D03*
X1497257D03*
X1484416Y541658D03*
X1490602Y544755D03*
X1497310Y543960D03*
X1494967Y541898D03*
X1497257Y560477D03*
X1489757Y567977D03*
X1497257D03*
X1491677Y583588D03*
X1490677Y580688D03*
X1498543Y587841D03*
X1494371Y594462D03*
X1495236Y612838D03*
X1495486Y599938D03*
X1497986Y602438D03*
Y599938D03*
X1495236Y605338D03*
X1495486Y602438D03*
X1495236Y607838D03*
Y610338D03*
X1492636Y605258D03*
Y607758D03*
Y610258D03*
Y612758D03*
X1497986Y612838D03*
Y605338D03*
Y607838D03*
Y610338D03*
X1495486Y615988D03*
Y618488D03*
X1497986Y615988D03*
Y618488D03*
X1492886Y618408D03*
Y615908D03*
X1497587Y711636D03*
X1495157D03*
X1492727D03*
X1489963Y705301D03*
X1487797Y706931D03*
X1487897Y709931D03*
X1489963Y708201D03*
X1485697Y708431D03*
Y705531D03*
Y711331D03*
X1492264Y714544D03*
Y717444D03*
Y721149D03*
X1486417Y729637D03*
Y732237D03*
X1489017Y729687D03*
Y732237D03*
X1492264Y724106D03*
X1487667Y727137D03*
X1492687Y727083D03*
X1495131Y727099D03*
X1497631D03*
X1486417Y734837D03*
X1489017D03*
X1484265Y745809D03*
X1491943Y776628D03*
X1494443D03*
X1491943Y769128D03*
Y771628D03*
Y774128D03*
X1494443D03*
Y771628D03*
Y769128D03*
X1494417Y766628D03*
X1491917D03*
X1489417Y776710D03*
Y774210D03*
Y769210D03*
Y771710D03*
Y766628D03*
X1494487Y779210D03*
Y784210D03*
Y786710D03*
Y781710D03*
X1491987Y779210D03*
Y784210D03*
Y786710D03*
Y781710D03*
X1489487Y779210D03*
Y784210D03*
Y786710D03*
Y781710D03*
X1489177Y803488D03*
X1496532Y803513D03*
X1485177Y803488D03*
X1498177Y817013D03*
X1489177Y812988D03*
X1487923Y816770D03*
X1492673Y828513D03*
X1490973Y825557D03*
X1495670Y826073D03*
X1486761Y826279D03*
X1494386Y1178743D03*
X1493260Y1167390D03*
X1496960D03*
X1499098Y1485895D03*
X1494308Y1492995D03*
X1499088D03*
X1498398Y1495595D03*
X1491698Y1505295D03*
X1488298D03*
X1494998Y1495595D03*
X1492398D03*
X1494298Y1505295D03*
X1485698D03*
X1494308Y1498195D03*
X1499088D03*
X1492388Y1502695D03*
X1487608D03*
X1492388Y1507895D03*
X1487608D03*
X1491698Y1505295D03*
X1488298D03*
X1498398Y1495595D03*
X1494998D03*
X1488648Y1577997D03*
X1493372D03*
X1498097D03*
X1488648Y1581397D03*
X1493372D03*
X1498097D03*
X1488648Y1577997D03*
X1493372D03*
X1498097D03*
X1488648Y1581397D03*
X1493372D03*
X1498097D03*
X1493372Y1583797D03*
X1498097Y1583897D03*
X1488648Y1583697D03*
X1496393Y1625380D03*
X1499793D03*
X1487733D03*
X1488511Y1622884D03*
X1495615D03*
X1484333Y1625380D03*
X1496393D03*
X1487733D03*
X1490363Y1635380D03*
X1493763D03*
X1494541Y1637876D03*
X1489585D03*
X1494541Y1632884D03*
X1489585D03*
X1488511Y1627876D03*
X1495615D03*
X1490363Y1635380D03*
X1493763D03*
X1490363Y1647292D03*
X1493763D03*
X1496393Y1657292D03*
X1487733D03*
X1499793D03*
X1488511Y1654796D03*
X1495615D03*
X1489585Y1649788D03*
X1494541D03*
X1489585Y1644796D03*
X1494541D03*
X1490363Y1647292D03*
X1493763D03*
X1488511Y1659788D03*
X1495615D03*
X1484333Y1657292D03*
X1496393D03*
X1487733D03*
X1502199Y49379D03*
X1513348Y253954D03*
X1503785Y464815D03*
X1505974Y470636D03*
X1511917Y483878D03*
X1499752Y488424D03*
X1500757Y537438D03*
X1504757Y537378D03*
X1508757Y537456D03*
X1512757Y537477D03*
X1506337Y561677D03*
X1508281Y559390D03*
X1502986Y602438D03*
Y599938D03*
X1500486Y602438D03*
Y599938D03*
X1502486Y605338D03*
Y607838D03*
Y610338D03*
Y612838D03*
X1500486Y615988D03*
Y618488D03*
X1502986Y615988D03*
Y618488D03*
X1501278Y699221D03*
X1513382Y697750D03*
X1500603Y702378D03*
X1508045Y701915D03*
X1506187Y717236D03*
Y711636D03*
X1501327D03*
X1503757D03*
X1501327Y717404D03*
X1503757D03*
X1513314Y704575D03*
X1508045Y704423D03*
X1504091Y703978D03*
X1501353Y704946D03*
X1511034Y708100D03*
X1502831Y721035D03*
X1500231D03*
Y723992D03*
X1502831D03*
X1505431D03*
X1508031D03*
X1500231Y727099D03*
X1502831D03*
X1505431D03*
X1508031D03*
X1505905Y746119D03*
X1508505D03*
X1510287Y771710D03*
Y769210D03*
Y774210D03*
Y776710D03*
X1507743Y776628D03*
Y774128D03*
Y771628D03*
Y769128D03*
X1505243Y776628D03*
Y769128D03*
Y771628D03*
Y774128D03*
X1505227Y766628D03*
X1507727D03*
X1510227D03*
X1507787Y786710D03*
Y781710D03*
X1505287Y779210D03*
Y784210D03*
Y786710D03*
Y781710D03*
X1510287Y779210D03*
Y784210D03*
Y786710D03*
Y781710D03*
X1507787Y779210D03*
Y784210D03*
X1499243Y803513D03*
X1508177Y803488D03*
X1501500Y799948D03*
X1501730Y811872D03*
X1510261Y814611D03*
X1500422Y814180D03*
X1512523Y809679D03*
X1502177Y817013D03*
X1512539Y812920D03*
X1505016Y817107D03*
X1501338Y825147D03*
X1501636Y828796D03*
X1499469Y860322D03*
Y863322D03*
X1513470Y1178265D03*
X1504470D03*
X1504362Y1167390D03*
X1508063D03*
X1505098Y1485895D03*
X1501698D03*
X1507698D03*
X1505788Y1483295D03*
X1501008D03*
X1505788Y1488495D03*
X1501008D03*
X1505098Y1485895D03*
X1501698D03*
X1515098Y1505295D03*
X1500998Y1495595D03*
X1512498Y1505295D03*
X1507546Y1577997D03*
X1512270D03*
X1502821D03*
X1507546Y1581397D03*
X1512270D03*
X1502821D03*
X1507546Y1577997D03*
X1512270D03*
X1502821D03*
X1507546Y1581397D03*
X1512270D03*
X1502821D03*
X1512270Y1583897D03*
X1502821D03*
X1507546D03*
X1511853Y1625380D03*
X1508453D03*
X1500571Y1622884D03*
X1512631D03*
X1507675D03*
X1508453Y1625380D03*
X1499793D03*
X1511853D03*
X1502423Y1635380D03*
X1505823D03*
X1514483D03*
X1501645Y1637876D03*
Y1632884D03*
X1506601Y1637876D03*
Y1632884D03*
X1513705Y1637876D03*
Y1632884D03*
X1500571Y1627876D03*
X1512631D03*
X1507675D03*
X1502423Y1635380D03*
X1505823D03*
X1514483Y1647292D03*
X1502423D03*
X1505823D03*
X1508453Y1657292D03*
X1511853D03*
X1500571Y1654796D03*
X1501645Y1649788D03*
X1507675Y1654796D03*
X1512631D03*
X1513705Y1649788D03*
X1506601D03*
X1501645Y1644796D03*
X1513705D03*
X1506601D03*
X1502423Y1647292D03*
X1505823D03*
X1500571Y1659788D03*
X1507675D03*
X1512831Y1659588D03*
X1508453Y1657292D03*
X1499793D03*
X1511853D03*
X1499351Y1737117D03*
X1524124Y47570D03*
X1515854Y119810D03*
X1522917Y119912D03*
X1517708Y216505D03*
X1527392Y238017D03*
X1516452Y249724D03*
X1514900Y251839D03*
X1515936Y484412D03*
X1516757Y537477D03*
X1519930Y543470D03*
X1516257Y547977D03*
X1516336Y551977D03*
X1516357Y555318D03*
X1516257Y559977D03*
X1519317Y561977D03*
X1524777Y605488D03*
Y607988D03*
X1527277Y605488D03*
Y607988D03*
X1524777Y610588D03*
X1527277D03*
X1524777Y613088D03*
X1527277D03*
X1524777Y615618D03*
X1527277D03*
X1524777Y618118D03*
X1527277D03*
X1515016Y699670D03*
X1514807Y715490D03*
Y712949D03*
X1525527Y711636D03*
X1527957D03*
X1522763Y708201D03*
Y705301D03*
X1518497Y705531D03*
X1520597Y706931D03*
X1518497Y708431D03*
X1520697Y709931D03*
X1518497Y711331D03*
X1525064Y714544D03*
Y717444D03*
Y721149D03*
Y724106D03*
X1521817Y729637D03*
Y732237D03*
X1525487Y727083D03*
X1527931Y727099D03*
X1519217Y729637D03*
Y732237D03*
X1520467Y727137D03*
X1521817Y734837D03*
X1519217D03*
X1515895Y746119D03*
X1518495D03*
X1522217Y771710D03*
X1527217Y766628D03*
X1522217Y769210D03*
X1524717Y766628D03*
X1522217D03*
Y774210D03*
Y776710D03*
X1524743Y776628D03*
X1527243D03*
X1524743Y769128D03*
Y771628D03*
Y774128D03*
X1527243D03*
Y771628D03*
Y769128D03*
X1527217Y779210D03*
Y784210D03*
Y786710D03*
Y781710D03*
X1524717Y779210D03*
X1522217D03*
X1524717Y784210D03*
Y786710D03*
X1522217Y784210D03*
Y786710D03*
X1524717Y781710D03*
X1522217D03*
X1515192Y814294D03*
X1517431Y811466D03*
X1521003Y1169488D03*
X1521217Y1190088D03*
X1524425Y1185241D03*
X1528498Y1485895D03*
X1525898D03*
X1527808Y1483295D03*
Y1488495D03*
X1521108Y1492995D03*
X1525888D03*
X1528498Y1485895D03*
X1518498Y1505295D03*
X1525198Y1495595D03*
X1521798D03*
X1521098Y1505295D03*
X1525898D03*
X1527798Y1495595D03*
X1519198D03*
X1521108Y1498195D03*
X1525888D03*
X1519188Y1502695D03*
X1527808D03*
X1514408D03*
X1519188Y1507895D03*
X1514408D03*
X1518498Y1505295D03*
X1525198Y1495595D03*
X1515098Y1505295D03*
X1521798Y1495595D03*
X1516994Y1577997D03*
X1521718D03*
X1526443D03*
X1516994Y1581397D03*
X1521718D03*
X1526443D03*
X1516994Y1577997D03*
X1521718D03*
X1526443D03*
X1516994Y1581397D03*
X1521718D03*
X1526443D03*
Y1583897D03*
X1516994Y1583697D03*
X1521718Y1583897D03*
X1520513Y1625380D03*
X1523913D03*
X1524691Y1622884D03*
X1519735D03*
X1520513Y1625380D03*
X1523913D03*
X1526543Y1635380D03*
X1517883D03*
X1529943D03*
X1518661Y1637876D03*
Y1632884D03*
X1525765Y1637876D03*
Y1632884D03*
X1519735Y1627876D03*
X1524691D03*
X1514483Y1635380D03*
X1526543D03*
X1517883D03*
X1526543Y1647292D03*
X1529943D03*
X1517883D03*
X1520513Y1657292D03*
X1523913D03*
X1518661Y1649788D03*
X1524691Y1654796D03*
X1519735D03*
X1525765Y1649788D03*
X1518661Y1644796D03*
X1525765D03*
X1514483Y1647292D03*
X1526543D03*
X1517883D03*
X1524991Y1659788D03*
X1519735D03*
X1520513Y1657292D03*
X1523913D03*
X1521351Y1737117D03*
X1539134Y-35912D03*
Y-32512D03*
Y-25912D03*
Y-35912D03*
Y-32512D03*
X1530063Y-40911D03*
X1530064Y-27930D03*
X1530049Y-30445D03*
X1530033Y-35881D03*
X1530018Y-33366D03*
X1530048Y-38396D03*
X1533316Y-40925D03*
X1533317Y-27916D03*
X1536342Y-29236D03*
X1533302Y-30431D03*
X1541580Y-38849D03*
Y-28849D03*
X1536341Y-39605D03*
X1533301Y-38410D03*
X1539134Y-22512D03*
D03*
Y-25912D03*
X1530048Y-20028D03*
X1530063Y-17513D03*
X1530018Y-25058D03*
X1530033Y-22543D03*
X1533301Y-20014D03*
X1533316Y-17499D03*
X1536341Y-18819D03*
X1541580Y-19575D03*
X1528993Y4115D03*
Y26115D03*
X1538342Y28406D03*
X1540342Y48720D03*
X1535566Y69340D03*
X1538966D03*
X1543862Y75343D03*
X1539756Y71839D03*
X1534776D03*
X1539756Y66847D03*
X1534776D03*
X1532866Y69340D03*
X1541666D03*
X1535566D03*
X1538966D03*
X1537450Y226293D03*
X1533160Y231250D03*
X1536542Y300819D03*
X1536538Y296819D03*
X1536542Y308819D03*
X1539693Y535212D03*
X1542902Y543641D03*
X1532853Y560264D03*
X1532730Y562949D03*
X1534565Y564945D03*
X1534078Y699221D03*
X1533403Y702378D03*
X1540845Y701915D03*
X1536557Y711636D03*
X1534127D03*
X1538987Y717236D03*
Y711636D03*
X1534127Y717236D03*
X1536557D03*
X1540845Y704423D03*
X1536891Y703978D03*
X1534153Y704946D03*
X1543834Y708100D03*
X1530387Y711636D03*
X1535631Y721035D03*
X1533031D03*
X1538231Y723992D03*
X1540831D03*
X1538231Y727099D03*
X1540831D03*
X1530431D03*
X1533031Y723992D03*
X1535631D03*
X1533031Y727099D03*
X1535631D03*
X1543563Y757803D03*
X1543585Y762919D03*
X1543574Y760361D03*
X1538027Y766628D03*
X1540527D03*
X1540543Y776628D03*
Y774128D03*
Y771628D03*
Y769128D03*
X1538043Y776628D03*
Y769128D03*
Y771628D03*
Y774128D03*
X1538027Y784710D03*
Y779210D03*
X1540527D03*
X1538027Y781710D03*
X1540527D03*
X1539972Y807319D03*
X1529306Y1177468D03*
X1540801Y1178265D03*
X1537301D03*
X1539301Y1175765D03*
X1534317Y1216828D03*
X1532896Y1234836D03*
X1531227Y1227648D03*
X1540227D03*
X1542747Y1253602D03*
X1538587Y1245065D03*
X1540850Y1240863D03*
X1543772Y1241016D03*
X1543519Y1248205D03*
X1536916Y1240844D03*
X1531898Y1485895D03*
X1541898D03*
X1545298D03*
X1534498D03*
X1539298D03*
X1541208Y1483295D03*
X1532588D03*
X1541208Y1488495D03*
X1532588D03*
X1531898Y1485895D03*
X1541898D03*
X1543582Y1524562D03*
X1541191Y1544953D03*
Y1547453D03*
Y1549953D03*
X1539369Y1552250D03*
X1542767Y1564073D03*
X1541876Y1554436D03*
X1531167Y1577997D03*
Y1581397D03*
X1542186Y1581563D03*
X1534067Y1582178D03*
X1531167Y1577997D03*
Y1581397D03*
Y1583797D03*
X1544633Y1625380D03*
X1532573D03*
X1535973D03*
X1536751Y1622884D03*
X1531795D03*
X1532573Y1625380D03*
X1535973D03*
X1538603Y1635380D03*
X1542003D03*
X1530721Y1637876D03*
Y1632884D03*
X1537825Y1637876D03*
X1542781D03*
X1537825Y1632790D03*
X1542781D03*
X1531795Y1627876D03*
X1536751D03*
X1538603Y1635380D03*
X1529943D03*
X1542003D03*
Y1647292D03*
X1538603D03*
X1532573Y1657292D03*
X1535973D03*
X1544633D03*
X1531795Y1654796D03*
X1530721Y1649788D03*
X1536751Y1654796D03*
X1542781Y1649788D03*
X1537825D03*
X1530721Y1644796D03*
X1542781D03*
X1537825D03*
X1538603Y1647292D03*
X1529943D03*
X1542003D03*
X1531795Y1659788D03*
X1536751D03*
X1532573Y1657292D03*
X1535973D03*
X1543351Y1737117D03*
X1556379Y19541D03*
X1559779D03*
X1550965Y3001D03*
X1555568Y17045D03*
X1552674Y26477D03*
X1549274D03*
X1555568Y22037D03*
X1553601Y19541D03*
X1554510Y28406D03*
X1555452Y25977D03*
X1547424Y28406D03*
X1553452Y23981D03*
X1548496D03*
X1546496Y25977D03*
X1552674Y26477D03*
X1556379Y19541D03*
X1549274Y26477D03*
X1554520Y37106D03*
X1547434D03*
X1554510Y40020D03*
X1547424D03*
X1554520Y48720D03*
X1547434D03*
X1557566Y69340D03*
X1546562Y75343D03*
X1549962D03*
X1552662D03*
X1556776Y71839D03*
X1550756Y72850D03*
X1545776D03*
X1554866Y69340D03*
X1556776Y66847D03*
X1557566Y69340D03*
X1546562Y75343D03*
X1549962D03*
X1550756Y77842D03*
X1545776D03*
X1554360Y207251D03*
X1552981Y220826D03*
X1555481Y218326D03*
X1553913Y298119D03*
X1544489Y288816D03*
X1546789Y287116D03*
X1558480Y302678D03*
X1553154Y479063D03*
X1558198Y486791D03*
X1546149Y541169D03*
X1545960Y565162D03*
X1545987Y562012D03*
X1551887Y606938D03*
X1553657Y678965D03*
X1553827Y687991D03*
X1556027Y680391D03*
X1555893Y686261D03*
Y683361D03*
X1553657Y681965D03*
X1553727Y684991D03*
X1558194Y702166D03*
Y699209D03*
X1558657Y689696D03*
X1558194Y695501D03*
Y692501D03*
X1552347Y712897D03*
X1554947D03*
X1552347Y710297D03*
Y707697D03*
X1554947Y710297D03*
Y707697D03*
X1553597Y705197D03*
X1558617Y705143D03*
X1546114Y704575D03*
X1547607Y715490D03*
Y712949D03*
X1551250Y723840D03*
X1553750D03*
X1545557Y722897D03*
X1556555Y740617D03*
X1556544Y738059D03*
X1554055Y740617D03*
X1554044Y738059D03*
X1546965Y746119D03*
X1546954Y743561D03*
X1556708Y747282D03*
X1556688Y744688D03*
X1548119Y751952D03*
X1545619D03*
X1548119Y754832D03*
X1545619D03*
X1546063Y757803D03*
X1546085Y762919D03*
X1546074Y760361D03*
X1556708Y749782D03*
Y754782D03*
Y752282D03*
Y757282D03*
Y762282D03*
Y759782D03*
Y764782D03*
Y769782D03*
Y767282D03*
X1556121Y798542D03*
X1551124Y801289D03*
X1551961Y807269D03*
X1556361D03*
X1547561D03*
X1549877Y1217288D03*
Y1221288D03*
X1548360Y1234750D03*
X1550517Y1232905D03*
X1555570Y1235968D03*
X1555367Y1248078D03*
X1555303Y1242557D03*
X1545627Y1254068D03*
X1545480Y1245090D03*
X1544911Y1260654D03*
X1543980Y1258312D03*
X1547062Y1258468D03*
X1553811Y1264488D03*
X1554692Y1269688D03*
X1557559Y1269095D03*
X1557510Y1280291D03*
X1554377Y1278763D03*
X1553226Y1288814D03*
X1553548Y1284991D03*
X1556515Y1292232D03*
X1547195Y1478165D03*
X1547216Y1480812D03*
X1547898Y1485895D03*
X1545988Y1483295D03*
Y1488495D03*
X1545298Y1485895D03*
X1552668Y1513682D03*
Y1517082D03*
Y1511082D03*
Y1519682D03*
X1555268Y1512992D03*
Y1517772D03*
X1550068Y1512992D03*
Y1517772D03*
X1545473Y1522117D03*
X1547548Y1520070D03*
X1552668Y1513682D03*
Y1517082D03*
Y1530482D03*
Y1527082D03*
Y1533082D03*
Y1524482D03*
X1555268Y1531172D03*
Y1526392D03*
X1550068Y1531172D03*
Y1526392D03*
X1552668Y1530482D03*
Y1527082D03*
X1548132Y1542654D03*
X1551821Y1549120D03*
Y1545220D03*
X1551546Y1552845D03*
X1556071Y1547576D03*
X1554635Y1542469D03*
X1552135D03*
X1556071Y1545076D03*
X1545644Y1552845D03*
X1545521Y1549120D03*
Y1545220D03*
X1548671Y1549120D03*
Y1545220D03*
X1548684Y1556953D03*
X1555993Y1563595D03*
X1558493D03*
X1556847Y1559750D03*
X1545267Y1564073D03*
X1547767D03*
X1548684Y1554436D03*
X1552118Y1569763D03*
X1549618D03*
X1554093Y1582295D03*
Y1574795D03*
Y1579795D03*
Y1577295D03*
X1551593Y1582295D03*
Y1579795D03*
X1556593Y1582295D03*
Y1579795D03*
Y1574795D03*
Y1577295D03*
X1549093Y1579795D03*
Y1582295D03*
X1546593D03*
Y1579795D03*
X1558560Y1571682D03*
X1556060D03*
X1557633Y1584844D03*
X1556693Y1625380D03*
X1560093D03*
X1548033D03*
X1548811Y1622884D03*
X1543855D03*
X1555915D03*
X1544633Y1625380D03*
X1556693D03*
X1548033D03*
X1550663Y1635380D03*
X1554063D03*
X1549885Y1637876D03*
X1554841D03*
X1549885Y1632884D03*
X1554841D03*
X1543855Y1627876D03*
X1548811D03*
X1555915D03*
X1550663Y1635380D03*
X1554063D03*
X1550663Y1647292D03*
X1554063D03*
X1556693Y1657292D03*
X1548033D03*
X1560093D03*
X1543855Y1654796D03*
X1555915D03*
X1548811D03*
X1554841Y1649788D03*
X1549885D03*
X1554841Y1644796D03*
X1549885D03*
X1550663Y1647292D03*
X1554063D03*
X1543855Y1659788D03*
X1555915D03*
X1548811D03*
X1544633Y1657292D03*
X1556693D03*
X1548033D03*
X1570552Y19541D03*
X1573952D03*
X1572965Y3001D03*
X1569742Y17045D03*
X1560548D03*
X1566847Y26477D03*
X1563447D03*
X1567774Y19541D03*
X1569742Y22037D03*
X1560548D03*
X1561597Y28406D03*
X1562669Y23981D03*
X1568683Y28406D03*
X1567625Y23981D03*
X1560669Y25977D03*
X1569625D03*
X1562557Y19541D03*
X1566847Y26477D03*
X1559779Y19541D03*
X1570552D03*
X1563447Y26477D03*
X1561607Y37106D03*
X1568693D03*
X1568683Y40020D03*
X1561597D03*
X1568693Y48720D03*
X1561607D03*
X1571966Y75340D03*
X1568566D03*
X1560966Y69340D03*
X1572756Y72847D03*
X1561756Y71839D03*
X1565866Y75340D03*
X1567776Y72847D03*
X1561756Y66847D03*
X1563666Y69340D03*
X1568566Y75340D03*
X1571966D03*
X1560966Y69340D03*
X1572756Y77839D03*
X1567776D03*
X1572502Y254250D03*
X1572549Y257491D03*
X1564517Y299432D03*
X1566442Y294816D03*
X1564506Y313734D03*
X1571516Y319099D03*
X1568070Y497847D03*
X1573070D03*
X1570570D03*
X1570068Y534095D03*
X1573326Y543351D03*
X1573487Y546996D03*
X1568176Y568423D03*
X1570676D03*
X1565676D03*
X1561376Y572258D03*
X1572436Y578933D03*
X1568446Y582733D03*
X1564946D03*
X1561246Y580393D03*
X1568936Y585933D03*
Y589433D03*
X1565436Y585933D03*
Y589433D03*
X1562016Y584283D03*
Y587783D03*
X1572436Y589433D03*
Y585933D03*
X1566010Y673210D03*
X1567208Y677281D03*
X1562730Y675180D03*
X1566533Y680438D03*
X1567283Y683006D03*
X1572117Y695296D03*
X1568761Y702052D03*
X1571361D03*
X1568761Y699095D03*
X1566161Y702052D03*
Y699095D03*
X1569687Y689696D03*
X1572117D03*
X1567257D03*
Y695296D03*
X1569687D03*
X1563517Y689696D03*
X1561087D03*
X1563561Y705159D03*
X1561061D03*
X1568761D03*
X1571361D03*
X1566161D03*
X1572514Y747188D03*
X1561714D03*
X1559214D03*
X1561688Y744688D03*
X1559188D03*
X1572498D03*
X1572588Y757282D03*
Y759782D03*
X1561708Y757282D03*
X1559208D03*
X1561708Y759782D03*
X1559208D03*
X1561708Y762282D03*
X1559208D03*
X1572514Y752188D03*
Y749688D03*
Y754688D03*
X1561714Y749688D03*
Y752188D03*
X1559214D03*
Y749688D03*
X1561714Y754688D03*
X1559214D03*
X1561708Y769782D03*
X1559208D03*
X1561708Y767282D03*
X1559208D03*
X1561708Y764782D03*
X1559208D03*
X1562995Y789522D03*
X1569518Y806684D03*
X1570583Y800104D03*
X1572668Y806778D03*
X1564267Y1253158D03*
X1561927Y1269901D03*
X1568660Y1283460D03*
X1559181Y1287165D03*
X1568100Y1290418D03*
X1567000Y1293446D03*
X1562820Y1309360D03*
X1572036Y1306083D03*
X1562937Y1341609D03*
X1566901Y1347726D03*
X1564758Y1367834D03*
X1572906Y1366759D03*
X1563967Y1363205D03*
X1573560Y1485895D03*
X1573550Y1492995D03*
X1568770D03*
X1572860Y1495595D03*
X1569460D03*
X1566860D03*
X1573550Y1498195D03*
X1568770D03*
X1572860Y1495595D03*
X1569460D03*
X1563222Y1516590D03*
Y1513190D03*
Y1519190D03*
Y1510590D03*
X1560622Y1517280D03*
Y1512500D03*
X1565822Y1517280D03*
Y1512500D03*
X1563222Y1516590D03*
Y1513190D03*
Y1534990D03*
Y1538390D03*
Y1532490D03*
X1560622Y1534300D03*
X1565822D03*
X1572230Y1533000D03*
X1563222Y1534990D03*
X1560622Y1539080D03*
X1565822D03*
X1563222Y1540990D03*
X1573597Y1543800D03*
Y1547420D03*
Y1551040D03*
X1563222Y1538390D03*
X1564581Y1562316D03*
X1562613Y1564816D03*
X1564839Y1554561D03*
X1567089Y1563596D03*
X1562640Y1556331D03*
Y1559731D03*
X1564128Y1572225D03*
X1562621Y1569761D03*
X1559093Y1577295D03*
Y1574795D03*
X1565963D03*
X1568463D03*
X1565963Y1577295D03*
X1568463D03*
Y1579795D03*
X1565963D03*
X1568463Y1582295D03*
X1565963D03*
X1570963Y1574795D03*
Y1582295D03*
Y1579795D03*
Y1577295D03*
X1563463Y1574795D03*
Y1582295D03*
Y1579795D03*
Y1577295D03*
X1560051Y1581199D03*
X1562556Y1584844D03*
X1560051Y1584099D03*
X1572153Y1625380D03*
X1568753D03*
X1560871Y1622884D03*
X1572931D03*
X1567975D03*
X1568753Y1625380D03*
X1560093D03*
X1572153D03*
X1562723Y1635380D03*
X1566123D03*
X1574783D03*
X1561945Y1637876D03*
Y1632884D03*
X1566901Y1637876D03*
Y1632884D03*
X1560871Y1627876D03*
X1572931D03*
X1567975D03*
X1562723Y1635380D03*
X1566123D03*
X1574783Y1647292D03*
X1562723D03*
X1566123D03*
X1568753Y1657292D03*
X1572153D03*
X1560871Y1654796D03*
X1561945Y1649788D03*
X1567975Y1654796D03*
X1572931D03*
X1566901Y1649788D03*
X1561945Y1644796D03*
X1566901D03*
X1562723Y1647292D03*
X1566123D03*
X1560871Y1659788D03*
X1567975D03*
X1572931D03*
X1568753Y1657292D03*
X1560093D03*
X1572153D03*
X1565351Y1737117D03*
X1588125Y19541D03*
X1584725D03*
X1583915Y17045D03*
X1574722D03*
X1581020Y26477D03*
X1577620D03*
X1581947Y19541D03*
X1583915Y22037D03*
X1576730Y19541D03*
X1574722Y22037D03*
X1575770Y28406D03*
X1576842Y23981D03*
X1582857Y28406D03*
X1581798Y23981D03*
X1574842Y25977D03*
X1583798D03*
X1588125Y19541D03*
X1581020Y26477D03*
X1573952Y19541D03*
X1584725D03*
X1577620Y26477D03*
X1575780Y37106D03*
X1582867D03*
X1582857Y40020D03*
X1575770D03*
X1582867Y48720D03*
X1575780D03*
X1590566Y75340D03*
X1579566Y69340D03*
X1582966D03*
X1587866Y75340D03*
X1574666D03*
X1578776Y71839D03*
X1583756D03*
X1576866Y69340D03*
X1578776Y66847D03*
X1583756D03*
X1585666Y69340D03*
X1579566D03*
X1582966D03*
X1574546Y251294D03*
X1586291Y306746D03*
Y303596D03*
X1586621Y484304D03*
X1580519Y497650D03*
X1575570Y497847D03*
X1579748Y536344D03*
X1584160Y558973D03*
X1584397Y655622D03*
X1586497Y651222D03*
X1586597Y654222D03*
X1584397Y652722D03*
Y649822D03*
X1579807Y671268D03*
X1586367Y671428D03*
X1587717Y676528D03*
Y673928D03*
X1585117Y676528D03*
Y673928D03*
Y679128D03*
X1587717D03*
X1573975Y679975D03*
X1579244Y682635D03*
X1573975Y682483D03*
X1576964Y686160D03*
X1578757Y700965D03*
X1573961Y702052D03*
X1586070Y696830D03*
Y694330D03*
X1580737Y693550D03*
Y691009D03*
X1573961Y705159D03*
X1578904Y721340D03*
Y723840D03*
X1577588Y747282D03*
X1575014Y747188D03*
X1577498Y744688D03*
X1574998D03*
X1575088Y757282D03*
X1577588Y749782D03*
Y754782D03*
Y752282D03*
X1575014Y749688D03*
Y752188D03*
Y754688D03*
X1584849Y793506D03*
X1575370Y1252770D03*
X1581327Y1252858D03*
X1586835Y1271918D03*
X1578690Y1283310D03*
X1574168Y1283300D03*
X1577077Y1270937D03*
X1580577D03*
X1584068Y1271198D03*
X1583007Y1288958D03*
X1580010Y1296100D03*
X1574560Y1296410D03*
X1580520Y1289900D03*
X1586167Y1295478D03*
X1575024Y1306373D03*
X1587028Y1307137D03*
X1586557Y1304509D03*
X1577913Y1341623D03*
X1575504Y1356103D03*
X1578336D03*
Y1359253D03*
X1578411Y1348623D03*
X1578020Y1344773D03*
X1579560Y1485895D03*
X1576160D03*
X1582160D03*
X1575470Y1483295D03*
X1580250D03*
X1575470Y1488495D03*
X1580250D03*
X1579560Y1485895D03*
X1576160D03*
X1589560Y1505295D03*
X1586960D03*
X1575460Y1495595D03*
X1574089Y1561731D03*
X1588363Y1577997D03*
Y1581397D03*
X1576653Y1579333D03*
X1588363Y1577997D03*
Y1581397D03*
Y1583797D03*
X1580813Y1625380D03*
X1584213D03*
X1584991Y1622884D03*
X1580035D03*
X1580813Y1625380D03*
X1584213D03*
X1586843Y1635380D03*
X1578183D03*
X1590243D03*
X1574005Y1637876D03*
Y1632884D03*
X1578961Y1637876D03*
Y1632884D03*
X1586065Y1637876D03*
Y1632884D03*
X1580035Y1627876D03*
X1584991D03*
X1586843Y1635380D03*
X1574783D03*
X1578183D03*
X1586843Y1647292D03*
X1590243D03*
X1578183D03*
X1580813Y1657292D03*
X1584213D03*
X1574005Y1649788D03*
X1580035Y1654796D03*
X1578961Y1649788D03*
X1584991Y1654796D03*
X1586065Y1649788D03*
X1574005Y1644796D03*
X1578961D03*
X1586065D03*
X1586843Y1647292D03*
X1574783D03*
X1578183D03*
X1580035Y1659788D03*
X1584991D03*
X1580813Y1657292D03*
X1584213D03*
X1587351Y1737117D03*
X1602299Y19541D03*
X1598899D03*
X1594965Y3001D03*
X1603072Y17045D03*
X1598092D03*
X1588895D03*
X1595194Y26477D03*
X1591794D03*
X1603072Y22037D03*
X1598092D03*
X1596121Y19541D03*
X1590903D03*
X1588895Y22037D03*
X1589943Y28406D03*
X1595972Y23981D03*
X1591016D03*
X1597030Y28406D03*
X1589016Y25977D03*
X1597972D03*
X1602299Y19541D03*
X1595194Y26477D03*
X1598899Y19541D03*
X1591794Y26477D03*
X1589953Y37106D03*
X1597040D03*
X1597030Y40020D03*
X1589943D03*
X1597040Y48720D03*
X1589953D03*
X1601562Y69343D03*
X1604962D03*
X1593966Y75340D03*
X1589776Y72847D03*
X1594756D03*
X1596666Y75340D03*
X1600776Y71842D03*
X1598866Y69343D03*
X1600776Y66850D03*
X1590566Y75340D03*
X1601562Y69343D03*
X1593966Y75340D03*
X1589776Y77839D03*
X1594756D03*
X1593303Y234250D03*
Y239250D03*
X1602270Y229530D03*
X1598303Y234250D03*
X1596462Y229790D03*
X1593658Y252010D03*
X1593303Y244250D03*
X1593349Y248160D03*
X1597481Y271991D03*
X1600918Y521688D03*
X1593214Y531226D03*
X1597562Y555463D03*
X1595036D03*
X1591962D03*
X1589436D03*
X1599978Y643512D03*
X1600027Y655927D03*
X1602457D03*
X1599303Y646669D03*
X1602791Y648269D03*
X1600053Y649237D03*
X1596287Y655927D03*
X1591427D03*
X1593857D03*
X1588663Y649592D03*
Y652492D03*
X1591387Y671374D03*
X1593831Y671390D03*
X1596331D03*
X1601531D03*
Y668283D03*
Y665326D03*
X1598931Y671390D03*
Y668283D03*
Y665326D03*
X1600027Y661527D03*
X1602457D03*
X1590964Y668397D03*
Y665440D03*
Y661741D03*
Y658741D03*
X1594844Y713419D03*
Y715919D03*
X1592344D03*
Y713419D03*
X1594818Y710919D03*
X1594844Y718419D03*
X1592344D03*
X1594844Y720919D03*
X1592344D03*
X1594688Y723512D03*
Y726012D03*
Y728512D03*
Y731012D03*
X1592188Y723512D03*
Y726012D03*
Y728512D03*
Y731012D03*
X1594688Y736012D03*
X1592188D03*
X1594688Y733512D03*
X1592188D03*
X1594900Y780112D03*
X1589557Y1252778D03*
X1590097Y1246768D03*
X1598467Y1267539D03*
X1588832Y1269083D03*
X1597177Y1282288D03*
X1594152Y1282578D03*
X1598883Y1270766D03*
X1590827Y1271378D03*
X1593397Y1271458D03*
X1596273Y1271472D03*
X1594539Y1295288D03*
X1591005Y1288892D03*
X1596363Y1286296D03*
X1603507Y1306262D03*
X1599241Y1306622D03*
X1589845Y1305289D03*
X1599007Y1309762D03*
X1601772Y1337293D03*
X1601959Y1351773D03*
X1595438Y1370603D03*
X1599139Y1400464D03*
X1600531Y1404710D03*
X1597992Y1433183D03*
X1595716Y1431861D03*
X1602782Y1435920D03*
X1600442Y1434535D03*
X1602960Y1485895D03*
X1595570Y1492995D03*
X1600350D03*
X1602270Y1483295D03*
X1600360Y1485895D03*
X1602270Y1488495D03*
X1602960Y1485895D03*
X1592960Y1505295D03*
X1599660Y1495595D03*
X1596260D03*
X1595560Y1505295D03*
X1602260Y1495595D03*
X1593660D03*
X1595570Y1498195D03*
X1600350D03*
X1588870Y1502695D03*
X1593650D03*
X1588870Y1507895D03*
X1593650D03*
X1592960Y1505295D03*
X1599660Y1495595D03*
X1589560Y1505295D03*
X1596260Y1495595D03*
X1593087Y1577997D03*
X1597812D03*
X1602536D03*
X1593087Y1581397D03*
X1597812D03*
X1602536D03*
X1593087Y1577997D03*
X1597812D03*
X1602536D03*
X1593087Y1581397D03*
X1597812D03*
X1602536D03*
X1593087Y1583797D03*
X1597812Y1583897D03*
X1602536Y1583697D03*
X1604933Y1625380D03*
X1592873D03*
X1596273D03*
X1597051Y1622884D03*
X1592095D03*
X1592873Y1625380D03*
X1596273D03*
X1598903Y1635380D03*
X1602303D03*
X1591021Y1637876D03*
Y1632884D03*
X1598125Y1637876D03*
X1603081D03*
X1598125Y1632884D03*
X1603081D03*
X1592095Y1627876D03*
X1597051D03*
X1598903Y1635380D03*
X1590243D03*
X1602303D03*
Y1647292D03*
X1598903D03*
X1592873Y1657292D03*
X1596273D03*
X1604933D03*
X1592095Y1654796D03*
X1591021Y1649788D03*
X1597051Y1654796D03*
X1603081Y1649788D03*
X1598125D03*
X1591021Y1644796D03*
X1603081D03*
X1598125D03*
X1598903Y1647292D03*
X1590243D03*
X1602303D03*
X1592095Y1659788D03*
X1597051D03*
X1592873Y1657292D03*
X1596273D03*
X1616965Y3001D03*
X1605077Y19541D03*
X1604117Y28406D03*
X1604127Y37106D03*
X1604117Y40020D03*
X1604127Y48720D03*
X1615966Y75340D03*
X1612566D03*
X1609866D03*
X1611776Y72847D03*
X1616756D03*
X1607666Y69343D03*
X1605756Y71842D03*
Y66850D03*
X1612566Y75340D03*
X1615966D03*
X1604962Y69343D03*
X1611776Y77839D03*
X1616756D03*
X1615020Y183050D03*
X1612144Y418552D03*
X1614701Y422587D03*
X1616464Y457509D03*
X1616250Y465042D03*
X1609166Y527300D03*
X1611775D03*
X1609166Y524700D03*
X1611775D03*
X1613169Y531819D03*
X1604991Y536344D03*
X1606535Y553297D03*
X1609355Y592794D03*
X1618356Y612137D03*
X1618434Y605753D03*
X1609044Y600986D03*
X1608640Y640660D03*
X1617397Y630822D03*
Y636622D03*
Y633722D03*
X1615677Y648488D03*
X1604887Y655927D03*
X1618117Y657528D03*
Y654928D03*
X1606745Y646206D03*
X1612014Y648866D03*
X1606745Y648714D03*
X1613507Y657240D03*
X1609734Y652391D03*
X1611557Y667165D03*
X1606731Y671390D03*
Y668283D03*
X1604131Y671390D03*
Y668283D03*
X1604887Y661527D03*
X1618117Y660128D03*
X1613507Y659781D03*
X1613154Y688238D03*
Y690738D03*
X1605644Y715919D03*
Y713419D03*
X1608144D03*
Y715919D03*
X1605628Y710919D03*
X1608128D03*
X1610628D03*
X1610718Y713513D03*
Y716013D03*
X1605644Y718419D03*
Y720919D03*
X1608144Y718419D03*
Y720919D03*
X1610718Y721013D03*
Y718513D03*
X1608118Y723512D03*
X1605618D03*
X1608118Y726012D03*
X1605618D03*
X1610618Y723512D03*
X1605618Y728512D03*
X1607267Y1271978D03*
X1604137Y1271358D03*
X1605801Y1286168D03*
X1605447Y1288748D03*
X1608901Y1285887D03*
X1605360Y1294595D03*
X1608652Y1303338D03*
X1608341Y1313269D03*
X1608418Y1333589D03*
Y1331089D03*
X1614767Y1443512D03*
X1605648Y1437305D03*
X1606360Y1485895D03*
X1607050Y1483295D03*
X1608960Y1485895D03*
X1607050Y1488495D03*
X1606360Y1485895D03*
X1619760Y1505295D03*
X1616360D03*
X1613760D03*
X1615670Y1502695D03*
Y1507895D03*
X1616360Y1505295D03*
X1607261Y1577997D03*
X1611985D03*
X1616710D03*
X1607261Y1581397D03*
X1611985D03*
X1616710D03*
X1607261Y1577997D03*
X1611985D03*
X1616710D03*
X1607261Y1581397D03*
X1611985D03*
X1616710D03*
X1607261Y1583897D03*
X1611985D03*
X1616710Y1583697D03*
X1616993Y1625380D03*
X1620393D03*
X1608333D03*
X1609111Y1622884D03*
X1604155D03*
X1616215D03*
X1604933Y1625380D03*
X1616993D03*
X1608333D03*
X1610963Y1635380D03*
X1614363D03*
X1610185Y1637876D03*
X1615141D03*
X1610185Y1632884D03*
X1615141D03*
X1604155Y1627876D03*
X1609111D03*
X1616215D03*
X1610963Y1635380D03*
X1614363D03*
X1610963Y1647292D03*
X1614363D03*
X1616993Y1657292D03*
X1608333D03*
X1620393D03*
X1604155Y1654796D03*
X1616215D03*
X1609111D03*
X1615141Y1649788D03*
X1610185D03*
X1615141Y1644796D03*
X1610185D03*
X1610963Y1647292D03*
X1614363D03*
X1604155Y1659788D03*
X1616215D03*
X1609111D03*
X1604933Y1657292D03*
X1616993D03*
X1608333D03*
X1609351Y1737117D03*
X1634765Y19541D03*
X1631060Y26477D03*
X1627660D03*
X1631987Y19541D03*
X1632896Y28406D03*
X1625809D03*
X1626882Y23981D03*
X1631838D03*
X1624882Y25977D03*
X1622329Y28261D03*
X1631060Y26477D03*
X1627660D03*
X1632906Y37106D03*
X1625819D03*
X1632896Y40020D03*
X1625809D03*
X1632906Y48720D03*
X1625819D03*
X1623189D03*
X1623562Y69343D03*
X1626962D03*
X1629662D03*
X1633070Y75340D03*
X1618666D03*
X1627756Y71842D03*
X1622776D03*
X1627756Y66850D03*
X1622776D03*
X1620862Y69343D03*
X1623562D03*
X1626962D03*
X1631200Y164110D03*
X1627410Y172008D03*
X1631455Y167875D03*
X1627152Y168920D03*
X1629597Y227157D03*
X1627156Y238303D03*
X1627986Y282728D03*
X1627909Y286742D03*
Y298742D03*
Y294742D03*
Y290742D03*
X1619909Y306746D03*
Y303596D03*
X1627909Y302742D03*
X1621680Y366920D03*
X1632500Y381500D03*
X1625000Y383399D03*
X1630927Y398002D03*
X1631889Y521480D03*
X1618884Y533388D03*
X1632798Y544564D03*
X1631558Y588513D03*
X1628756Y588591D03*
X1624067Y588474D03*
X1621187Y588591D03*
X1632012Y603015D03*
X1621512D03*
X1625012D03*
X1628512D03*
X1632978Y624512D03*
X1632303Y627669D03*
X1633027Y636927D03*
Y642527D03*
X1633053Y630237D03*
X1626857Y636927D03*
X1629287D03*
X1624427D03*
X1621663Y630592D03*
X1619597Y635222D03*
X1621663Y633492D03*
X1619497Y632222D03*
X1623964Y642741D03*
Y639741D03*
X1620717Y657528D03*
X1631931Y652390D03*
Y649283D03*
X1626831Y652390D03*
X1629331D03*
X1631931Y646326D03*
X1624387Y652374D03*
X1619367Y652428D03*
X1620717Y654928D03*
X1623964Y649397D03*
Y646440D03*
X1621050Y671768D03*
X1623550D03*
X1620717Y660128D03*
X1627643Y694419D03*
Y696919D03*
Y699419D03*
X1625143D03*
Y696919D03*
Y694419D03*
X1627643Y701919D03*
X1625143D03*
X1627617Y691919D03*
X1625117D03*
Y709512D03*
Y704512D03*
Y707012D03*
Y712012D03*
X1627617Y709512D03*
Y704512D03*
Y707012D03*
Y712012D03*
X1628046Y756765D03*
Y760265D03*
X1618996Y760177D03*
Y756831D03*
X1628046Y767265D03*
X1623496Y776910D03*
X1628046Y763765D03*
X1618946Y763524D03*
X1628946Y790296D03*
X1623496Y783603D03*
X1627896Y795315D03*
X1628946Y800335D03*
X1623496Y807028D03*
Y813721D03*
Y820414D03*
X1627896Y832126D03*
X1628946Y827107D03*
Y837146D03*
X1623496Y843839D03*
Y850532D03*
X1628946Y863918D03*
X1623496Y857225D03*
X1627896Y868937D03*
X1628946Y873957D03*
X1623496Y880650D03*
Y887343D03*
Y894036D03*
X1627896Y905749D03*
X1628946Y900729D03*
Y910768D03*
X1623496Y917461D03*
Y924154D03*
X1628946Y937540D03*
X1623496Y930847D03*
X1627896Y942560D03*
X1628946Y947579D03*
X1623496Y954272D03*
Y960965D03*
Y967658D03*
Y974351D03*
Y981044D03*
Y987736D03*
Y994429D03*
Y1004469D03*
Y1034587D03*
Y1041280D03*
Y1047973D03*
Y1054666D03*
Y1061359D03*
Y1071398D03*
X1627896Y1089804D03*
X1628946Y1084784D03*
X1623496Y1078091D03*
X1628946Y1094823D03*
X1623496Y1101516D03*
Y1108209D03*
Y1114902D03*
X1627896Y1126615D03*
X1628946Y1121595D03*
Y1131634D03*
X1623496Y1138327D03*
Y1145020D03*
X1627896Y1163426D03*
X1628946Y1158406D03*
X1623496Y1151713D03*
X1628946Y1168445D03*
X1623496Y1175138D03*
Y1181831D03*
Y1188524D03*
X1627896Y1200237D03*
X1628946Y1195217D03*
Y1205256D03*
X1623496Y1211949D03*
Y1218642D03*
X1627896Y1237048D03*
X1628946Y1232028D03*
X1623496Y1225335D03*
X1628946Y1242067D03*
X1623496Y1248760D03*
Y1255453D03*
X1626928Y1260917D03*
X1629428D03*
X1631928D03*
X1626333Y1311091D03*
Y1308091D03*
X1627052Y1424716D03*
X1627174Y1420450D03*
X1625285Y1433384D03*
X1627217Y1428366D03*
X1627242Y1436148D03*
X1627181Y1448016D03*
X1622697Y1440797D03*
X1625170Y1444016D03*
X1633160Y1485895D03*
X1629760D03*
X1627160D03*
X1629070Y1483295D03*
Y1488495D03*
X1622370Y1492995D03*
X1627150D03*
X1633160Y1485895D03*
X1629760D03*
X1626460Y1495595D03*
X1623060D03*
X1629060D03*
X1620460D03*
X1622360Y1505295D03*
X1622370Y1498195D03*
X1627150D03*
X1620450Y1502695D03*
Y1507895D03*
X1619760Y1505295D03*
X1626460Y1495595D03*
X1623060D03*
X1621434Y1577997D03*
X1626159D03*
X1630883D03*
X1621434Y1581397D03*
X1626159D03*
X1630883D03*
X1621434Y1577997D03*
X1626159D03*
X1630883D03*
X1621434Y1581397D03*
X1626159D03*
X1630883D03*
X1621434Y1583797D03*
X1626159Y1583897D03*
X1630883D03*
X1632453Y1625380D03*
X1629053D03*
X1621171Y1622884D03*
X1628275D03*
X1629053Y1625380D03*
X1620393D03*
X1632453D03*
X1623023Y1635380D03*
X1626423D03*
X1635083D03*
X1622245Y1637876D03*
Y1632884D03*
X1627201Y1637876D03*
Y1632884D03*
X1621171Y1627876D03*
X1628275D03*
X1623023Y1635380D03*
X1626423D03*
X1635083Y1647292D03*
X1623023D03*
X1626423D03*
X1629053Y1657292D03*
X1632453D03*
X1621171Y1654796D03*
X1622245Y1649788D03*
X1628275Y1654796D03*
X1627201Y1649788D03*
X1622245Y1644796D03*
X1627201D03*
X1623023Y1647292D03*
X1626423D03*
X1621171Y1659788D03*
X1628275D03*
X1629053Y1657292D03*
X1620393D03*
X1632453D03*
X1631351Y1737117D03*
X1638165Y19541D03*
X1648938D03*
X1638965Y3001D03*
X1648128Y17045D03*
X1633954D03*
X1638934D03*
X1645233Y26477D03*
X1641833D03*
X1648128Y22037D03*
X1647069Y28406D03*
X1648011Y25977D03*
X1633954Y22037D03*
X1638934D03*
X1646160Y19541D03*
X1640943D03*
X1639983Y28406D03*
X1641055Y23981D03*
X1646011D03*
X1639055Y25977D03*
X1633838D03*
X1645233Y26477D03*
X1638165Y19541D03*
X1641833Y26477D03*
X1634765Y19541D03*
X1647079Y37106D03*
X1639993D03*
X1647069Y40020D03*
X1639983D03*
X1647079Y48720D03*
X1639993D03*
X1646770Y69340D03*
X1650170D03*
X1635770Y75340D03*
X1639170D03*
X1634980Y72847D03*
X1639960D03*
X1641870Y75340D03*
X1645980Y71839D03*
X1644070Y69340D03*
X1645980Y66847D03*
X1646770Y69340D03*
X1635770Y75340D03*
X1639170D03*
X1634980Y77839D03*
X1639960D03*
X1636047Y224597D03*
Y229912D03*
X1642240Y399603D03*
X1647310Y408922D03*
Y411422D03*
X1639800Y426982D03*
X1636800D03*
X1639800Y429982D03*
X1636800D03*
X1639800Y432982D03*
X1636800D03*
X1639800Y435982D03*
X1636800D03*
X1639800Y438982D03*
X1636800D03*
X1636929Y524690D03*
Y528190D03*
Y531690D03*
Y535190D03*
Y538690D03*
X1639868Y542444D03*
X1636783Y542604D03*
X1635798Y545564D03*
X1638798D03*
Y548964D03*
Y552164D03*
X1635798D03*
Y548964D03*
Y555364D03*
X1638798D03*
X1635798Y558364D03*
X1635697Y561253D03*
X1635944Y612510D03*
X1636022Y606126D03*
X1647158Y618971D03*
X1639745Y627206D03*
X1637887Y642527D03*
Y636927D03*
X1635457D03*
Y642527D03*
X1646507Y640781D03*
X1645014Y629866D03*
X1639745Y629714D03*
X1635791Y629269D03*
X1646507Y638240D03*
X1642734Y633391D03*
X1644457Y648265D03*
X1639731Y652390D03*
X1634531D03*
X1637131D03*
X1639731Y649283D03*
X1634531D03*
X1637131D03*
X1634531Y646326D03*
X1638443Y699419D03*
Y696919D03*
Y694419D03*
Y701919D03*
X1640943Y694419D03*
Y696919D03*
Y699419D03*
Y701919D03*
X1643517Y702013D03*
Y699513D03*
Y694513D03*
Y697013D03*
X1643427Y691919D03*
X1640927D03*
X1638427D03*
X1640877Y706972D03*
Y709472D03*
X1638377D03*
Y704472D03*
Y706972D03*
X1640877Y704472D03*
X1643377Y709510D03*
Y704510D03*
Y707010D03*
X1640877Y711972D03*
X1638377D03*
X1643377Y712010D03*
X1635088Y756765D03*
X1644138Y756831D03*
X1635088Y763765D03*
X1639638Y773563D03*
X1635088Y767205D03*
Y771005D03*
X1644138Y763524D03*
X1644188Y770217D03*
X1644038Y791969D03*
X1634188Y786949D03*
X1639638Y780256D03*
X1634188Y796988D03*
X1639638Y803681D03*
Y810374D03*
Y817067D03*
X1644038Y828780D03*
X1634188Y823760D03*
Y833799D03*
X1639638Y840492D03*
Y847185D03*
X1644038Y865591D03*
X1634188Y860571D03*
X1639638Y853878D03*
X1634188Y870610D03*
X1639638Y877303D03*
Y883996D03*
Y890689D03*
X1644038Y902402D03*
X1634188Y897382D03*
Y907422D03*
X1639638Y914114D03*
Y920807D03*
X1644038Y939213D03*
X1634188Y934193D03*
X1639638Y927500D03*
X1634188Y944233D03*
X1639638Y950925D03*
Y957618D03*
Y964311D03*
Y971004D03*
Y960965D03*
X1634138D03*
X1639638Y977697D03*
Y984390D03*
Y991083D03*
Y997776D03*
Y1004469D03*
Y1031240D03*
Y1037933D03*
Y1044626D03*
Y1051319D03*
Y1058012D03*
Y1068051D03*
Y1074744D03*
X1644038Y1086457D03*
X1634188Y1081437D03*
Y1091477D03*
X1639638Y1098170D03*
Y1104862D03*
X1634188Y1118248D03*
X1639638Y1111555D03*
X1644038Y1123268D03*
X1634188Y1128288D03*
X1639638Y1134981D03*
Y1141674D03*
Y1148366D03*
X1644038Y1160079D03*
X1634188Y1155059D03*
Y1165099D03*
X1639638Y1171792D03*
Y1178485D03*
X1634188Y1191870D03*
X1639638Y1185177D03*
X1644038Y1196890D03*
X1634188Y1201910D03*
X1639638Y1208603D03*
Y1215296D03*
Y1221988D03*
X1644038Y1233701D03*
X1634188Y1228681D03*
Y1238721D03*
X1639638Y1245414D03*
Y1252107D03*
X1634428Y1260917D03*
X1645163Y1276184D03*
X1641677Y1341488D03*
X1641904Y1351467D03*
Y1348567D03*
X1641677Y1344488D03*
X1641087Y1396118D03*
X1641065Y1403393D03*
Y1406393D03*
X1643283Y1425541D03*
X1643183Y1419441D03*
X1643283Y1431541D03*
X1645979Y1437950D03*
X1635760Y1485895D03*
X1633850Y1483295D03*
Y1488495D03*
X1646560Y1505295D03*
X1649860Y1495595D03*
X1643160Y1505295D03*
X1647260Y1495595D03*
X1640560Y1505295D03*
X1647250Y1502695D03*
X1642470D03*
X1647250Y1507895D03*
X1642470D03*
X1646560Y1505295D03*
X1643160D03*
X1635608Y1577997D03*
X1640332D03*
X1645056D03*
X1635608Y1581397D03*
X1640332D03*
X1645056D03*
X1649780Y1577997D03*
Y1581397D03*
X1635608Y1577997D03*
X1640332D03*
X1645056D03*
X1635608Y1581397D03*
X1640332D03*
X1645056D03*
X1640332Y1583897D03*
X1645056Y1583697D03*
X1635608Y1583897D03*
X1641113Y1625380D03*
X1644513D03*
X1633231Y1622884D03*
X1645291D03*
X1640335D03*
X1641113Y1625380D03*
X1644513D03*
X1647143Y1635380D03*
X1638483D03*
X1634305Y1637876D03*
Y1632790D03*
X1639261Y1637876D03*
Y1632790D03*
X1646365Y1637876D03*
Y1632884D03*
X1633231Y1627876D03*
X1640335D03*
X1645291D03*
X1635083Y1635380D03*
X1647143D03*
X1638483D03*
X1647143Y1647292D03*
X1638483D03*
X1641113Y1657292D03*
X1644513D03*
X1633231Y1654796D03*
X1634305Y1649788D03*
X1640335Y1654796D03*
X1639261Y1649788D03*
X1645291Y1654796D03*
X1646365Y1649788D03*
X1634305Y1644796D03*
X1639261D03*
X1646365D03*
X1635083Y1647292D03*
X1647143D03*
X1638483D03*
X1633231Y1659788D03*
X1640335D03*
X1645291D03*
X1641113Y1657292D03*
X1644513D03*
X1647700Y1674228D03*
X1646879Y1681738D03*
X1648013Y1713684D03*
X1648029Y1708609D03*
X1648013Y1728834D03*
X1648029Y1718759D03*
Y1723759D03*
Y1733909D03*
X1652338Y19541D03*
X1660965Y3001D03*
X1653108Y17045D03*
X1655116Y19541D03*
X1653108Y22037D03*
X1654156Y28406D03*
X1652338Y19541D03*
X1648938D03*
X1654166Y37106D03*
X1654156Y40020D03*
X1654166Y48720D03*
X1661166Y75343D03*
X1657766D03*
X1650960Y66847D03*
X1652870Y69340D03*
X1655066Y75343D03*
X1662065Y72850D03*
X1656980D03*
X1650960Y71839D03*
X1657766Y75343D03*
X1661166D03*
X1650170Y69340D03*
X1662065Y77842D03*
X1656980D03*
X1652525Y146762D03*
Y151762D03*
Y161762D03*
X1650023Y221842D03*
X1654419Y224597D03*
X1659419D03*
X1654419Y233062D03*
X1650023Y227157D03*
X1654419Y229912D03*
X1661928Y230172D03*
X1652610Y394727D03*
X1659610D03*
X1652810Y407402D03*
X1650020Y408952D03*
Y411452D03*
X1657545Y434506D03*
X1650035Y434750D03*
X1660194Y609450D03*
X1654194D03*
X1660194Y599956D03*
X1654194D03*
X1650917Y657528D03*
Y654928D03*
X1653517Y657528D03*
X1652167Y652428D03*
X1653517Y654928D03*
X1648604Y671768D03*
X1650917Y660128D03*
X1659618Y659021D03*
X1662298D03*
X1651104Y671768D03*
X1653517Y660128D03*
X1656938Y659021D03*
X1651959Y689800D03*
X1662377Y696300D03*
Y693300D03*
X1657747Y756765D03*
Y760265D03*
X1648697Y760177D03*
Y756831D03*
X1657747Y767265D03*
X1653197Y776910D03*
X1657747Y763765D03*
X1648647Y766870D03*
Y763524D03*
X1653197Y780256D03*
Y786949D03*
Y793642D03*
X1658647Y790296D03*
X1653197Y783603D03*
Y780256D03*
Y786949D03*
Y803681D03*
Y796988D03*
X1657597Y795315D03*
X1658647Y800335D03*
X1653197Y807028D03*
Y803681D03*
Y793642D03*
Y796988D03*
Y817067D03*
Y810374D03*
Y823760D03*
Y813721D03*
Y820414D03*
Y817067D03*
Y810374D03*
Y830453D03*
Y833799D03*
X1657597Y832126D03*
X1658647Y827107D03*
Y837146D03*
X1653197Y823760D03*
Y830453D03*
Y833799D03*
Y840492D03*
Y847185D03*
Y853878D03*
Y843839D03*
Y850532D03*
Y840492D03*
Y847185D03*
Y860571D03*
Y867264D03*
X1658647Y863918D03*
X1653197Y857225D03*
Y853878D03*
Y860571D03*
Y877303D03*
Y870610D03*
Y883996D03*
X1657597Y868937D03*
X1658647Y873957D03*
X1653197Y880650D03*
Y877303D03*
Y867264D03*
Y870610D03*
Y890689D03*
Y897382D03*
Y887343D03*
Y894036D03*
Y883996D03*
Y890689D03*
Y904075D03*
Y907422D03*
X1657597Y905749D03*
X1658647Y900729D03*
Y910768D03*
X1653197Y897382D03*
Y904075D03*
Y907422D03*
Y914114D03*
Y920807D03*
Y927500D03*
Y917461D03*
Y924154D03*
Y914114D03*
Y920807D03*
Y934193D03*
Y940886D03*
X1658647Y937540D03*
X1653197Y930847D03*
Y927500D03*
Y934193D03*
Y940886D03*
Y950925D03*
Y944233D03*
Y957618D03*
X1657597Y942560D03*
X1658647Y947579D03*
X1653197Y954272D03*
Y950925D03*
Y944233D03*
X1663839Y960965D03*
X1653197Y964311D03*
Y971004D03*
Y960965D03*
Y967658D03*
Y964311D03*
Y957618D03*
Y971004D03*
Y977697D03*
Y984390D03*
Y974351D03*
Y981044D03*
Y977697D03*
Y984390D03*
Y1001122D03*
Y997776D03*
Y991083D03*
Y987736D03*
Y994429D03*
Y1001122D03*
Y997776D03*
Y991083D03*
Y1004469D03*
Y1031240D03*
Y1037933D03*
Y1044626D03*
Y1034587D03*
Y1041280D03*
Y1031240D03*
Y1037933D03*
Y1044626D03*
Y1058012D03*
Y1051319D03*
Y1047973D03*
Y1054666D03*
Y1058012D03*
Y1051319D03*
Y1074744D03*
Y1061359D03*
Y1071398D03*
Y1074744D03*
Y1068051D03*
Y1064705D03*
Y1081437D03*
Y1088130D03*
Y1091477D03*
X1657597Y1089804D03*
X1658647Y1084784D03*
X1653197Y1078091D03*
Y1081437D03*
Y1088130D03*
Y1098170D03*
Y1104862D03*
X1658647Y1094823D03*
X1653197Y1101516D03*
Y1098170D03*
Y1104862D03*
Y1091477D03*
Y1111555D03*
Y1118248D03*
Y1108209D03*
Y1114902D03*
Y1111555D03*
Y1118248D03*
Y1134981D03*
Y1124941D03*
Y1128288D03*
X1657597Y1126615D03*
X1658647Y1121595D03*
Y1131634D03*
X1653197Y1134981D03*
Y1124941D03*
Y1128288D03*
Y1148366D03*
Y1141674D03*
Y1138327D03*
Y1145020D03*
Y1148366D03*
Y1141674D03*
Y1155059D03*
Y1161752D03*
Y1165099D03*
X1657597Y1163426D03*
X1658647Y1158406D03*
X1653197Y1151713D03*
Y1155059D03*
Y1161752D03*
Y1165099D03*
Y1171792D03*
Y1178485D03*
X1658647Y1168445D03*
X1653197Y1175138D03*
Y1171792D03*
Y1178485D03*
Y1185177D03*
Y1191870D03*
Y1188524D03*
Y1181831D03*
Y1185177D03*
Y1191870D03*
Y1208603D03*
Y1198563D03*
Y1201910D03*
X1657597Y1200237D03*
X1658647Y1205256D03*
Y1195217D03*
X1653197Y1208603D03*
Y1198563D03*
Y1201910D03*
Y1215296D03*
Y1221988D03*
Y1211949D03*
Y1218642D03*
Y1215296D03*
Y1221988D03*
Y1228681D03*
Y1235374D03*
Y1238721D03*
X1657597Y1237048D03*
X1658647Y1232028D03*
X1653197Y1225335D03*
Y1228681D03*
Y1235374D03*
Y1238721D03*
Y1245414D03*
Y1252107D03*
Y1248760D03*
X1658647Y1242067D03*
X1653197Y1245414D03*
Y1252107D03*
Y1255453D03*
X1660594Y1298735D03*
X1651187D03*
X1660594Y1303935D03*
Y1306535D03*
Y1301335D03*
X1651187Y1303935D03*
Y1306535D03*
Y1301335D03*
X1651072Y1314137D03*
X1660572Y1313837D03*
X1660635Y1329166D03*
X1651072Y1323137D03*
Y1320137D03*
Y1317137D03*
X1660572Y1322837D03*
Y1319837D03*
X1660635Y1326466D03*
X1660572Y1316837D03*
X1658015Y1328966D03*
X1658115Y1326466D03*
X1660635Y1331666D03*
Y1334166D03*
Y1339166D03*
Y1336666D03*
X1650177Y1341488D03*
X1658277Y1341888D03*
X1658015Y1336466D03*
Y1338966D03*
Y1331466D03*
Y1333966D03*
X1650177Y1351467D03*
Y1348567D03*
X1658904Y1351467D03*
Y1348567D03*
X1650177Y1344488D03*
X1658677D03*
X1662010Y1384570D03*
X1662766Y1377814D03*
X1660166D03*
X1662766Y1374707D03*
X1660166D03*
X1651301Y1378765D03*
X1653390Y1386316D03*
Y1388857D03*
X1662010Y1390170D03*
X1654774Y1402619D03*
X1648857Y1403424D03*
X1649197Y1396743D03*
X1654883Y1397231D03*
X1660152Y1397383D03*
Y1399891D03*
X1657163Y1393706D03*
X1655383Y1425541D03*
X1649283Y1419441D03*
Y1431541D03*
X1655383D03*
Y1419441D03*
X1662487Y1424178D03*
X1662465Y1444358D03*
X1655957Y1445116D03*
X1658089Y1437444D03*
X1649380Y1446713D03*
X1659960Y1485895D03*
X1656560D03*
X1662560D03*
X1653960D03*
X1655870Y1483295D03*
X1660650D03*
X1655870Y1488495D03*
X1660650D03*
X1649170Y1492995D03*
X1653950D03*
X1659960Y1485895D03*
X1656560D03*
X1653260Y1495595D03*
X1649160Y1505295D03*
X1655860Y1495595D03*
X1649170Y1498195D03*
X1653950D03*
X1653260Y1495595D03*
X1649860D03*
X1654505Y1577997D03*
X1659229D03*
X1654505Y1581397D03*
X1659229D03*
X1662129Y1582178D03*
X1649780Y1577997D03*
X1654505D03*
X1659229D03*
X1649780Y1581397D03*
X1654505D03*
X1659229D03*
X1654505Y1583897D03*
X1659229Y1583797D03*
X1649780Y1583897D03*
X1659975Y1592929D03*
X1650543Y1635380D03*
X1651321Y1637876D03*
Y1632884D03*
X1650543Y1635380D03*
Y1647292D03*
X1651321Y1649788D03*
Y1644796D03*
X1650543Y1647292D03*
X1653464Y1668416D03*
X1661101Y1671631D03*
X1653930Y1660640D03*
X1656180Y1659220D03*
X1656849Y1664949D03*
X1651101Y1700478D03*
X1661125Y1690751D03*
X1656997Y1708609D03*
X1660541Y1704237D03*
X1656997Y1723759D03*
Y1718759D03*
X1653351Y1737117D03*
X1656997Y1733909D03*
X1678899Y19541D03*
X1675194Y26477D03*
X1671794D03*
X1677030Y28406D03*
X1677972Y25977D03*
X1676121Y19541D03*
X1669943Y28406D03*
X1675972Y23981D03*
X1671016D03*
X1669016Y25977D03*
X1675194Y26477D03*
X1671794D03*
X1677040Y37106D03*
X1669953D03*
X1677030Y40020D03*
X1669943D03*
X1677040Y48720D03*
X1669953D03*
X1679904Y75340D03*
X1668770Y69340D03*
X1672170D03*
X1677204Y75340D03*
X1663866Y75343D03*
X1672960Y71839D03*
X1667980Y66847D03*
X1672960D03*
X1674870Y69340D03*
X1667980Y71839D03*
X1666070Y69340D03*
X1668770D03*
X1672170D03*
X1673100Y126762D03*
Y131762D03*
X1665100Y156762D03*
Y166762D03*
X1673403Y199997D03*
X1664335Y210191D03*
X1673223Y220857D03*
X1663310Y215488D03*
X1663610Y394727D03*
X1671516Y599956D03*
X1677516D03*
X1671516Y609450D03*
X1677516D03*
X1667498Y659021D03*
X1664898D03*
X1664789Y756765D03*
X1673839Y756831D03*
X1669339Y776910D03*
X1664789Y763765D03*
X1669339Y773563D03*
X1664789Y767265D03*
Y771065D03*
X1669339Y776910D03*
X1673839Y763524D03*
X1673889Y770217D03*
X1669339Y783603D03*
Y790296D03*
Y793642D03*
X1673739Y791969D03*
X1663889Y786949D03*
X1669339Y780256D03*
Y783603D03*
Y790296D03*
Y800335D03*
Y807028D03*
X1663889Y796988D03*
X1669339Y803681D03*
Y800335D03*
Y807028D03*
Y793642D03*
Y813721D03*
Y820414D03*
Y810374D03*
Y817067D03*
Y813721D03*
Y820414D03*
Y837146D03*
Y830453D03*
Y827107D03*
X1673739Y828780D03*
X1663889Y823760D03*
Y833799D03*
X1669339Y837146D03*
Y830453D03*
Y827107D03*
Y843839D03*
Y850532D03*
Y840492D03*
Y847185D03*
Y843839D03*
Y850532D03*
Y857225D03*
Y863918D03*
Y867264D03*
X1673739Y865591D03*
X1663889Y860571D03*
X1669339Y853878D03*
Y857225D03*
Y863918D03*
Y873957D03*
Y880650D03*
X1663889Y870610D03*
X1669339Y877303D03*
Y873957D03*
Y880650D03*
Y867264D03*
Y887343D03*
Y894036D03*
Y883996D03*
Y890689D03*
Y887343D03*
Y894036D03*
Y910768D03*
Y904075D03*
Y900729D03*
X1673739Y902402D03*
X1663889Y897382D03*
Y907422D03*
X1669339Y910768D03*
Y904075D03*
Y900729D03*
Y924154D03*
Y917461D03*
Y914114D03*
Y920807D03*
Y924154D03*
Y917461D03*
Y930847D03*
Y940886D03*
Y937540D03*
X1673739Y939213D03*
X1663889Y934193D03*
X1669339Y927500D03*
Y930847D03*
Y940886D03*
Y937540D03*
Y947579D03*
Y954272D03*
X1663889Y944233D03*
X1669339Y950925D03*
Y947579D03*
Y954272D03*
Y967658D03*
Y957618D03*
Y964311D03*
Y971004D03*
Y960965D03*
X1663839D03*
X1669339Y967658D03*
Y974351D03*
Y981044D03*
Y987736D03*
Y977697D03*
Y984390D03*
Y974351D03*
Y981044D03*
Y994429D03*
Y1001122D03*
Y991083D03*
Y997776D03*
Y987736D03*
Y994429D03*
Y1001122D03*
Y1004469D03*
Y1027894D03*
D03*
Y1034587D03*
Y1041280D03*
Y1047973D03*
Y1031240D03*
Y1037933D03*
Y1044626D03*
Y1034587D03*
Y1041280D03*
Y1054666D03*
Y1061359D03*
Y1051319D03*
Y1058012D03*
Y1047973D03*
Y1054666D03*
Y1071398D03*
Y1064705D03*
Y1068051D03*
Y1074744D03*
Y1061359D03*
Y1071398D03*
Y1064705D03*
Y1078091D03*
Y1088130D03*
Y1084784D03*
X1673739Y1086457D03*
X1663889Y1081437D03*
X1669339Y1078091D03*
Y1088130D03*
Y1084784D03*
Y1094823D03*
Y1101516D03*
X1663889Y1091477D03*
X1669339Y1098170D03*
Y1104862D03*
Y1094823D03*
Y1101516D03*
Y1108209D03*
Y1114902D03*
Y1121595D03*
X1663889Y1118248D03*
X1669339Y1111555D03*
Y1108209D03*
Y1114902D03*
Y1131634D03*
Y1124941D03*
X1673739Y1123268D03*
X1663889Y1128288D03*
X1669339Y1134981D03*
Y1131634D03*
Y1124941D03*
Y1121595D03*
Y1138327D03*
Y1145020D03*
Y1151713D03*
Y1141674D03*
Y1148366D03*
Y1138327D03*
Y1145020D03*
Y1161752D03*
Y1158406D03*
X1673739Y1160079D03*
X1663889Y1155059D03*
Y1165099D03*
X1669339Y1151713D03*
Y1161752D03*
Y1158406D03*
Y1168445D03*
Y1175138D03*
Y1181831D03*
Y1171792D03*
Y1178485D03*
Y1168445D03*
Y1175138D03*
Y1188524D03*
Y1195217D03*
X1663889Y1191870D03*
X1669339Y1185177D03*
Y1181831D03*
Y1188524D03*
Y1205256D03*
Y1198563D03*
Y1211949D03*
X1673739Y1196890D03*
X1663889Y1201910D03*
X1669339Y1208603D03*
Y1205256D03*
Y1198563D03*
Y1195217D03*
Y1218642D03*
Y1225335D03*
Y1215296D03*
Y1221988D03*
Y1211949D03*
Y1218642D03*
Y1235374D03*
Y1232028D03*
X1673739Y1233701D03*
X1663889Y1228681D03*
Y1238721D03*
X1669339Y1225335D03*
Y1235374D03*
Y1232028D03*
Y1242067D03*
Y1248760D03*
Y1245414D03*
Y1252107D03*
Y1242067D03*
Y1248760D03*
X1675187Y1298735D03*
Y1303935D03*
Y1306535D03*
Y1301335D03*
X1674972Y1313837D03*
X1675134Y1329219D03*
X1675234Y1326519D03*
X1674972Y1316837D03*
X1672623Y1326476D03*
X1663437Y1326526D03*
X1674972Y1319837D03*
Y1322837D03*
X1677754Y1326519D03*
Y1329019D03*
X1663437Y1334726D03*
X1672623Y1334676D03*
X1663437Y1329726D03*
X1672623Y1332176D03*
X1663437Y1332226D03*
X1672623Y1329676D03*
X1675134Y1331719D03*
Y1334219D03*
Y1336719D03*
Y1339219D03*
X1677754Y1339019D03*
Y1336519D03*
Y1331519D03*
Y1334019D03*
X1674831Y1351266D03*
Y1348366D03*
X1675901Y1377594D03*
Y1380551D03*
X1666870Y1384570D03*
X1664440D03*
X1675510Y1374723D03*
X1667966Y1374707D03*
X1670566D03*
X1665366Y1377814D03*
Y1380771D03*
Y1374707D03*
X1667966Y1377814D03*
Y1380771D03*
X1673066Y1374707D03*
X1675931Y1384335D03*
Y1387235D03*
X1666870Y1390170D03*
X1664440D03*
X1666919Y1402585D03*
X1667594Y1399428D03*
X1666844Y1396860D03*
X1675470Y1390170D03*
X1673040D03*
X1670610D03*
X1671067Y1405418D03*
X1672277Y1407694D03*
X1674777D03*
X1672501Y1416678D03*
X1672907Y1429928D03*
X1672273Y1420567D03*
X1675641Y1432891D03*
X1672401Y1423365D03*
X1664237Y1426278D03*
X1663239Y1428592D03*
X1666290Y1444391D03*
X1670147Y1444311D03*
X1673360Y1485895D03*
X1669960D03*
X1675960D03*
X1667360D03*
X1669270Y1483295D03*
X1674050D03*
X1669270Y1488495D03*
X1674050D03*
X1673360Y1485895D03*
X1669960D03*
X1673630Y1533092D03*
Y1537872D03*
X1671034Y1549734D03*
Y1552234D03*
X1668703Y1550898D03*
X1673674Y1563575D03*
X1668827Y1553551D03*
X1671034Y1557234D03*
Y1554734D03*
X1673706Y1560425D03*
X1670248Y1581563D03*
X1671006Y1576744D03*
Y1574244D03*
Y1571744D03*
X1668826Y1575498D03*
Y1572998D03*
X1676176Y1580650D03*
X1674923Y1582973D03*
X1677556Y1656405D03*
X1674356D03*
X1671156D03*
X1670534Y1670149D03*
X1666168Y1667688D03*
X1673245Y1673475D03*
X1674338Y1677832D03*
X1671902Y1676267D03*
X1669377Y1675241D03*
X1664256Y1690794D03*
X1673132Y1690741D03*
X1670773Y1688827D03*
X1668000Y1711759D03*
X1665520Y1716877D03*
X1672500Y1708927D03*
X1668000Y1726909D03*
X1675360Y1721252D03*
X1675351Y1737117D03*
X1665520Y1732027D03*
X1682299Y19541D03*
X1693072D03*
X1682965Y3001D03*
X1692262Y17045D03*
X1678088D03*
X1683068D03*
X1689367Y26477D03*
X1685967D03*
X1692262Y22037D03*
X1692145Y25977D03*
X1678088Y22037D03*
X1683068D03*
X1690294Y19541D03*
X1685077D03*
X1684117Y28406D03*
X1691203D03*
X1690145Y23981D03*
X1685189D03*
X1683189Y25977D03*
X1689367Y26477D03*
X1682299Y19541D03*
X1685967Y26477D03*
X1678899Y19541D03*
X1684127Y37106D03*
X1691213D03*
X1691203Y40020D03*
X1684117D03*
X1691213Y48720D03*
X1684127D03*
X1690900Y69343D03*
X1694300D03*
X1683304Y75340D03*
X1679114Y72847D03*
X1688200Y69343D03*
X1690114Y66850D03*
Y71842D03*
X1686004Y75340D03*
X1684094Y72847D03*
X1690900Y69343D03*
X1679904Y75340D03*
X1683304D03*
X1679114Y77839D03*
X1684094D03*
X1684925Y118762D03*
X1683275Y120762D03*
X1684925Y131762D03*
Y136762D03*
Y123762D03*
Y126762D03*
Y149762D03*
Y145762D03*
Y141762D03*
Y161762D03*
Y153762D03*
Y157762D03*
Y166762D03*
X1678809Y206451D03*
X1682433Y220857D03*
X1684942Y234000D03*
X1689000D03*
X1686154Y434160D03*
X1690140D03*
X1692974Y553115D03*
X1685890Y708610D03*
X1687448Y756765D03*
Y760265D03*
X1678398Y760177D03*
Y756831D03*
X1682898Y776910D03*
X1687448Y767265D03*
Y763765D03*
X1678348Y766870D03*
Y763524D03*
X1682898Y780256D03*
Y786949D03*
Y793642D03*
Y783603D03*
X1688348Y790296D03*
X1682898Y780256D03*
Y786949D03*
Y803681D03*
Y796988D03*
X1687298Y795315D03*
X1688348Y800335D03*
X1682898Y807028D03*
Y803681D03*
Y793642D03*
Y796988D03*
Y817067D03*
Y810374D03*
Y823760D03*
Y820414D03*
Y813721D03*
Y817067D03*
Y810374D03*
Y830453D03*
Y833799D03*
X1688348Y827107D03*
X1687298Y832126D03*
X1688348Y837146D03*
X1682898Y823760D03*
Y830453D03*
Y833799D03*
Y840492D03*
Y847185D03*
Y853878D03*
Y850532D03*
Y843839D03*
Y840492D03*
Y847185D03*
Y860571D03*
Y867264D03*
X1688348Y863918D03*
X1682898Y857225D03*
Y853878D03*
Y860571D03*
Y877303D03*
Y870610D03*
Y883996D03*
X1687298Y868937D03*
X1688348Y873957D03*
X1682898Y880650D03*
Y877303D03*
Y867264D03*
Y870610D03*
Y890689D03*
Y897382D03*
Y894036D03*
Y887343D03*
Y883996D03*
Y890689D03*
Y904075D03*
Y907422D03*
X1687298Y905749D03*
X1688348Y910768D03*
Y900729D03*
X1682898Y897382D03*
Y904075D03*
Y907422D03*
Y914114D03*
Y920807D03*
Y927500D03*
Y917461D03*
Y924154D03*
Y914114D03*
Y920807D03*
Y934193D03*
Y940886D03*
Y930847D03*
X1688348Y937540D03*
X1682898Y927500D03*
Y934193D03*
Y940886D03*
Y950925D03*
Y944233D03*
Y957618D03*
X1687298Y942560D03*
X1688348Y947579D03*
X1682898Y954272D03*
Y950925D03*
Y944233D03*
X1693540Y960965D03*
X1682898Y964311D03*
Y971004D03*
Y967658D03*
Y960965D03*
Y964311D03*
Y957618D03*
Y971004D03*
Y977697D03*
Y984390D03*
Y981044D03*
Y974351D03*
Y977697D03*
Y984390D03*
Y1001122D03*
Y997776D03*
Y991083D03*
Y994429D03*
Y987736D03*
Y1001122D03*
Y997776D03*
Y991083D03*
Y1004469D03*
Y1031240D03*
Y1037933D03*
Y1044626D03*
Y1041280D03*
Y1034587D03*
Y1031240D03*
Y1037933D03*
Y1044626D03*
Y1058012D03*
Y1051319D03*
Y1054666D03*
Y1047973D03*
Y1058012D03*
Y1051319D03*
Y1074744D03*
Y1061359D03*
Y1071398D03*
Y1074744D03*
Y1068051D03*
Y1064705D03*
Y1081437D03*
Y1088130D03*
Y1091477D03*
Y1078091D03*
X1687298Y1089804D03*
X1688348Y1084784D03*
X1682898Y1081437D03*
Y1088130D03*
Y1098170D03*
Y1104862D03*
X1688348Y1094823D03*
X1682898Y1101516D03*
Y1098170D03*
Y1104862D03*
Y1091477D03*
Y1111555D03*
Y1118248D03*
Y1108209D03*
Y1114902D03*
Y1111555D03*
Y1118248D03*
Y1134981D03*
Y1124941D03*
Y1128288D03*
X1688348Y1131634D03*
Y1121595D03*
X1687298Y1126615D03*
X1682898Y1134981D03*
Y1124941D03*
Y1128288D03*
Y1148366D03*
Y1141674D03*
Y1138327D03*
Y1145020D03*
Y1148366D03*
Y1141674D03*
Y1155059D03*
Y1161752D03*
Y1165099D03*
X1688348Y1158406D03*
X1682898Y1151713D03*
X1687298Y1163426D03*
X1682898Y1155059D03*
Y1161752D03*
Y1165099D03*
Y1171792D03*
Y1178485D03*
X1688348Y1168445D03*
X1682898Y1175138D03*
Y1171792D03*
Y1178485D03*
Y1185177D03*
Y1191870D03*
Y1188524D03*
Y1181831D03*
Y1185177D03*
Y1191870D03*
Y1208603D03*
Y1198563D03*
Y1201910D03*
X1688348Y1205256D03*
X1687298Y1200237D03*
X1688348Y1195217D03*
X1682898Y1208603D03*
Y1198563D03*
Y1201910D03*
Y1215296D03*
Y1221988D03*
Y1211949D03*
Y1218642D03*
Y1215296D03*
Y1221988D03*
Y1228681D03*
Y1235374D03*
Y1238721D03*
Y1225335D03*
X1687298Y1237048D03*
X1688348Y1232028D03*
X1682898Y1228681D03*
Y1235374D03*
Y1238721D03*
Y1245414D03*
Y1252107D03*
Y1248760D03*
X1688348Y1242067D03*
X1682898Y1245414D03*
Y1252107D03*
Y1255453D03*
X1684708Y1298435D03*
Y1303635D03*
Y1306235D03*
Y1301035D03*
X1684672Y1313837D03*
X1690697Y1329066D03*
Y1326566D03*
X1684672Y1322837D03*
Y1319837D03*
Y1316837D03*
X1690697Y1336566D03*
Y1334066D03*
Y1331566D03*
X1679028Y1341733D03*
X1687234Y1341533D03*
Y1344033D03*
X1679028Y1344233D03*
X1690697Y1339066D03*
X1687233Y1351320D03*
X1679133Y1351420D03*
X1687233Y1348420D03*
X1679133Y1348520D03*
X1679180Y1372169D03*
X1681780D03*
X1679180Y1366969D03*
X1681780D03*
Y1369569D03*
X1679180D03*
X1683896Y1378765D03*
X1692948Y1377914D03*
Y1374807D03*
X1680530Y1374669D03*
X1686172Y1386416D03*
Y1388957D03*
X1685963Y1402187D03*
X1687665Y1397331D03*
X1692934Y1397483D03*
X1689945Y1393806D03*
X1682500Y1390475D03*
X1680300Y1391875D03*
X1682500Y1396275D03*
X1680400Y1394875D03*
X1678234Y1393605D03*
Y1396505D03*
X1682500Y1393375D03*
X1687621Y1404138D03*
X1683587Y1433425D03*
X1684677Y1440258D03*
X1687357Y1440268D03*
X1683741Y1443075D03*
X1685298Y1451231D03*
X1687783Y1472068D03*
X1680730Y1517082D03*
Y1513682D03*
X1680430Y1511198D03*
X1680730Y1519682D03*
X1682760Y1512169D03*
X1683330Y1517772D03*
X1678130Y1512992D03*
Y1517772D03*
X1680730Y1517082D03*
Y1513682D03*
Y1530482D03*
Y1527082D03*
Y1533082D03*
Y1524482D03*
X1683330Y1531172D03*
Y1526392D03*
X1678130Y1531172D03*
Y1526392D03*
X1680730Y1530482D03*
Y1527082D03*
X1682561Y1552726D03*
X1685745Y1552579D03*
X1686219Y1549994D03*
X1691226Y1563526D03*
X1680558Y1555690D03*
X1688584Y1553284D03*
X1691548Y1555287D03*
X1691226Y1559526D03*
X1685745Y1555079D03*
Y1557579D03*
X1685995Y1561516D03*
X1680589Y1559626D03*
Y1563526D03*
X1682494Y1568271D03*
Y1575125D03*
X1680491Y1578089D03*
Y1571235D03*
X1689880Y1572067D03*
X1690353Y1591494D03*
X1680695Y1656307D03*
X1688243Y1663802D03*
X1692415Y1663740D03*
X1685500Y1663599D03*
X1686857Y1683918D03*
X1679420Y1683597D03*
X1691357Y1688418D03*
X1691952Y1698947D03*
X1683013Y1713684D03*
X1691997Y1708609D03*
X1683029D03*
X1682724Y1717701D03*
X1680519Y1726825D03*
X1689383Y1729187D03*
X1692218Y1717539D03*
X1685383Y1729559D03*
X1696472Y19541D03*
X1704965Y3001D03*
X1697242Y17045D03*
X1707186Y15708D03*
X1699250Y19541D03*
X1697242Y22037D03*
X1698290Y28406D03*
X1705376D03*
X1696472Y19541D03*
X1693072D03*
X1703583Y26505D03*
X1700183D03*
X1698300Y37106D03*
X1705381Y37108D03*
X1698290Y40020D03*
X1698300Y48720D03*
X1705386D03*
X1703536Y50649D03*
X1700136D03*
X1705304Y75340D03*
X1701904D03*
X1701114Y72847D03*
X1706094D03*
X1697000Y69343D03*
X1699204Y75340D03*
X1695094Y66850D03*
Y71842D03*
X1701904Y75340D03*
X1705304D03*
X1694300Y69343D03*
X1706094Y77839D03*
X1701114D03*
X1695100Y126762D03*
Y141762D03*
Y151762D03*
X1705120Y143610D03*
X1693000Y234000D03*
X1698220Y369652D03*
X1699809Y403985D03*
X1695579D03*
X1704444Y407045D03*
X1707444D03*
X1706500Y415862D03*
Y413362D03*
X1697914Y427155D03*
X1698014Y424055D03*
X1701124Y433650D03*
X1697214Y433655D03*
X1704624Y433650D03*
X1704974Y553115D03*
X1700974D03*
X1696974D03*
X1693490Y620672D03*
X1701121Y641658D03*
X1706101D03*
X1697530Y636369D03*
X1694490Y756765D03*
X1703540Y756831D03*
X1699040Y776910D03*
X1694490Y763765D03*
X1699040Y773563D03*
X1694490Y767265D03*
Y771065D03*
X1703590Y766870D03*
X1699040Y776910D03*
X1703540Y763524D03*
X1703590Y770217D03*
X1699040Y783603D03*
Y790296D03*
Y793642D03*
X1703440Y791969D03*
X1699040Y780256D03*
X1693590Y786949D03*
X1699040Y783603D03*
Y790296D03*
Y800335D03*
Y807028D03*
Y803681D03*
X1693590Y796988D03*
X1699040Y800335D03*
Y807028D03*
Y793642D03*
Y813721D03*
Y820414D03*
Y817067D03*
Y810374D03*
Y813721D03*
Y820414D03*
Y837146D03*
Y830453D03*
Y827107D03*
X1693590Y823760D03*
X1703440Y828780D03*
X1693590Y833799D03*
X1699040Y837146D03*
Y830453D03*
Y827107D03*
Y843839D03*
Y850532D03*
Y847185D03*
Y840492D03*
Y843839D03*
Y850532D03*
Y857225D03*
Y863918D03*
Y867264D03*
Y853878D03*
X1693590Y860571D03*
X1703440Y865591D03*
X1699040Y857225D03*
Y863918D03*
Y873957D03*
Y880650D03*
X1693590Y870610D03*
X1699040Y877303D03*
Y873957D03*
Y880650D03*
Y867264D03*
Y887343D03*
Y894036D03*
Y883996D03*
Y890689D03*
Y887343D03*
Y894036D03*
Y910768D03*
Y904075D03*
Y900729D03*
X1693590Y907422D03*
X1703440Y902402D03*
X1693590Y897382D03*
X1699040Y910768D03*
Y904075D03*
Y900729D03*
Y924154D03*
Y917461D03*
Y914114D03*
Y920807D03*
Y924154D03*
Y917461D03*
Y930847D03*
Y940886D03*
Y937540D03*
X1693590Y934193D03*
X1699040Y927500D03*
X1703440Y939213D03*
X1699040Y930847D03*
Y940886D03*
Y937540D03*
Y947579D03*
Y954272D03*
X1693590Y944233D03*
X1699040Y950925D03*
Y947579D03*
Y954272D03*
Y967658D03*
Y964311D03*
Y971004D03*
Y957618D03*
Y960965D03*
X1693540D03*
X1699040Y967658D03*
Y974351D03*
Y981044D03*
Y987736D03*
Y977697D03*
Y984390D03*
Y974351D03*
Y981044D03*
Y994429D03*
Y1001122D03*
Y997776D03*
Y991083D03*
Y987736D03*
Y994429D03*
Y1001122D03*
Y1004469D03*
Y1027894D03*
D03*
Y1034587D03*
Y1041280D03*
Y1047973D03*
Y1044626D03*
Y1037933D03*
Y1031240D03*
Y1034587D03*
Y1041280D03*
Y1054666D03*
Y1061359D03*
Y1058012D03*
Y1051319D03*
Y1047973D03*
Y1054666D03*
Y1071398D03*
Y1064705D03*
Y1074744D03*
Y1068051D03*
Y1061359D03*
Y1071398D03*
Y1064705D03*
Y1078091D03*
Y1088130D03*
Y1084784D03*
X1703440Y1086457D03*
X1693590Y1081437D03*
X1699040Y1078091D03*
Y1088130D03*
Y1084784D03*
Y1094823D03*
Y1101516D03*
X1693590Y1091477D03*
X1699040Y1104862D03*
Y1098170D03*
Y1094823D03*
Y1101516D03*
Y1108209D03*
Y1114902D03*
Y1121595D03*
Y1111555D03*
X1693590Y1118248D03*
X1699040Y1108209D03*
Y1114902D03*
Y1131634D03*
Y1124941D03*
Y1134981D03*
X1703440Y1123268D03*
X1693590Y1128288D03*
X1699040Y1131634D03*
Y1124941D03*
Y1121595D03*
Y1138327D03*
Y1145020D03*
Y1151713D03*
Y1141674D03*
Y1148366D03*
Y1138327D03*
Y1145020D03*
Y1161752D03*
Y1158406D03*
X1693590Y1155059D03*
Y1165099D03*
X1703440Y1160079D03*
X1699040Y1151713D03*
Y1161752D03*
Y1158406D03*
Y1168445D03*
Y1175138D03*
Y1181831D03*
Y1171792D03*
Y1178485D03*
Y1168445D03*
Y1175138D03*
Y1188524D03*
Y1195217D03*
X1693590Y1191870D03*
X1699040Y1185177D03*
Y1181831D03*
Y1188524D03*
Y1205256D03*
Y1198563D03*
Y1211949D03*
X1693590Y1201910D03*
X1703440Y1196890D03*
X1699040Y1208603D03*
Y1205256D03*
Y1198563D03*
Y1195217D03*
Y1218642D03*
Y1225335D03*
Y1221988D03*
Y1215296D03*
Y1211949D03*
Y1218642D03*
Y1235374D03*
Y1232028D03*
X1693590Y1228681D03*
Y1238721D03*
X1703440Y1233701D03*
X1699040Y1225335D03*
Y1235374D03*
Y1232028D03*
Y1242067D03*
Y1248760D03*
Y1245414D03*
Y1252107D03*
Y1242067D03*
Y1248760D03*
X1699087Y1298435D03*
Y1303635D03*
Y1306235D03*
Y1301035D03*
X1699072Y1313737D03*
X1696047Y1326576D03*
X1705383D03*
X1693417Y1329266D03*
X1693217Y1326566D03*
X1699072Y1322737D03*
Y1319737D03*
Y1316737D03*
X1693417Y1334266D03*
Y1331766D03*
X1705383Y1334676D03*
X1696047D03*
X1705383Y1329676D03*
X1696047Y1332176D03*
Y1329676D03*
X1705383Y1332176D03*
X1693417Y1336766D03*
Y1339266D03*
X1695533Y1351320D03*
Y1348420D03*
X1694792Y1384670D03*
X1700748Y1377914D03*
Y1380871D03*
Y1374807D03*
X1703348D03*
X1705848D03*
X1698148Y1377914D03*
X1695548D03*
X1698148Y1380871D03*
X1695548Y1374807D03*
X1698148D03*
X1699652Y1384670D03*
X1697222D03*
X1699652Y1390270D03*
X1694792D03*
X1697222D03*
X1699701Y1402685D03*
X1700376Y1399528D03*
X1696888Y1397928D03*
X1699626Y1396960D03*
X1703392Y1390270D03*
X1705822D03*
X1700272Y1460547D03*
X1702281Y1449801D03*
X1705108Y1451774D03*
X1695020Y1465621D03*
X1698440Y1466590D03*
X1705246Y1465325D03*
X1701348Y1466557D03*
X1695529Y1545193D03*
X1704822Y1694243D03*
X1702985Y1700328D03*
X1700156Y1698830D03*
X1702750Y1696185D03*
X1706086Y1691568D03*
X1700520Y1716877D03*
X1703000Y1711759D03*
X1702777Y1723593D03*
X1695166Y1717606D03*
X1697351Y1737117D03*
X1720148Y22910D03*
X1712977Y19986D03*
X1722148Y19910D03*
X1710106Y39768D03*
Y48978D03*
X1708004Y75340D03*
X1715861Y72593D03*
X1710886Y82208D03*
X1715550Y102923D03*
X1712486Y117908D03*
X1719909Y112713D03*
Y116713D03*
X1717384Y135373D03*
X1716609Y141297D03*
X1721628Y147312D03*
X1714293Y156278D03*
X1711293D03*
X1716893D03*
X1719493D03*
X1722093D03*
X1711293Y158878D03*
X1714293D03*
X1711293Y161478D03*
X1714293D03*
X1711293Y163978D03*
X1714293D03*
X1711293Y166478D03*
X1714293D03*
X1722093Y158878D03*
X1719493D03*
X1716893D03*
X1722093Y161478D03*
Y163978D03*
Y166478D03*
X1719493Y161478D03*
X1716893D03*
X1719493Y163978D03*
X1716893D03*
Y166478D03*
X1719493D03*
X1721400Y374462D03*
X1719200Y371162D03*
X1717220Y381152D03*
X1713720D03*
X1717220Y384652D03*
Y388152D03*
X1713720D03*
Y384652D03*
X1717220Y391652D03*
X1713720D03*
X1709000Y415862D03*
Y413362D03*
X1711144Y425945D03*
X1709339Y637251D03*
X1718241Y652105D03*
X1709759Y670221D03*
X1708305Y679720D03*
X1717149Y756765D03*
Y760265D03*
X1708099Y760177D03*
Y756831D03*
X1712599Y776910D03*
X1717149Y767265D03*
Y763765D03*
X1708049Y763524D03*
X1712599Y780256D03*
Y786949D03*
Y793642D03*
X1718049Y790296D03*
X1712599Y783603D03*
Y780256D03*
Y786949D03*
Y803681D03*
Y796988D03*
Y807028D03*
X1716999Y795315D03*
X1718049Y800335D03*
X1712599Y803681D03*
Y793642D03*
Y796988D03*
Y817067D03*
Y810374D03*
Y823760D03*
Y820414D03*
Y813721D03*
Y817067D03*
Y810374D03*
Y830453D03*
Y833799D03*
X1718049Y827107D03*
X1716999Y832126D03*
X1718049Y837146D03*
X1712599Y823760D03*
Y830453D03*
Y833799D03*
Y840492D03*
Y847185D03*
Y853878D03*
Y850532D03*
Y843839D03*
Y840492D03*
Y847185D03*
Y860571D03*
Y867264D03*
X1718049Y863918D03*
X1712599Y857225D03*
Y853878D03*
Y860571D03*
Y877303D03*
Y870610D03*
Y883996D03*
X1716999Y868937D03*
X1712599Y880650D03*
X1718049Y873957D03*
X1712599Y877303D03*
Y867264D03*
Y870610D03*
Y890689D03*
Y897382D03*
Y894036D03*
Y887343D03*
Y883996D03*
Y890689D03*
Y904075D03*
Y907422D03*
X1716999Y905749D03*
X1718049Y910768D03*
Y900729D03*
X1712599Y897382D03*
Y904075D03*
Y907422D03*
Y914114D03*
Y920807D03*
Y927500D03*
Y917461D03*
Y924154D03*
Y914114D03*
Y920807D03*
Y934193D03*
Y940886D03*
Y930847D03*
X1718049Y937540D03*
X1712599Y927500D03*
Y934193D03*
Y940886D03*
Y950925D03*
Y944233D03*
Y957618D03*
X1716999Y942560D03*
X1718049Y947579D03*
X1712599Y954272D03*
Y950925D03*
Y944233D03*
X1723241Y960965D03*
X1712599Y964311D03*
Y971004D03*
Y967658D03*
Y960965D03*
Y964311D03*
Y957618D03*
Y971004D03*
Y977697D03*
Y984390D03*
Y981044D03*
Y974351D03*
Y977697D03*
Y984390D03*
Y1001122D03*
Y997776D03*
Y991083D03*
Y994429D03*
Y987736D03*
Y1001122D03*
Y997776D03*
Y991083D03*
Y1004469D03*
Y1031240D03*
Y1037933D03*
Y1044626D03*
Y1041280D03*
Y1034587D03*
Y1031240D03*
Y1037933D03*
Y1044626D03*
Y1058012D03*
Y1051319D03*
Y1054666D03*
Y1047973D03*
Y1058012D03*
Y1051319D03*
Y1074744D03*
Y1061359D03*
Y1071398D03*
Y1074744D03*
Y1068051D03*
Y1064705D03*
Y1081437D03*
Y1088130D03*
Y1091477D03*
Y1078091D03*
X1716999Y1089804D03*
X1718049Y1084784D03*
X1712599Y1081437D03*
Y1088130D03*
Y1098170D03*
Y1104862D03*
X1718049Y1094823D03*
X1712599Y1101516D03*
Y1098170D03*
Y1104862D03*
Y1091477D03*
Y1111555D03*
Y1118248D03*
Y1108209D03*
Y1114902D03*
Y1111555D03*
Y1118248D03*
Y1134981D03*
Y1124941D03*
Y1128288D03*
X1718049Y1131634D03*
Y1121595D03*
X1716999Y1126615D03*
X1712599Y1134981D03*
Y1124941D03*
Y1128288D03*
Y1148366D03*
Y1141674D03*
Y1138327D03*
Y1145020D03*
Y1148366D03*
Y1141674D03*
Y1155059D03*
Y1161752D03*
Y1165099D03*
X1718049Y1158406D03*
X1712599Y1151713D03*
X1716999Y1163426D03*
X1712599Y1155059D03*
Y1161752D03*
Y1165099D03*
Y1171792D03*
Y1178485D03*
X1718049Y1168445D03*
X1712599Y1175138D03*
Y1171792D03*
Y1178485D03*
Y1185177D03*
Y1191870D03*
Y1188524D03*
Y1181831D03*
Y1185177D03*
Y1191870D03*
Y1208603D03*
Y1198563D03*
Y1201910D03*
X1718049Y1195217D03*
Y1205256D03*
X1716999Y1200237D03*
X1712599Y1208603D03*
Y1198563D03*
Y1201910D03*
Y1215296D03*
Y1221988D03*
Y1218642D03*
Y1211949D03*
Y1215296D03*
Y1221988D03*
Y1228681D03*
Y1235374D03*
Y1238721D03*
Y1225335D03*
X1716999Y1237048D03*
X1718049Y1232028D03*
X1712599Y1228681D03*
Y1235374D03*
Y1238721D03*
Y1245414D03*
Y1252107D03*
Y1248760D03*
X1718049Y1242067D03*
X1712599Y1245414D03*
Y1252107D03*
Y1255453D03*
X1721754Y1299488D03*
X1708754Y1298388D03*
X1721847Y1307298D03*
X1721754Y1304688D03*
X1708754Y1300988D03*
X1721754Y1302088D03*
X1708754Y1303588D03*
Y1306188D03*
X1722672Y1313237D03*
X1708672Y1313737D03*
X1707916Y1329319D03*
X1722672Y1316237D03*
X1708672Y1322737D03*
Y1319737D03*
X1710536Y1329119D03*
X1708016Y1326619D03*
X1710536D03*
X1722672Y1319237D03*
Y1322237D03*
X1719916Y1326559D03*
X1717396D03*
X1719916Y1329059D03*
X1717396D03*
X1708672Y1316737D03*
X1707916Y1334319D03*
Y1331819D03*
Y1339319D03*
Y1336819D03*
X1710536Y1336619D03*
Y1339119D03*
X1719916Y1339059D03*
X1717396D03*
X1719916Y1336559D03*
X1717396D03*
X1710536Y1334119D03*
Y1331619D03*
X1719916Y1331559D03*
Y1334059D03*
X1717396D03*
Y1331559D03*
X1710176Y1342089D03*
X1718706Y1341629D03*
Y1344129D03*
X1718813Y1348450D03*
Y1351350D03*
X1709533Y1351520D03*
Y1348620D03*
X1710176Y1344589D03*
X1711962Y1367069D03*
X1714562D03*
X1711962Y1369669D03*
X1714562D03*
X1719902Y1368509D03*
Y1365909D03*
Y1363409D03*
X1708678Y1380621D03*
Y1377664D03*
X1716267Y1375178D03*
X1713312Y1374769D03*
X1708292Y1374823D03*
X1708713Y1384435D03*
Y1387335D03*
X1708252Y1390270D03*
X1715282Y1396375D03*
X1713082Y1391975D03*
X1715282Y1390575D03*
X1711016Y1393705D03*
Y1396605D03*
X1713182Y1394975D03*
X1715282Y1393475D03*
X1717447Y1417213D03*
X1714447D03*
X1717447Y1423213D03*
Y1420213D03*
X1714447D03*
Y1423213D03*
X1720210Y1435330D03*
X1722334Y1468146D03*
X1722347Y1471246D03*
X1716070Y1472037D03*
X1719893Y1594940D03*
X1712870Y1586615D03*
X1719893Y1599740D03*
Y1606340D03*
Y1609640D03*
X1720845Y1668498D03*
X1722149Y1715265D03*
X1719149Y1703190D03*
X1710360Y1706502D03*
X1721912Y1705115D03*
X1722133Y1725340D03*
X1722149Y1730415D03*
Y1720265D03*
X1710230Y1729654D03*
X1719351Y1737117D03*
X1729557Y-35912D03*
Y-32512D03*
Y-25912D03*
Y-35912D03*
Y-32512D03*
X1735375Y-40925D03*
X1727111Y-38849D03*
Y-28849D03*
X1732350Y-39605D03*
X1735390Y-38410D03*
X1735374Y-27916D03*
X1732349Y-29236D03*
X1735389Y-30431D03*
X1729557Y-22512D03*
D03*
Y-25912D03*
X1727111Y-19575D03*
X1735390Y-20014D03*
X1735375Y-17499D03*
X1732350Y-18819D03*
X1726965Y3001D03*
X1732286Y28208D03*
X1728786D03*
X1725286D03*
X1736006Y41838D03*
Y44338D03*
X1727336Y57024D03*
X1726596Y61784D03*
X1729836Y57024D03*
Y54524D03*
X1727336D03*
X1724685Y51454D03*
X1727225Y51424D03*
X1729895Y51354D03*
X1726741Y48822D03*
X1730241D03*
X1726596Y64284D03*
X1737617Y75640D03*
Y73140D03*
Y79140D03*
Y81640D03*
X1726814Y102968D03*
X1722984Y101713D03*
X1723184Y93313D03*
X1736731Y102293D03*
X1736986Y109723D03*
Y112223D03*
X1733344Y134953D03*
X1736474D03*
X1725093Y156278D03*
Y158878D03*
Y161478D03*
Y163978D03*
Y166478D03*
X1730364Y177588D03*
X1735471Y293682D03*
Y290682D03*
Y296682D03*
Y299682D03*
X1730331Y293722D03*
Y296722D03*
X1732831D03*
X1730331Y299722D03*
X1732831D03*
Y293722D03*
X1723492Y293068D03*
X1732751Y305732D03*
X1730251D03*
X1732751Y302732D03*
X1730251D03*
X1735391Y305692D03*
Y302692D03*
X1725400Y372062D03*
X1737260Y368132D03*
X1732660Y372692D03*
X1725500Y383662D03*
X1728300Y377787D03*
X1723259Y653641D03*
X1733083Y654034D03*
X1726409Y653641D03*
X1726334Y670345D03*
X1724191Y756765D03*
X1733241Y756831D03*
X1728741Y776910D03*
X1724191Y763765D03*
X1728741Y773563D03*
X1724191Y767299D03*
Y771099D03*
X1733727Y766870D03*
X1728741Y776910D03*
X1733241Y763524D03*
X1733291Y770217D03*
X1728741Y783603D03*
Y790296D03*
Y793642D03*
X1733141Y791969D03*
X1723291Y786949D03*
X1728741Y780256D03*
Y783603D03*
Y790296D03*
Y800335D03*
Y807028D03*
Y803681D03*
X1723291Y796988D03*
X1728741Y800335D03*
Y807028D03*
Y793642D03*
Y813721D03*
Y820414D03*
Y817067D03*
Y810374D03*
Y813721D03*
Y820414D03*
Y837146D03*
Y830453D03*
Y827107D03*
X1733141Y828780D03*
X1723291Y823760D03*
Y833799D03*
X1728741Y837146D03*
Y830453D03*
Y827107D03*
Y843839D03*
Y850532D03*
Y847185D03*
Y840492D03*
Y843839D03*
Y850532D03*
Y857225D03*
Y863918D03*
Y867264D03*
Y853878D03*
X1733141Y865591D03*
X1723291Y860571D03*
X1728741Y857225D03*
Y863918D03*
Y873957D03*
Y880650D03*
X1723291Y870610D03*
X1728741Y877303D03*
Y873957D03*
Y880650D03*
Y867264D03*
Y887343D03*
Y894036D03*
Y883996D03*
Y890689D03*
Y887343D03*
Y894036D03*
Y910768D03*
Y904075D03*
Y900729D03*
X1723291Y907422D03*
X1733141Y902402D03*
X1723291Y897382D03*
X1728741Y910768D03*
Y904075D03*
Y900729D03*
Y924154D03*
Y917461D03*
Y914114D03*
Y920807D03*
Y924154D03*
Y917461D03*
Y930847D03*
Y940886D03*
Y937540D03*
X1723291Y934193D03*
X1728741Y927500D03*
X1733141Y939213D03*
X1728741Y930847D03*
Y940886D03*
Y937540D03*
Y947579D03*
Y954272D03*
X1723291Y944233D03*
X1728741Y950925D03*
Y947579D03*
Y954272D03*
Y967658D03*
Y964311D03*
Y971004D03*
Y957618D03*
Y960965D03*
X1723241D03*
X1728741Y967658D03*
Y974351D03*
Y981044D03*
Y987736D03*
Y977697D03*
Y984390D03*
Y974351D03*
Y981044D03*
Y994429D03*
Y1001122D03*
Y997776D03*
Y991083D03*
Y987736D03*
Y994429D03*
Y1001122D03*
Y1004469D03*
Y1027894D03*
D03*
Y1034587D03*
Y1041280D03*
Y1047973D03*
Y1044626D03*
Y1037933D03*
Y1031240D03*
Y1034587D03*
Y1041280D03*
Y1054666D03*
Y1061359D03*
Y1058012D03*
Y1051319D03*
Y1047973D03*
Y1054666D03*
Y1071398D03*
Y1064705D03*
Y1074744D03*
Y1068051D03*
Y1061359D03*
Y1071398D03*
Y1064705D03*
Y1078091D03*
Y1088130D03*
Y1084784D03*
X1733141Y1086457D03*
X1723291Y1081437D03*
X1728741Y1078091D03*
Y1088130D03*
Y1084784D03*
Y1094823D03*
Y1101516D03*
X1723291Y1091477D03*
X1728741Y1104862D03*
Y1098170D03*
Y1094823D03*
Y1101516D03*
Y1108209D03*
Y1114902D03*
Y1121595D03*
Y1111555D03*
X1723291Y1118248D03*
X1728741Y1108209D03*
Y1114902D03*
Y1131634D03*
Y1124941D03*
Y1134981D03*
X1733141Y1123268D03*
X1723291Y1128288D03*
X1728741Y1131634D03*
Y1124941D03*
Y1121595D03*
Y1138327D03*
Y1145020D03*
Y1151713D03*
Y1141674D03*
Y1148366D03*
Y1138327D03*
Y1145020D03*
Y1161752D03*
Y1158406D03*
X1723291Y1155059D03*
X1733141Y1160079D03*
X1723291Y1165099D03*
X1728741Y1151713D03*
Y1161752D03*
Y1158406D03*
Y1168445D03*
Y1175138D03*
Y1181831D03*
Y1171792D03*
Y1178485D03*
Y1168445D03*
Y1175138D03*
Y1188524D03*
Y1195217D03*
X1723291Y1191870D03*
X1728741Y1185177D03*
Y1181831D03*
Y1188524D03*
Y1205256D03*
Y1198563D03*
Y1211949D03*
X1723291Y1201910D03*
X1733141Y1196890D03*
X1728741Y1208603D03*
Y1205256D03*
Y1198563D03*
Y1195217D03*
Y1218642D03*
Y1225335D03*
Y1221988D03*
Y1215296D03*
Y1211949D03*
Y1218642D03*
Y1235374D03*
Y1232028D03*
X1733141Y1233701D03*
X1723291Y1228681D03*
Y1238721D03*
X1728741Y1225335D03*
Y1235374D03*
Y1232028D03*
Y1242067D03*
Y1248760D03*
Y1245414D03*
Y1252107D03*
Y1242067D03*
Y1248760D03*
X1732624Y1299718D03*
X1732717Y1307528D03*
X1732624Y1302318D03*
Y1304918D03*
X1732702Y1313007D03*
Y1316007D03*
Y1322007D03*
Y1319007D03*
X1735202Y1368279D03*
Y1365679D03*
Y1363179D03*
X1723917Y1380518D03*
Y1377178D03*
X1737126Y1403838D03*
Y1401238D03*
X1732766Y1410562D03*
Y1413062D03*
X1735266Y1410562D03*
Y1413062D03*
X1732766Y1426362D03*
Y1428862D03*
X1735266Y1426362D03*
Y1428862D03*
X1722810Y1435330D03*
X1737606Y1539807D03*
X1737541Y1543707D03*
X1730004Y1540968D03*
X1734575Y1562068D03*
X1735379Y1566282D03*
X1735354Y1580480D03*
X1735351Y1569832D03*
X1736579Y1587480D03*
X1730202Y1602093D03*
X1723929Y1654456D03*
X1726381Y1647386D03*
X1723963Y1658965D03*
Y1663465D03*
Y1667965D03*
X1724263Y1681465D03*
X1724323Y1676965D03*
X1724263Y1672465D03*
X1735463Y1694465D03*
X1725423Y1692656D03*
X1731117Y1705115D03*
Y1715265D03*
Y1720265D03*
Y1730415D03*
X1738628Y-40911D03*
X1738658Y-35881D03*
X1738673Y-33366D03*
X1738643Y-38396D03*
X1738627Y-27930D03*
X1738642Y-30445D03*
X1738643Y-20028D03*
X1738628Y-17513D03*
X1738673Y-25058D03*
X1738658Y-22543D03*
X1748965Y3001D03*
X1752008Y25146D03*
X1748116Y37058D03*
X1738093Y53103D03*
Y55603D03*
X1741621Y76613D03*
Y74113D03*
Y82613D03*
Y80113D03*
X1738435Y100244D03*
X1741935D03*
X1745435D03*
X1740231Y102293D03*
X1743731D03*
X1740091Y92827D03*
X1745451Y119585D03*
X1747448Y121413D03*
X1740529Y112223D03*
Y109723D03*
X1744072Y112223D03*
Y109723D03*
X1747616Y112223D03*
Y109723D03*
X1750325Y179827D03*
X1750851Y216427D03*
X1748325D03*
X1752461Y255337D03*
X1749571Y255317D03*
X1752461Y252337D03*
X1749571Y252317D03*
X1752022Y269794D03*
Y266794D03*
X1742971Y293682D03*
Y290682D03*
X1737971D03*
X1740471Y293682D03*
Y290682D03*
Y299682D03*
X1737971D03*
X1740471Y296682D03*
X1737971D03*
Y293682D03*
X1751352Y293386D03*
X1745671Y290682D03*
Y293682D03*
X1752250Y303850D03*
X1737891Y302692D03*
X1740391D03*
X1737891Y305692D03*
X1740391D03*
X1742398Y484304D03*
X1742652Y671494D03*
X1745502Y660088D03*
X1745484Y668216D03*
X1751490Y713890D03*
X1748990D03*
X1746490D03*
X1743990D03*
X1751490Y706390D03*
X1748990D03*
X1746490D03*
X1743990D03*
X1751490Y708890D03*
X1748990D03*
X1746490D03*
X1743990D03*
X1751490Y711390D03*
X1748990D03*
X1746490D03*
X1743990D03*
X1746850Y756765D03*
Y760265D03*
X1737800Y756831D03*
Y760177D03*
X1742300Y776910D03*
X1746850Y767265D03*
Y763765D03*
X1737750Y763524D03*
X1742300Y780256D03*
Y786949D03*
Y793642D03*
Y783603D03*
X1747750Y790296D03*
X1742300Y780256D03*
Y786949D03*
Y803681D03*
Y796988D03*
X1746700Y795315D03*
X1747750Y800335D03*
X1742300Y807028D03*
Y803681D03*
Y793642D03*
Y796988D03*
Y817067D03*
Y810374D03*
Y823760D03*
Y820414D03*
Y813721D03*
Y817067D03*
Y810374D03*
Y830453D03*
Y833799D03*
X1747750Y827107D03*
X1746700Y832126D03*
X1747750Y837146D03*
X1742300Y823760D03*
Y830453D03*
Y833799D03*
Y840492D03*
Y847185D03*
Y853878D03*
Y850532D03*
Y843839D03*
Y840492D03*
Y847185D03*
Y860571D03*
Y867264D03*
X1747750Y863918D03*
X1742300Y857225D03*
Y853878D03*
Y860571D03*
Y877303D03*
Y870610D03*
Y883996D03*
X1746700Y868937D03*
X1747750Y873957D03*
X1742300Y880650D03*
Y877303D03*
Y867264D03*
Y870610D03*
Y890689D03*
Y897382D03*
Y894036D03*
Y887343D03*
Y883996D03*
Y890689D03*
Y904075D03*
Y907422D03*
X1746700Y905749D03*
X1747750Y910768D03*
Y900729D03*
X1742300Y897382D03*
Y904075D03*
Y907422D03*
Y914114D03*
Y920807D03*
Y927500D03*
Y917461D03*
Y924154D03*
Y914114D03*
Y920807D03*
Y934193D03*
Y940886D03*
Y930847D03*
X1747750Y937540D03*
X1742300Y927500D03*
Y934193D03*
Y940886D03*
Y950925D03*
Y944233D03*
Y957618D03*
X1746700Y942560D03*
X1747750Y947579D03*
X1742300Y954272D03*
Y950925D03*
Y944233D03*
X1752942Y960965D03*
X1742300Y964311D03*
Y971004D03*
Y960965D03*
Y967658D03*
Y964311D03*
Y957618D03*
Y971004D03*
Y977697D03*
Y984390D03*
Y981044D03*
Y974351D03*
Y977697D03*
Y984390D03*
Y1001122D03*
Y997776D03*
Y991083D03*
Y994429D03*
Y987736D03*
Y1001122D03*
Y997776D03*
Y991083D03*
Y1004469D03*
Y1031240D03*
Y1037933D03*
Y1044626D03*
Y1041280D03*
Y1034587D03*
Y1031240D03*
Y1037933D03*
Y1044626D03*
Y1058012D03*
Y1051319D03*
Y1054666D03*
Y1047973D03*
Y1058012D03*
Y1051319D03*
Y1074744D03*
Y1061359D03*
Y1071398D03*
Y1074744D03*
Y1068051D03*
Y1064705D03*
Y1081437D03*
Y1088130D03*
Y1091477D03*
Y1078091D03*
X1746700Y1089804D03*
X1747750Y1084784D03*
X1742300Y1081437D03*
Y1088130D03*
Y1098170D03*
Y1104862D03*
X1747750Y1094823D03*
X1742300Y1101516D03*
Y1098170D03*
Y1104862D03*
Y1091477D03*
Y1111555D03*
Y1118248D03*
Y1108209D03*
Y1114902D03*
Y1111555D03*
Y1118248D03*
Y1134981D03*
Y1124941D03*
Y1128288D03*
X1747750Y1131634D03*
Y1121595D03*
X1746700Y1126615D03*
X1742300Y1134981D03*
Y1124941D03*
Y1128288D03*
Y1148366D03*
Y1141674D03*
Y1138327D03*
Y1145020D03*
Y1148366D03*
Y1141674D03*
Y1155059D03*
Y1161752D03*
Y1165099D03*
X1747750Y1158406D03*
X1742300Y1151713D03*
X1746700Y1163426D03*
X1742300Y1155059D03*
Y1161752D03*
Y1165099D03*
Y1171792D03*
Y1178485D03*
X1747750Y1168445D03*
X1742300Y1175138D03*
Y1171792D03*
Y1178485D03*
Y1185177D03*
Y1191870D03*
Y1188524D03*
Y1181831D03*
Y1185177D03*
Y1191870D03*
Y1208603D03*
Y1198563D03*
Y1201910D03*
X1747750Y1205256D03*
X1746700Y1200237D03*
X1747750Y1195217D03*
X1742300Y1208603D03*
Y1198563D03*
Y1201910D03*
Y1215296D03*
Y1221988D03*
Y1218642D03*
Y1211949D03*
Y1215296D03*
Y1221988D03*
Y1228681D03*
Y1235374D03*
Y1238721D03*
Y1225335D03*
X1746700Y1237048D03*
X1747750Y1232028D03*
X1742300Y1228681D03*
Y1235374D03*
Y1238721D03*
Y1245414D03*
Y1252107D03*
Y1248760D03*
X1747750Y1242067D03*
X1742300Y1245414D03*
Y1252107D03*
Y1255453D03*
X1742766Y1418462D03*
Y1415962D03*
X1737766Y1410562D03*
Y1413062D03*
X1740266Y1410562D03*
Y1413062D03*
X1742766D03*
Y1410562D03*
X1740266Y1415962D03*
Y1418462D03*
X1743072Y1432211D03*
X1737766Y1426362D03*
Y1428862D03*
X1742766Y1423462D03*
X1740266Y1426362D03*
Y1423462D03*
Y1420962D03*
X1742766D03*
X1741329Y1482405D03*
Y1485405D03*
Y1491405D03*
Y1488405D03*
Y1506405D03*
Y1503405D03*
Y1509405D03*
Y1512405D03*
X1745543Y1518678D03*
X1742758Y1521239D03*
X1745746D03*
X1751120Y1521223D03*
X1751087Y1518704D03*
X1748346Y1521223D03*
X1748313Y1518704D03*
X1740058Y1537419D03*
X1739565Y1528105D03*
X1751132Y1526748D03*
Y1524248D03*
Y1529248D03*
X1742810Y1524534D03*
X1745410D03*
X1748358Y1526748D03*
Y1524248D03*
Y1529248D03*
X1744866Y1539589D03*
X1742165Y1539620D03*
X1743188Y1543871D03*
Y1547871D03*
X1740587Y1547946D03*
X1737738Y1548021D03*
X1740400Y1543682D03*
X1752364Y1556323D03*
Y1559430D03*
X1744564Y1556323D03*
Y1559430D03*
X1749764Y1556323D03*
Y1559430D03*
X1747164Y1556323D03*
Y1559430D03*
X1752564Y1562537D03*
X1751518Y1566186D03*
X1740079Y1559505D03*
X1740188Y1556371D03*
X1746558Y1566186D03*
X1749038D03*
X1749964Y1562537D03*
X1751518Y1571786D03*
X1746558D03*
X1749038D03*
X1740979Y1577905D03*
X1746079Y1587705D03*
X1743681Y1626750D03*
X1750681D03*
X1747181D03*
X1743481Y1616550D03*
X1750481D03*
X1746981D03*
X1747963Y1641965D03*
X1749329Y1662956D03*
X1743329Y1668956D03*
X1743153Y1662956D03*
X1749329Y1674956D03*
X1743329D03*
X1747986Y1686215D03*
X1739640Y1713383D03*
X1742120Y1708265D03*
X1750380Y1707468D03*
X1739640Y1728533D03*
X1742120Y1723415D03*
X1749480Y1718158D03*
X1741351Y1737117D03*
X1762420Y17031D03*
X1753388Y28406D03*
X1760475D03*
X1765980Y27031D03*
X1758638Y26477D03*
X1755238D03*
X1763840Y37790D03*
X1753398Y48720D03*
X1760485D03*
X1759666Y57708D03*
X1764366Y57508D03*
X1763010Y51223D03*
X1758635Y50649D03*
X1755235D03*
X1758047Y68637D03*
X1757923Y72637D03*
X1758539Y87153D03*
Y83653D03*
X1758534Y79743D03*
X1765034Y80443D03*
X1761417Y90017D03*
X1754364Y100353D03*
X1766244Y93673D03*
X1760444Y106173D03*
X1763644D03*
X1755944Y111073D03*
Y108473D03*
X1760944Y116773D03*
X1757944D03*
X1760124Y128246D03*
X1766911Y179890D03*
X1752851Y179827D03*
X1757385Y179890D03*
X1764385D03*
X1759911D03*
X1755504Y202263D03*
X1758030D03*
X1762564Y202326D03*
X1765090D03*
X1757951Y216427D03*
X1755425D03*
X1762485Y216490D03*
X1765011D03*
X1758859Y251544D03*
X1755969Y251524D03*
X1758859Y248544D03*
X1755969Y248524D03*
X1766399Y251361D03*
X1763509Y251341D03*
X1766399Y248361D03*
X1763509Y248341D03*
X1761573Y266657D03*
X1764573D03*
X1761573Y269657D03*
X1764573D03*
X1758022Y269794D03*
Y266794D03*
X1755022Y269794D03*
Y266794D03*
X1755772Y278859D03*
X1758772D03*
X1761772D03*
X1755772Y281859D03*
X1758772D03*
X1761772D03*
X1752772Y278859D03*
Y281859D03*
X1754850Y303930D03*
X1756800Y364048D03*
Y368048D03*
X1756933Y372452D03*
X1759379Y507927D03*
X1753566Y512968D03*
X1753990Y711390D03*
Y708890D03*
Y706390D03*
Y713890D03*
X1753892Y756765D03*
X1762942Y756831D03*
X1758442Y776910D03*
X1753892Y763765D03*
X1758442Y773563D03*
X1753891Y767305D03*
Y771105D03*
X1762992Y766870D03*
X1758442Y776910D03*
X1762942Y763524D03*
X1762992Y770217D03*
X1758442Y783603D03*
Y790296D03*
Y793642D03*
X1762842Y791969D03*
X1752992Y786949D03*
X1758442Y780256D03*
Y783603D03*
Y790296D03*
Y800335D03*
Y807028D03*
Y803681D03*
X1752992Y796988D03*
X1758442Y800335D03*
Y807028D03*
Y793642D03*
Y813721D03*
Y820414D03*
Y817067D03*
Y810374D03*
Y813721D03*
Y820414D03*
Y837146D03*
Y830453D03*
Y827107D03*
X1752992Y823760D03*
Y833799D03*
X1762842Y828780D03*
X1758442Y837146D03*
Y830453D03*
Y827107D03*
Y843839D03*
Y850532D03*
Y847185D03*
Y840492D03*
Y843839D03*
Y850532D03*
Y857225D03*
Y863918D03*
Y867264D03*
X1752992Y860571D03*
X1758442Y853878D03*
X1762842Y865591D03*
X1758442Y857225D03*
Y863918D03*
Y873957D03*
Y880650D03*
X1752992Y870610D03*
X1758442Y877303D03*
Y873957D03*
Y880650D03*
Y867264D03*
Y887343D03*
Y894036D03*
Y883996D03*
Y890689D03*
Y887343D03*
Y894036D03*
Y910768D03*
Y904075D03*
Y900729D03*
X1752992Y907422D03*
Y897382D03*
X1762842Y902402D03*
X1758442Y910768D03*
Y904075D03*
Y900729D03*
Y924154D03*
Y917461D03*
Y914114D03*
Y920807D03*
Y924154D03*
Y917461D03*
Y930847D03*
Y940886D03*
Y937540D03*
X1752992Y934193D03*
X1758442Y927500D03*
X1762842Y939213D03*
X1758442Y930847D03*
Y940886D03*
Y937540D03*
Y947579D03*
Y954272D03*
X1752992Y944233D03*
X1758442Y950925D03*
Y947579D03*
Y954272D03*
Y967658D03*
Y964311D03*
Y971004D03*
Y957618D03*
Y960965D03*
X1752942D03*
X1758442Y967658D03*
Y974351D03*
Y981044D03*
Y987736D03*
Y977697D03*
Y984390D03*
Y974351D03*
Y981044D03*
Y994429D03*
Y1001122D03*
Y997776D03*
Y991083D03*
Y987736D03*
Y994429D03*
Y1001122D03*
Y1004469D03*
Y1027894D03*
D03*
Y1034587D03*
Y1041280D03*
Y1047973D03*
Y1044626D03*
Y1037933D03*
Y1031240D03*
Y1034587D03*
Y1041280D03*
Y1054666D03*
Y1061359D03*
Y1058012D03*
Y1051319D03*
Y1047973D03*
Y1054666D03*
Y1071398D03*
Y1064705D03*
Y1074744D03*
Y1068051D03*
Y1061359D03*
Y1071398D03*
Y1064705D03*
Y1078091D03*
Y1088130D03*
Y1084784D03*
X1752992Y1081437D03*
X1762842Y1086457D03*
X1758442Y1078091D03*
Y1088130D03*
Y1084784D03*
Y1094823D03*
Y1101516D03*
X1752992Y1091477D03*
X1758442Y1104862D03*
Y1098170D03*
Y1094823D03*
Y1101516D03*
Y1108209D03*
Y1114902D03*
Y1121595D03*
X1752992Y1118248D03*
X1758442Y1111555D03*
Y1108209D03*
Y1114902D03*
Y1131634D03*
Y1124941D03*
Y1134981D03*
X1752992Y1128288D03*
X1762842Y1123268D03*
X1758442Y1131634D03*
Y1124941D03*
Y1121595D03*
Y1138327D03*
Y1145020D03*
Y1151713D03*
Y1141674D03*
Y1148366D03*
Y1138327D03*
Y1145020D03*
Y1161752D03*
Y1158406D03*
X1752992Y1155059D03*
Y1165099D03*
X1762842Y1160079D03*
X1758442Y1151713D03*
Y1161752D03*
Y1158406D03*
Y1168445D03*
Y1175138D03*
Y1181831D03*
Y1171792D03*
Y1178485D03*
Y1168445D03*
Y1175138D03*
Y1188524D03*
Y1195217D03*
X1752992Y1191870D03*
X1758442Y1185177D03*
Y1181831D03*
Y1188524D03*
Y1205256D03*
Y1198563D03*
Y1211949D03*
X1752992Y1201910D03*
X1762842Y1196890D03*
X1758442Y1208603D03*
Y1205256D03*
Y1198563D03*
Y1195217D03*
Y1218642D03*
Y1225335D03*
Y1221988D03*
Y1215296D03*
Y1211949D03*
Y1218642D03*
Y1235374D03*
Y1232028D03*
X1752992Y1228681D03*
Y1238721D03*
X1762842Y1233701D03*
X1758442Y1225335D03*
Y1235374D03*
Y1232028D03*
Y1242067D03*
Y1248760D03*
Y1245414D03*
Y1252107D03*
Y1242067D03*
Y1248760D03*
X1759949Y1297324D03*
X1764267Y1460080D03*
X1764029Y1485405D03*
Y1482405D03*
Y1491405D03*
Y1488405D03*
X1756329Y1485405D03*
Y1482405D03*
Y1491405D03*
Y1488405D03*
Y1506405D03*
Y1503405D03*
X1764029Y1506405D03*
Y1503405D03*
X1756329Y1509405D03*
Y1512405D03*
X1764029Y1509405D03*
Y1512405D03*
X1765286Y1518471D03*
X1765176Y1515902D03*
X1765286Y1521095D03*
X1765246Y1524001D03*
Y1526601D03*
X1765334Y1529342D03*
X1758238Y1556238D03*
X1761108Y1556339D03*
Y1559446D03*
X1761079Y1562605D03*
X1755038Y1556238D03*
X1765709Y1556050D03*
X1757438Y1571982D03*
X1755008D03*
X1762195D03*
X1759868D03*
X1764679Y1572105D03*
X1765679Y1575405D03*
X1762679D03*
X1766079Y1578705D03*
X1763079D03*
X1754479Y1585905D03*
X1753079Y1596650D03*
X1753512Y1583478D03*
X1753079Y1606550D03*
Y1603050D03*
Y1600150D03*
X1763706Y1616451D03*
X1760206D03*
X1767206D03*
X1761839Y1634223D03*
X1754763Y1641665D03*
X1757763Y1643365D03*
X1765854Y1646456D03*
X1755329Y1668956D03*
Y1662956D03*
X1761494Y1661947D03*
X1762263Y1671765D03*
X1755329Y1674956D03*
X1763463Y1691465D03*
X1758963Y1691565D03*
X1752864Y1716383D03*
X1763351Y1737117D03*
X1770965Y3001D03*
X1775920Y17031D03*
X1769420Y19506D03*
X1777420D03*
Y24506D03*
X1775920Y27068D03*
X1772886Y37430D03*
X1768956Y37558D03*
X1777720Y37792D03*
X1774294Y60133D03*
X1774291Y57191D03*
X1769240Y50788D03*
X1769200Y54300D03*
X1780300Y54400D03*
X1774294Y63033D03*
X1779744Y72973D03*
Y70073D03*
X1770334Y72737D03*
X1768134Y80543D03*
X1778205Y90982D03*
X1778544Y97973D03*
X1769244Y113773D03*
Y110973D03*
Y108073D03*
X1771881Y128439D03*
Y125939D03*
Y123439D03*
X1781966Y128501D03*
Y126001D03*
Y123501D03*
X1781368Y162824D03*
X1771385Y179890D03*
X1773911D03*
X1780929Y179408D03*
X1778500Y183790D03*
X1773581Y194120D03*
X1771055D03*
X1771931Y200920D03*
X1769405D03*
X1777170Y201002D03*
X1774644D03*
X1769585Y215090D03*
X1772111D03*
X1776585D03*
X1779111D03*
X1778874Y253799D03*
X1775984Y253779D03*
X1778874Y256799D03*
X1775984Y256779D03*
X1778796Y261633D03*
X1767573Y266657D03*
X1775633Y261666D03*
X1767573Y269657D03*
X1778796Y266633D03*
Y269133D03*
Y264133D03*
X1775633Y269166D03*
Y266666D03*
Y264166D03*
X1778796Y271633D03*
X1775633Y271666D03*
X1770520Y368148D03*
X1770280Y372452D03*
X1770220Y382952D03*
Y377452D03*
X1782324Y403932D03*
Y410432D03*
Y418932D03*
Y425432D03*
X1771236Y557224D03*
X1779376Y558324D03*
X1773963Y557537D03*
X1776550Y756765D03*
Y760265D03*
X1776986Y749023D03*
X1767500Y760177D03*
Y756831D03*
X1772000Y776910D03*
X1776550Y767265D03*
Y763765D03*
X1767450Y763524D03*
X1772000Y780256D03*
Y786949D03*
Y793642D03*
X1777450Y790296D03*
X1772000Y783603D03*
Y780256D03*
Y786949D03*
Y803681D03*
Y796988D03*
Y807028D03*
X1776400Y795315D03*
X1777450Y800335D03*
X1772000Y803681D03*
Y793642D03*
Y796988D03*
Y817067D03*
Y810374D03*
Y823760D03*
Y813721D03*
Y820414D03*
Y817067D03*
Y810374D03*
Y830453D03*
Y833799D03*
X1777450Y827107D03*
X1776400Y832126D03*
X1777450Y837146D03*
X1772000Y823760D03*
Y830453D03*
Y833799D03*
Y840492D03*
Y847185D03*
Y853878D03*
Y850532D03*
Y843839D03*
Y840492D03*
Y847185D03*
Y860571D03*
Y867264D03*
Y857225D03*
X1777450Y863918D03*
X1772000Y853878D03*
Y860571D03*
Y877303D03*
Y870610D03*
Y883996D03*
X1776400Y868937D03*
X1772000Y880650D03*
X1777450Y873957D03*
X1772000Y877303D03*
Y867264D03*
Y870610D03*
Y890689D03*
Y897382D03*
Y894036D03*
Y887343D03*
Y883996D03*
Y890689D03*
Y904075D03*
Y907422D03*
X1776400Y905749D03*
X1777450Y910768D03*
Y900729D03*
X1772000Y897382D03*
Y904075D03*
Y907422D03*
Y914114D03*
Y920807D03*
Y927500D03*
Y917461D03*
Y924154D03*
Y914114D03*
Y920807D03*
Y934193D03*
Y940886D03*
Y930847D03*
X1777450Y937540D03*
X1772000Y927500D03*
Y934193D03*
Y940886D03*
Y950925D03*
Y944233D03*
Y957618D03*
X1776400Y942560D03*
X1777450Y947579D03*
X1772000Y954272D03*
Y950925D03*
Y944233D03*
X1782642Y960965D03*
X1772000Y964311D03*
Y971004D03*
Y967658D03*
Y960965D03*
Y964311D03*
Y957618D03*
Y971004D03*
Y977697D03*
Y984390D03*
Y981044D03*
Y974351D03*
Y977697D03*
Y984390D03*
Y1001122D03*
Y997776D03*
Y991083D03*
Y994429D03*
Y987736D03*
Y1001122D03*
Y997776D03*
Y991083D03*
Y1004469D03*
Y1031240D03*
Y1037933D03*
Y1044626D03*
Y1041280D03*
Y1034587D03*
Y1031240D03*
Y1037933D03*
Y1044626D03*
Y1058012D03*
Y1051319D03*
Y1047973D03*
Y1054666D03*
Y1058012D03*
Y1051319D03*
Y1074744D03*
Y1061359D03*
Y1071398D03*
Y1074744D03*
Y1068051D03*
Y1064705D03*
Y1081437D03*
Y1088130D03*
Y1091477D03*
Y1078091D03*
X1776400Y1089804D03*
X1777450Y1084784D03*
X1772000Y1081437D03*
Y1088130D03*
Y1098170D03*
Y1104862D03*
X1777450Y1094823D03*
X1772000Y1101516D03*
Y1098170D03*
Y1104862D03*
Y1091477D03*
Y1111555D03*
Y1118248D03*
Y1108209D03*
Y1114902D03*
Y1111555D03*
Y1118248D03*
Y1134981D03*
Y1124941D03*
Y1128288D03*
X1777450Y1131634D03*
Y1121595D03*
X1776400Y1126615D03*
X1772000Y1134981D03*
Y1124941D03*
Y1128288D03*
Y1148366D03*
Y1141674D03*
Y1138327D03*
Y1145020D03*
Y1148366D03*
Y1141674D03*
Y1155059D03*
Y1161752D03*
Y1165099D03*
Y1151713D03*
X1777450Y1158406D03*
X1776400Y1163426D03*
X1772000Y1155059D03*
Y1161752D03*
Y1165099D03*
Y1171792D03*
Y1178485D03*
X1777450Y1168445D03*
X1772000Y1175138D03*
Y1171792D03*
Y1178485D03*
Y1185177D03*
Y1191870D03*
Y1188524D03*
Y1181831D03*
Y1185177D03*
Y1191870D03*
Y1208603D03*
Y1198563D03*
Y1201910D03*
X1777450Y1205256D03*
X1776400Y1200237D03*
X1777450Y1195217D03*
X1772000Y1208603D03*
Y1198563D03*
Y1201910D03*
Y1215296D03*
Y1221988D03*
Y1218642D03*
Y1211949D03*
Y1215296D03*
Y1221988D03*
Y1228681D03*
Y1235374D03*
Y1238721D03*
Y1225335D03*
X1776400Y1237048D03*
X1777450Y1232028D03*
X1772000Y1228681D03*
Y1235374D03*
Y1238721D03*
Y1245414D03*
Y1252107D03*
Y1248760D03*
X1777450Y1242067D03*
X1772000Y1245414D03*
Y1252107D03*
Y1255453D03*
X1769650Y1280200D03*
X1771000Y1278060D03*
X1782369Y1447581D03*
X1782385Y1450095D03*
X1782337Y1453191D03*
X1775682Y1466568D03*
X1779029Y1482405D03*
Y1485405D03*
Y1491405D03*
Y1488405D03*
Y1506405D03*
Y1503405D03*
Y1509405D03*
Y1512405D03*
X1780012Y1518631D03*
Y1516031D03*
Y1521231D03*
X1777152Y1518631D03*
Y1516031D03*
Y1521231D03*
X1774552D03*
Y1516031D03*
Y1518631D03*
X1768176Y1515902D03*
X1768286Y1518471D03*
Y1521095D03*
X1770886D03*
Y1518471D03*
X1770776Y1515902D03*
X1780039Y1523860D03*
Y1526360D03*
X1779997Y1528888D03*
X1777179Y1526360D03*
Y1523860D03*
X1774579D03*
Y1526360D03*
X1768246Y1526601D03*
Y1524001D03*
X1768334Y1529342D03*
X1770846Y1524001D03*
Y1526601D03*
X1776188Y1543871D03*
Y1546871D03*
X1769188D03*
Y1543871D03*
X1768688Y1552871D03*
Y1549871D03*
X1772688Y1543871D03*
Y1546871D03*
X1776113Y1541172D03*
X1769113D03*
X1772613D03*
X1780307Y1559430D03*
Y1556323D03*
X1775979Y1556805D03*
Y1559805D03*
X1782301Y1566186D03*
X1768209Y1556000D03*
X1769826Y1562559D03*
X1771079Y1566782D03*
X1782301Y1571786D03*
X1770404Y1575330D03*
X1771094Y1570332D03*
X1772904Y1585005D03*
X1778794Y1585332D03*
X1768105Y1595925D03*
X1775794Y1585332D03*
X1768030Y1599249D03*
X1768180Y1606549D03*
X1768030Y1603149D03*
X1780154Y1615026D03*
X1777454D03*
X1780154Y1617726D03*
X1777454D03*
X1773349Y1631938D03*
Y1634438D03*
Y1636938D03*
X1770649Y1631938D03*
Y1634438D03*
X1781423Y1634394D03*
Y1636894D03*
X1778723Y1634294D03*
X1776023D03*
Y1636894D03*
X1778723D03*
X1773929Y1657465D03*
Y1654956D03*
X1768929Y1651956D03*
X1773863Y1661465D03*
X1774940Y1669037D03*
X1773738Y1672965D03*
X1773963Y1680965D03*
X1774338Y1676865D03*
X1771038Y1692956D03*
X1792965Y3001D03*
X1793070Y25001D03*
X1796781Y46686D03*
X1783700Y50011D03*
X1785072Y53161D03*
X1794099Y50461D03*
X1788204Y74958D03*
X1785144Y86973D03*
Y89973D03*
X1788204Y82338D03*
Y78108D03*
X1784144Y113973D03*
Y111173D03*
Y108273D03*
X1784006Y137395D03*
X1788950Y142750D03*
X1787390Y161834D03*
Y165834D03*
Y151834D03*
X1789811Y178083D03*
X1793444D03*
X1794629Y193323D03*
X1791645Y193397D03*
X1795219Y185910D03*
X1795949Y205580D03*
X1795909Y209128D03*
X1795365Y197567D03*
X1796019Y202030D03*
X1791445Y197497D03*
X1783448Y212957D03*
X1795794Y253719D03*
X1787534Y253769D03*
X1795794Y256719D03*
X1787534Y256769D03*
X1783896Y266633D03*
Y269133D03*
X1794174Y274499D03*
X1790674D03*
X1783896Y271633D03*
X1795479Y408056D03*
X1795468Y421334D03*
X1785376Y558324D03*
X1792895Y683536D03*
X1783592Y756765D03*
X1792642Y756831D03*
X1788142Y776910D03*
X1783592Y763765D03*
X1788142Y773563D03*
X1783592Y767565D03*
Y771365D03*
X1788142Y776910D03*
X1792642Y763524D03*
X1792692Y770217D03*
X1788142Y783603D03*
Y790296D03*
Y793642D03*
X1792542Y791969D03*
X1782692Y786949D03*
X1788142Y780256D03*
Y783603D03*
Y790296D03*
Y800335D03*
Y807028D03*
X1782692Y796988D03*
X1788142Y803681D03*
Y800335D03*
Y807028D03*
Y793642D03*
Y813721D03*
Y820414D03*
Y817067D03*
Y810374D03*
Y813721D03*
Y820414D03*
Y837146D03*
Y830453D03*
Y827107D03*
X1782692Y823760D03*
Y833799D03*
X1792542Y828780D03*
X1788142Y837146D03*
Y830453D03*
Y827107D03*
Y843839D03*
Y850532D03*
Y847185D03*
Y840492D03*
Y843839D03*
Y850532D03*
Y857225D03*
Y863918D03*
Y867264D03*
Y853878D03*
X1792542Y865591D03*
X1782692Y860571D03*
X1788142Y857225D03*
Y863918D03*
Y873957D03*
Y880650D03*
X1782692Y870610D03*
X1788142Y877303D03*
Y873957D03*
Y880650D03*
Y867264D03*
Y887343D03*
Y894036D03*
Y883996D03*
Y890689D03*
Y887343D03*
Y894036D03*
Y910768D03*
Y904075D03*
Y900729D03*
X1782692Y907422D03*
Y897382D03*
X1792542Y902402D03*
X1788142Y910768D03*
Y904075D03*
Y900729D03*
Y924154D03*
Y917461D03*
Y914114D03*
Y920807D03*
Y924154D03*
Y917461D03*
Y930847D03*
Y940886D03*
Y937540D03*
X1782692Y934193D03*
X1788142Y927500D03*
X1792542Y939213D03*
X1788142Y930847D03*
Y940886D03*
Y937540D03*
Y947579D03*
Y954272D03*
X1782692Y944233D03*
X1788142Y950925D03*
Y947579D03*
Y954272D03*
Y967658D03*
Y964311D03*
Y971004D03*
Y957618D03*
Y960965D03*
X1782642D03*
X1788142Y967658D03*
Y974351D03*
Y981044D03*
Y987736D03*
Y977697D03*
Y984390D03*
Y974351D03*
Y981044D03*
Y994429D03*
Y1001122D03*
Y997776D03*
Y991083D03*
Y987736D03*
Y994429D03*
Y1001122D03*
Y1004469D03*
Y1027894D03*
D03*
Y1034587D03*
Y1041280D03*
Y1047973D03*
Y1044626D03*
Y1037933D03*
Y1031240D03*
Y1034587D03*
Y1041280D03*
Y1054666D03*
Y1061359D03*
Y1058012D03*
Y1051319D03*
Y1047973D03*
Y1054666D03*
Y1071398D03*
Y1064705D03*
Y1074744D03*
Y1068051D03*
Y1061359D03*
Y1071398D03*
Y1064705D03*
Y1078091D03*
Y1088130D03*
Y1084784D03*
X1782692Y1081437D03*
X1792542Y1086457D03*
X1788142Y1078091D03*
Y1088130D03*
Y1084784D03*
Y1094823D03*
Y1101516D03*
X1782692Y1091477D03*
X1788142Y1098170D03*
Y1104862D03*
Y1094823D03*
Y1101516D03*
Y1108209D03*
Y1114902D03*
Y1121595D03*
X1782692Y1118248D03*
X1788142Y1111555D03*
Y1108209D03*
Y1114902D03*
Y1131634D03*
Y1124941D03*
Y1134981D03*
X1782692Y1128288D03*
X1792542Y1123268D03*
X1788142Y1131634D03*
Y1124941D03*
Y1121595D03*
Y1138327D03*
Y1145020D03*
Y1151713D03*
Y1141674D03*
Y1148366D03*
Y1138327D03*
Y1145020D03*
Y1161752D03*
Y1158406D03*
X1782692Y1155059D03*
Y1165099D03*
X1792542Y1160079D03*
X1788142Y1151713D03*
Y1161752D03*
Y1158406D03*
Y1168445D03*
Y1175138D03*
Y1181831D03*
Y1171792D03*
Y1178485D03*
Y1168445D03*
Y1175138D03*
Y1188524D03*
Y1195217D03*
X1782692Y1191870D03*
X1788142Y1185177D03*
Y1181831D03*
Y1188524D03*
Y1205256D03*
Y1198563D03*
Y1211949D03*
X1782692Y1201910D03*
X1792542Y1196890D03*
X1788142Y1208603D03*
Y1205256D03*
Y1198563D03*
Y1195217D03*
Y1218642D03*
Y1225335D03*
Y1221988D03*
Y1215296D03*
Y1211949D03*
Y1218642D03*
Y1235374D03*
Y1232028D03*
X1782692Y1228681D03*
Y1238721D03*
X1792542Y1233701D03*
X1788142Y1225335D03*
Y1235374D03*
Y1232028D03*
Y1242067D03*
Y1248760D03*
Y1245414D03*
Y1252107D03*
Y1242067D03*
Y1248760D03*
X1794362Y1275546D03*
X1785336Y1447565D03*
Y1450065D03*
X1785634Y1456326D03*
X1782530Y1456229D03*
X1785408Y1453385D03*
X1788029Y1485405D03*
Y1482405D03*
Y1491405D03*
Y1488405D03*
Y1506405D03*
Y1503405D03*
Y1509405D03*
Y1512405D03*
X1794265Y1518262D03*
Y1520862D03*
Y1523462D03*
Y1526062D03*
X1794268Y1528720D03*
X1796838Y1556125D03*
X1788107Y1556323D03*
X1793833Y1556195D03*
X1790633D03*
X1788107Y1559430D03*
X1788307Y1562537D03*
X1787261Y1566186D03*
X1782907Y1559430D03*
Y1556323D03*
X1784781Y1566186D03*
X1785507Y1559430D03*
Y1556323D03*
X1785707Y1562537D03*
X1796257Y1561255D03*
Y1558755D03*
X1787261Y1571786D03*
X1784781D03*
X1784601Y1578967D03*
X1787239Y1579406D03*
X1793181Y1571982D03*
X1790751D03*
X1795611D03*
X1788679Y1585805D03*
X1789379Y1588478D03*
X1789294Y1583278D03*
X1797118Y1596588D03*
X1797143Y1607014D03*
X1797076Y1603662D03*
X1797043Y1599811D03*
X1791979Y1616550D03*
X1795479D03*
X1782654Y1615026D03*
Y1617726D03*
X1784048Y1636875D03*
Y1634375D03*
X1786615Y1631800D03*
X1786588Y1634472D03*
X1786624Y1637021D03*
X1807515Y56461D03*
X1805525Y146716D03*
X1800040Y164393D03*
X1802565Y156557D03*
X1804111Y178083D03*
X1807711D03*
Y175083D03*
X1800554Y177229D03*
X1808622Y170869D03*
X1803165Y196127D03*
X1797621Y193373D03*
X1800389Y193424D03*
X1803045Y193397D03*
X1797719Y186610D03*
X1802570Y186913D03*
X1798943Y204744D03*
Y209044D03*
X1802276Y209013D03*
X1805235Y208950D03*
X1802276Y204713D03*
X1800125Y201857D03*
X1805235Y204650D03*
X1799629Y198870D03*
X1803145Y198697D03*
X1811668Y218900D03*
X1811606Y222513D03*
X1808367Y222450D03*
X1810479Y211850D03*
X1810509Y214660D03*
X1808260Y213232D03*
X1808367Y226375D03*
X1807296Y255033D03*
X1804174Y253739D03*
Y256739D03*
X1807596Y264133D03*
Y266633D03*
Y269133D03*
X1797674Y274499D03*
X1801174D03*
X1807596Y271633D03*
X1800160Y362542D03*
X1808962Y698055D03*
Y700555D03*
Y703055D03*
X1798462Y698055D03*
X1801962D03*
X1805462D03*
Y700555D03*
X1801962D03*
X1798462D03*
X1805462Y703055D03*
X1801962D03*
X1798462D03*
X1808962Y705555D03*
Y708055D03*
X1798462Y705555D03*
X1801962D03*
X1805462D03*
X1798462Y708055D03*
X1801962D03*
X1805462D03*
X1809002Y710945D03*
Y713445D03*
Y715945D03*
X1805502Y710945D03*
Y713445D03*
Y715945D03*
X1802050Y710940D03*
X1811526Y1281671D03*
X1812029Y1485405D03*
Y1482405D03*
X1803029D03*
Y1485405D03*
X1812029Y1491405D03*
Y1488405D03*
X1803029Y1491405D03*
Y1488405D03*
Y1506405D03*
Y1503405D03*
X1812029Y1506405D03*
Y1503405D03*
X1803029Y1509405D03*
Y1512405D03*
X1812029Y1509405D03*
Y1512405D03*
X1797362Y1518304D03*
X1799882Y1520912D03*
Y1518312D03*
X1797362Y1520904D03*
X1801789Y1536742D03*
X1804049Y1528031D03*
X1799882Y1523512D03*
X1797362Y1523504D03*
X1799882Y1526112D03*
X1797362Y1526104D03*
X1799994Y1528674D03*
X1797450Y1528768D03*
X1809890Y1524532D03*
X1807290D03*
X1804688Y1545871D03*
Y1542371D03*
Y1552871D03*
Y1549371D03*
X1801688Y1545871D03*
Y1542371D03*
Y1552871D03*
Y1549371D03*
X1807408Y1539223D03*
X1810408D03*
X1804688Y1555871D03*
X1801688D03*
X1804688Y1559371D03*
X1797938Y1571982D03*
X1798479Y1575605D03*
X1798879Y1578905D03*
X1801479Y1575605D03*
X1800479Y1572305D03*
X1801879Y1578905D03*
X1812078Y1596725D03*
X1812003Y1607375D03*
Y1603875D03*
X1812078Y1600225D03*
X1809179Y1616550D03*
X1809254Y1613775D03*
X1798979Y1616550D03*
X1818615Y49379D03*
X1818155Y149325D03*
X1815005D03*
X1812570Y159275D03*
X1825111Y164393D03*
X1817196Y163797D03*
Y159947D03*
X1817674Y188699D03*
X1813224Y194699D03*
X1813079Y211850D03*
X1813109Y214660D03*
X1819529Y320321D03*
X1817157Y373829D03*
X1816994Y398052D03*
X1816224Y410432D03*
X1822724Y424948D03*
X1815724Y423932D03*
X1825874Y424948D03*
X1827073Y565157D03*
X1824073D03*
X1821073D03*
X1812462Y698055D03*
Y700555D03*
Y703055D03*
Y705555D03*
Y708055D03*
X1812502Y710945D03*
Y713445D03*
Y715945D03*
X1827029Y1488405D03*
Y1491405D03*
Y1485405D03*
Y1482405D03*
Y1506405D03*
Y1503405D03*
Y1509405D03*
Y1512405D03*
X1818475Y1524682D03*
X1815875D03*
X1823649Y1525144D03*
X1815344Y1539373D03*
X1818344D03*
X1823112Y1538659D03*
X1812679Y1616550D03*
X1816179D03*
X1812754Y1613775D03*
X1816254D03*
X1840615Y49379D03*
X1831166Y149986D03*
X1837641Y159275D03*
X1827580Y151834D03*
X1840700Y326201D03*
Y348201D03*
Y370201D03*
X1829732Y367359D03*
X1840700Y392201D03*
Y414201D03*
X1828483Y431678D03*
X1840700Y436201D03*
Y458201D03*
Y480201D03*
Y502201D03*
Y524201D03*
Y546201D03*
Y568201D03*
Y590201D03*
Y656201D03*
Y678201D03*
Y700201D03*
Y722201D03*
Y744201D03*
Y766201D03*
Y788201D03*
Y810201D03*
Y832201D03*
Y854201D03*
Y876201D03*
Y898201D03*
Y920201D03*
Y942201D03*
Y964201D03*
Y986201D03*
Y1008201D03*
Y1030201D03*
Y1052201D03*
Y1074201D03*
Y1096201D03*
Y1118201D03*
Y1140201D03*
Y1162201D03*
Y1184201D03*
Y1206201D03*
Y1228201D03*
Y1250201D03*
Y1272201D03*
Y1294201D03*
Y1316201D03*
Y1338201D03*
Y1404201D03*
Y1448201D03*
Y1470201D03*
X1833288Y1469639D03*
X1840700Y1492201D03*
Y1514201D03*
Y1536201D03*
Y1558201D03*
Y1580201D03*
X1835198Y1601502D03*
X1828889Y1622578D03*
Y1644578D03*
Y1666578D03*
Y1688578D03*
X1854479Y66461D03*
Y110461D03*
Y132461D03*
Y154461D03*
X1847866Y159124D03*
X1854479Y176461D03*
X1850791Y170287D03*
X1854479Y198461D03*
Y220461D03*
Y242461D03*
Y264461D03*
Y286461D03*
X1853692Y308447D03*
X2392820Y1336506D03*
X4298920Y144856D03*
X4302420Y415856D03*
X4303420Y688356D03*
X4301920Y992356D03*
X4306920Y1308856D03*
X4309598Y1624295D03*
X5116564Y119366D03*
X5116530Y392185D03*
X5119120Y663356D03*
X5121120Y945856D03*
X5120120Y1259856D03*
Y1575356D03*
G54D11*
X19685Y-29134D03*
Y1803261D03*
X2081889Y-29134D03*
Y1803261D03*
G54D20*
X117933Y605376D03*
X763602Y605413D03*
X1094076Y605378D03*
X1739745Y605411D03*
X2392820Y-377394D03*
G54D30*
X676509Y145866D03*
X2392820Y36306D03*
G54D21*
X182947Y1507512D03*
X180780Y1507509D03*
X178580D03*
X186530Y1521453D03*
X185688Y1519195D03*
X186860Y1514243D03*
X177487Y1521612D03*
X177086Y1518121D03*
X178745Y1513218D03*
X186579Y1536063D03*
X177579Y1528725D03*
Y1523810D03*
X177533Y1535698D03*
Y1537898D03*
X186530Y1523953D03*
X183051Y1542425D03*
X178980Y1540317D03*
X183051Y1544625D03*
X185966Y1592380D03*
Y1624292D03*
X188254Y1507295D03*
X192979D03*
X197703D03*
X191254Y1521453D03*
X195979D03*
X200703D03*
X196309Y1514243D03*
X201033D03*
X191584D03*
X188155Y1516970D03*
X192879D03*
X197604D03*
X189730Y1519698D03*
X194454D03*
X199178D03*
X187081Y1528853D03*
X191805D03*
X196530D03*
X201254D03*
X196029Y1536063D03*
X200753D03*
X191304D03*
X188155Y1530608D03*
X192879D03*
X197604D03*
X189730Y1533336D03*
X194454D03*
X199178D03*
X195979Y1523953D03*
X196530Y1526353D03*
X191805D03*
X187081D03*
X200703Y1523953D03*
X201254Y1526353D03*
X191254Y1523953D03*
X197703Y1542641D03*
X188254D03*
X192979D03*
X198026Y1592380D03*
X193766D03*
X192006Y1602380D03*
X199786D03*
X193766Y1624292D03*
X198026D03*
X199786Y1614292D03*
X192006D03*
X202427Y1507295D03*
X207152D03*
X211876D03*
X216601D03*
X205427Y1521453D03*
X210152D03*
X214876D03*
X205758Y1514243D03*
X215206D03*
X210482D03*
X202328Y1516970D03*
X207052D03*
X211777D03*
X216501D03*
X203903Y1519698D03*
X208627D03*
X213352D03*
X205478Y1536063D03*
X210202D03*
X205978Y1528853D03*
X210703D03*
X215427D03*
X214926Y1536063D03*
X202328Y1530608D03*
X207052D03*
X211777D03*
X216501D03*
X203903Y1533336D03*
X208627D03*
X213352D03*
X205427Y1523953D03*
X205978Y1526353D03*
X210703D03*
X210152Y1523953D03*
X214876D03*
X215427Y1526353D03*
X211876Y1542641D03*
X202427D03*
X207152D03*
X216601D03*
X210086Y1592380D03*
X205826D03*
X216126Y1602380D03*
X204066D03*
X211846D03*
X205826Y1624292D03*
X210086D03*
X216126Y1614292D03*
X211846D03*
X204066D03*
X221325Y1507295D03*
X226049D03*
X230774D03*
X219601Y1521453D03*
X224325D03*
X229049D03*
X219931Y1514243D03*
X224655D03*
X229380D03*
X221226Y1516970D03*
X225950D03*
X230674D03*
X218076Y1519698D03*
X222800D03*
X227525D03*
X219651Y1536063D03*
X229100D03*
X220152Y1528853D03*
X224876D03*
X229600D03*
X224375Y1536063D03*
X221226Y1530608D03*
X225950D03*
X230674D03*
X218076Y1533336D03*
X222800D03*
X227525D03*
X220152Y1526353D03*
X224876D03*
X224325Y1523953D03*
X219601D03*
X229049D03*
X229600Y1526353D03*
X226049Y1542641D03*
X230774D03*
X221325D03*
X229946Y1592380D03*
X217886D03*
X222146D03*
X223906Y1602380D03*
X228186D03*
X229946Y1624292D03*
X222146D03*
X217886D03*
X228186Y1614292D03*
X223906D03*
X235498Y1507295D03*
X240223D03*
X244947D03*
X243223Y1521453D03*
X238498D03*
X233774D03*
X234104Y1514243D03*
X238828D03*
X243553D03*
X235399Y1516970D03*
X240123D03*
X244848D03*
X236974Y1519698D03*
X241698D03*
X246422D03*
X232249D03*
X233824Y1536063D03*
X243273D03*
X243774Y1528853D03*
X239049D03*
X234325D03*
X238548Y1536063D03*
X235399Y1530608D03*
X240123D03*
X244848D03*
X236974Y1533336D03*
X241698D03*
X246422D03*
X232249D03*
X243223Y1523953D03*
X243774Y1526353D03*
X238498Y1523953D03*
X239049Y1526353D03*
X233774Y1523953D03*
X234325Y1526353D03*
X240223Y1542641D03*
X235498D03*
X244947D03*
X242006Y1592380D03*
X234206D03*
X246266D03*
X235966Y1602380D03*
X240246D03*
X246266Y1624292D03*
X242006D03*
X234206D03*
X240246Y1614292D03*
X235966D03*
X241141Y1679320D03*
Y1683857D03*
X233267Y1675383D03*
Y1679920D03*
Y1684454D03*
X241141Y1688391D03*
Y1693493D03*
Y1698030D03*
X233267Y1689556D03*
Y1694093D03*
Y1698627D03*
X241141Y1702564D03*
Y1707666D03*
Y1712203D03*
Y1716737D03*
X233267Y1703729D03*
Y1708266D03*
Y1712800D03*
X241141Y1721840D03*
Y1726377D03*
Y1730911D03*
X233267Y1717903D03*
Y1722440D03*
Y1726974D03*
X259120Y1507295D03*
X249671D03*
X254396D03*
X253002Y1514243D03*
X257396Y1521453D03*
X252672D03*
X247947D03*
X248277Y1514243D03*
X257726D03*
X249572Y1516970D03*
X254297D03*
X259021D03*
X251147Y1519698D03*
X255871D03*
X260596D03*
X252722Y1536063D03*
X257947Y1528853D03*
X253223D03*
X248498D03*
X257446Y1536063D03*
X247997D03*
X249572Y1530608D03*
X254297D03*
X259021D03*
X251147Y1533336D03*
X255871D03*
X260596D03*
X257396Y1523953D03*
X253223Y1526353D03*
X252672Y1523953D03*
X257947Y1526353D03*
X248498D03*
X247947Y1523953D03*
X254396Y1542641D03*
X259120D03*
X249671D03*
X258326Y1592380D03*
X254066D03*
X248026Y1602380D03*
X252306D03*
X260086D03*
X258326Y1624292D03*
X254066D03*
X248026Y1614292D03*
X252306D03*
X260086D03*
X256889Y1679320D03*
Y1683857D03*
X249015Y1684454D03*
Y1679920D03*
Y1675383D03*
X256889Y1688391D03*
Y1693493D03*
Y1698030D03*
X249015Y1698627D03*
Y1694093D03*
Y1689556D03*
X256889Y1702564D03*
Y1707666D03*
Y1712203D03*
Y1716737D03*
X249015Y1712800D03*
Y1708266D03*
Y1703729D03*
X256889Y1721840D03*
Y1726377D03*
Y1730911D03*
X249015Y1726974D03*
Y1722440D03*
Y1717903D03*
X265421Y1507355D03*
X263321D03*
X262141Y1521453D03*
X266828Y1514073D03*
X266772Y1516336D03*
X262777Y1536063D03*
X267123Y1536640D03*
Y1534540D03*
X267124Y1531618D03*
X267035Y1528698D03*
X266538Y1538658D03*
X270386Y1592380D03*
X266126D03*
X264366Y1602380D03*
X272146D03*
X270386Y1624292D03*
X266126D03*
X272146Y1614292D03*
X264366D03*
X272637Y1679320D03*
Y1683857D03*
X264763Y1684454D03*
Y1679920D03*
Y1675383D03*
X272637Y1688391D03*
Y1693493D03*
Y1698030D03*
X264763Y1698627D03*
Y1694093D03*
Y1689556D03*
X272637Y1702564D03*
Y1707666D03*
Y1712203D03*
Y1716737D03*
X264763Y1712800D03*
Y1708266D03*
Y1703729D03*
X272637Y1721840D03*
Y1726377D03*
Y1730911D03*
X264763Y1726974D03*
Y1722440D03*
Y1717903D03*
X290246Y1592380D03*
X278186D03*
X282446D03*
X276426Y1602380D03*
X284206D03*
X288486D03*
X290236Y1624292D03*
X282446D03*
X278186D03*
X288486Y1614292D03*
X284206D03*
X276426D03*
X288385Y1683857D03*
Y1679320D03*
X280511Y1684454D03*
Y1679920D03*
Y1675383D03*
X288385Y1688391D03*
Y1693494D03*
Y1698031D03*
X280511Y1698627D03*
Y1694093D03*
Y1689556D03*
X288385Y1712204D03*
Y1716738D03*
Y1702565D03*
Y1707667D03*
X280511Y1712800D03*
Y1708266D03*
Y1703729D03*
X288385Y1721840D03*
Y1726377D03*
Y1730911D03*
X280511Y1726974D03*
Y1722440D03*
Y1717903D03*
X303154Y879624D03*
Y886002D03*
X305004Y882813D03*
X303154Y892380D03*
Y898758D03*
X302413Y906182D03*
Y912560D03*
Y918938D03*
Y925316D03*
Y931694D03*
Y938072D03*
Y944450D03*
Y950828D03*
Y957206D03*
Y963584D03*
Y969962D03*
Y976340D03*
Y982718D03*
Y989096D03*
Y995474D03*
Y1008230D03*
Y1001852D03*
X303594Y1030198D03*
Y1036576D03*
Y1042954D03*
Y1055710D03*
Y1049332D03*
Y1062088D03*
Y1074844D03*
Y1068466D03*
Y1081222D03*
Y1087600D03*
Y1093978D03*
Y1100356D03*
Y1106734D03*
Y1113112D03*
Y1119490D03*
Y1125868D03*
Y1132246D03*
Y1138623D03*
Y1145001D03*
Y1157757D03*
Y1151379D03*
X305549Y1521612D03*
X305148Y1518121D03*
X305641Y1528725D03*
Y1523810D03*
X305595Y1535698D03*
Y1537898D03*
X302306Y1592380D03*
X294506D03*
X296266Y1602380D03*
X300546D03*
X302306Y1624292D03*
X294516D03*
X300546Y1614292D03*
X296266D03*
X300196Y1675383D03*
Y1679920D03*
Y1684454D03*
Y1689556D03*
Y1694093D03*
Y1698627D03*
Y1703729D03*
Y1708266D03*
Y1712800D03*
Y1717903D03*
Y1722440D03*
Y1726974D03*
X310555Y873246D03*
X317957Y879624D03*
X310555D03*
X319807Y876435D03*
X314256Y873246D03*
X310555Y886002D03*
X314256D03*
X316107Y882813D03*
Y889191D03*
X308705D03*
X319807Y882813D03*
X314256Y892380D03*
X308705Y895569D03*
Y882813D03*
X317957Y886002D03*
X319807Y889191D03*
Y895569D03*
X317957Y892380D03*
X316107Y895569D03*
X314256Y898758D03*
X316107Y901947D03*
X308705D03*
Y908325D03*
X314256Y911513D03*
X316107Y908325D03*
X319807D03*
X317957Y898758D03*
X319807Y901947D03*
X317957Y905135D03*
Y911513D03*
X314256Y905135D03*
Y917891D03*
X308705Y914702D03*
Y921080D03*
X316107D03*
X317957Y917891D03*
X319807Y921080D03*
X317957Y924269D03*
X319807Y914702D03*
X314256Y924269D03*
X316107Y914702D03*
Y940214D03*
X308705Y927458D03*
X316107D03*
X308705Y933836D03*
X314256Y930647D03*
Y937025D03*
X308705Y940214D03*
X319807Y927458D03*
X317957Y937025D03*
X319807Y940214D03*
Y933836D03*
X317957Y930647D03*
X316107Y933836D03*
X314256Y949781D03*
X316107Y946592D03*
X308705D03*
Y952970D03*
X314256Y956159D03*
X317957Y943403D03*
X319807Y946592D03*
X317957Y956159D03*
X319807Y952970D03*
X317957Y949781D03*
X316107Y952970D03*
X314256Y943403D03*
X316107Y959348D03*
X308705D03*
Y965726D03*
X316107D03*
X314256Y968915D03*
X317957Y962537D03*
X319807Y965726D03*
Y959348D03*
X317957Y968915D03*
X314256Y962537D03*
X317957Y981671D03*
X308705Y978482D03*
X316107D03*
X314256Y975293D03*
X308705Y972104D03*
X316107Y984860D03*
X308705D03*
X312406D03*
X319807D03*
X317957Y975293D03*
X319807Y978482D03*
Y972104D03*
X316107D03*
X314256Y981671D03*
X308705Y991238D03*
X310555Y988049D03*
X314256D03*
X316107Y997616D03*
X308705D03*
X314256Y994427D03*
X317957D03*
X319807Y997616D03*
X317957Y1000805D03*
X319807Y991238D03*
X314256Y1000805D03*
X316107Y991238D03*
X317957Y988049D03*
X316107Y1003994D03*
X314256Y1007183D03*
X316107Y1010372D03*
X308705D03*
Y1003994D03*
X319807Y1010372D03*
X317957Y1007183D03*
X319807Y1003994D03*
X309886Y1028056D03*
X317288D03*
X313587D03*
X320988D03*
X315437Y1031245D03*
X317288Y1040812D03*
X309886D03*
X317288Y1034434D03*
X309886D03*
X315437Y1044001D03*
X320988Y1034434D03*
X319138Y1037623D03*
X320988Y1040812D03*
X319138Y1044001D03*
X315437Y1037623D03*
X319138Y1031245D03*
X309886Y1047190D03*
X311736Y1056757D03*
X309886Y1053568D03*
X315437Y1050379D03*
X317288Y1053568D03*
Y1059946D03*
X309886D03*
X313587D03*
X320988D03*
X319138Y1050379D03*
X320988Y1053568D03*
X315437Y1056757D03*
X317288Y1047190D03*
X319138Y1056757D03*
X320988Y1047190D03*
X315437Y1063135D03*
X317288Y1072702D03*
X309886D03*
Y1066324D03*
X315437Y1069513D03*
X320988Y1072702D03*
X319138Y1063135D03*
Y1069513D03*
X320988Y1066324D03*
X317288D03*
Y1079080D03*
X309886D03*
X315437Y1082269D03*
Y1088647D03*
X309886Y1085458D03*
X319138Y1075891D03*
X320988Y1079080D03*
X319138Y1082269D03*
Y1088647D03*
X320988Y1085458D03*
X317288D03*
X315437Y1075891D03*
X309886Y1091836D03*
X317288D03*
X309886Y1104592D03*
X315437Y1101403D03*
X317288Y1098214D03*
X309886D03*
X319138Y1101403D03*
X320988Y1091836D03*
X319138Y1095025D03*
X320988Y1098214D03*
Y1104592D03*
X317288D03*
X315437Y1095025D03*
Y1107781D03*
X309886Y1110970D03*
X317288D03*
X309886Y1117348D03*
X317288D03*
X320988Y1110970D03*
X319138Y1114159D03*
X320988Y1117348D03*
X319138Y1107781D03*
X315437Y1114159D03*
X309886Y1123726D03*
X315437Y1120537D03*
Y1126915D03*
X309886Y1130103D03*
X317288D03*
X319138Y1120537D03*
X320988Y1130103D03*
X319138Y1133293D03*
Y1126915D03*
X320988Y1123726D03*
X315437Y1133293D03*
X317288Y1123726D03*
X309886Y1136481D03*
X315437Y1139670D03*
X317288Y1136481D03*
X309886Y1142859D03*
X317288Y1149237D03*
X309886D03*
X315437Y1146048D03*
X320988Y1136481D03*
X319138Y1139670D03*
X320988Y1149237D03*
X319138Y1146048D03*
X320988Y1142859D03*
X317288D03*
X315437Y1158804D03*
X317288Y1155615D03*
X309886D03*
X313587D03*
X308036Y1158804D03*
X311736Y1165182D03*
X320988Y1155615D03*
Y1161993D03*
X319138Y1152426D03*
X315437D03*
X319138Y1158804D03*
X311115Y1214093D03*
X310957Y1219126D03*
X311009Y1507514D03*
X316316Y1507295D03*
X321041D03*
X306694Y1507279D03*
X308893Y1507460D03*
X319316Y1521453D03*
X314592D03*
X313750Y1519195D03*
X314922Y1514243D03*
X319646D03*
X316217Y1516970D03*
X320941D03*
X317792Y1519698D03*
X306807Y1513218D03*
X319867Y1528853D03*
X315143D03*
X319366Y1536063D03*
X314641D03*
X316217Y1530608D03*
X320941D03*
X317792Y1533336D03*
X319867Y1526353D03*
X315143D03*
X319316Y1523953D03*
X314592D03*
X311113Y1542425D03*
X316316Y1542641D03*
X321041D03*
X311113Y1544625D03*
X307042Y1540317D03*
X318626Y1592380D03*
X306566D03*
X314366D03*
X308326Y1602380D03*
X312606D03*
X320386D03*
X314366Y1624292D03*
X318626D03*
X306566D03*
X320386Y1614292D03*
X312606D03*
X308326D03*
X315944Y1675383D03*
Y1679920D03*
Y1684454D03*
X308070Y1683857D03*
Y1679320D03*
X315944Y1689556D03*
Y1694093D03*
Y1698627D03*
X308070Y1698030D03*
Y1693493D03*
Y1688391D03*
X315944Y1703729D03*
Y1708266D03*
Y1712800D03*
X308070Y1716737D03*
Y1712203D03*
Y1707666D03*
Y1702564D03*
X315944Y1722440D03*
Y1726974D03*
X308070Y1730911D03*
Y1726377D03*
Y1721840D03*
X315944Y1717903D03*
X327209Y876435D03*
X332760Y879624D03*
X325358D03*
X334598Y872066D03*
X327209Y882813D03*
X334610D03*
X321658Y886002D03*
X325358D03*
X330910Y882813D03*
X329059Y886002D03*
X334610Y889191D03*
X327209D03*
X334610Y895569D03*
X321658Y892380D03*
X327209Y895569D03*
X329059Y892380D03*
X323508Y889191D03*
X325358Y892380D03*
X323508Y895569D03*
X332760Y886002D03*
X330910Y889191D03*
Y895569D03*
X332760Y892380D03*
X323508Y882813D03*
X334610Y901947D03*
X321658Y898758D03*
X327209Y901947D03*
X329059Y898758D03*
X321658Y905135D03*
Y911513D03*
X329059Y905135D03*
Y911513D03*
X327209Y908325D03*
X334610Y908324D03*
X325358Y911513D03*
X323508Y901947D03*
X325358Y905135D03*
X323508Y908325D03*
X325358Y898758D03*
X330910Y908325D03*
X332760Y898758D03*
X330910Y901947D03*
X332760Y905135D03*
Y911513D03*
X334610Y914702D03*
X321658Y917891D03*
X327209Y914702D03*
X329059Y917891D03*
X334610Y921080D03*
X321658Y924269D03*
X329059D03*
X327209Y921080D03*
X323508D03*
X325358Y924269D03*
X323508Y914702D03*
X325358Y917891D03*
X332760D03*
X330910Y921080D03*
X332760Y924269D03*
X330910Y914702D03*
X334610Y927458D03*
Y933836D03*
X321658Y930647D03*
X327209Y927458D03*
Y933836D03*
X329059Y930647D03*
X334610Y940214D03*
X321658Y937025D03*
X327209Y940214D03*
X329059Y937025D03*
X323508Y927458D03*
X325358Y930647D03*
X323508Y940214D03*
Y933836D03*
X325358Y937025D03*
X330910Y927458D03*
X332760Y937025D03*
X330910Y940214D03*
Y933836D03*
X332760Y930647D03*
X329059Y956159D03*
X334610Y946592D03*
X321658Y943403D03*
Y949781D03*
X329059Y943403D03*
Y949781D03*
X327209Y946592D03*
X334610Y952970D03*
X321658Y956159D03*
X327209Y952970D03*
X325358Y943403D03*
X323508Y946592D03*
X325358Y949781D03*
X323508Y952970D03*
X325358Y956159D03*
X332760Y943403D03*
X330910Y946592D03*
X332760Y956159D03*
X330910Y952970D03*
X332760Y949781D03*
X334610Y959348D03*
Y965726D03*
X329059Y962537D03*
X327209Y965726D03*
X321658Y962537D03*
X327209Y959348D03*
X321658Y968915D03*
X329059D03*
X323508Y965726D03*
X325358Y968915D03*
X323508Y959348D03*
X325358Y962537D03*
X332760D03*
X330910Y965726D03*
Y959348D03*
X332760Y968915D03*
X334610Y972104D03*
Y978482D03*
X321658Y975293D03*
Y981671D03*
X329059Y975293D03*
X327209Y972104D03*
X332760Y981671D03*
X329059D03*
X327209Y978482D03*
X334610Y984860D03*
X327209D03*
X330910D03*
X323508D03*
Y978482D03*
X325358Y981671D03*
X323508Y972104D03*
X325358Y975293D03*
X332760D03*
X330910Y978482D03*
Y972104D03*
X334610Y991238D03*
Y997616D03*
X321658Y988049D03*
Y994427D03*
X327209Y991238D03*
X329059Y988049D03*
Y994427D03*
X327209Y997616D03*
X321658Y1000805D03*
X329059D03*
X325358Y988049D03*
X323508Y997616D03*
X325358Y1000805D03*
Y994427D03*
X332760D03*
X330910Y997616D03*
X332760Y1000805D03*
X330910Y991238D03*
X332760Y988049D03*
X323508Y991238D03*
X334610Y1003994D03*
Y1010372D03*
X321658Y1007183D03*
X327209Y1010372D03*
X329059Y1007183D03*
X327209Y1003994D03*
X323508D03*
X325358Y1007183D03*
X330910Y1010372D03*
X332760Y1007183D03*
X330910Y1003994D03*
X323508Y1010372D03*
X328390Y1028056D03*
X335791D03*
X324689D03*
X332091D03*
X322839Y1031245D03*
Y1037623D03*
Y1044001D03*
X328390Y1040812D03*
Y1034434D03*
X330240Y1031245D03*
Y1037623D03*
Y1044001D03*
X335791Y1040812D03*
Y1034434D03*
X326539Y1031245D03*
X324689Y1034434D03*
X326539Y1037623D03*
X324689Y1040812D03*
X332091Y1034434D03*
X333941Y1037623D03*
X332091Y1040812D03*
X333941Y1044001D03*
Y1031245D03*
X326540Y1044001D03*
X328390Y1047190D03*
X322839Y1050379D03*
Y1056757D03*
X326539D03*
X328390Y1053568D03*
Y1059946D03*
X324689D03*
X330240Y1050379D03*
Y1056757D03*
X335791Y1047190D03*
Y1053568D03*
Y1059946D03*
X326539Y1050379D03*
X324689Y1047190D03*
X332091Y1059946D03*
X333941Y1050379D03*
X332091Y1053568D03*
X333941Y1056757D03*
X332091Y1047190D03*
X324689Y1053568D03*
X328390Y1072702D03*
X330240Y1069513D03*
X335791Y1072702D03*
Y1066324D03*
X322839Y1063135D03*
X330240D03*
X322839Y1069513D03*
X328390Y1066324D03*
X326539Y1063135D03*
X324689Y1066324D03*
X326539Y1069513D03*
X324689Y1072702D03*
X332091D03*
X333941Y1063135D03*
Y1069513D03*
X332091Y1066324D03*
X322839Y1075891D03*
X330240D03*
X328390Y1079080D03*
X322839Y1088647D03*
X328390Y1085458D03*
X330240Y1088647D03*
X322839Y1082269D03*
X330240D03*
X335791Y1079080D03*
Y1085458D03*
X326539Y1075891D03*
X324689Y1079080D03*
X326539Y1082269D03*
X324689Y1085458D03*
X326539Y1088647D03*
X333941Y1075891D03*
X332091Y1079080D03*
X333941Y1082269D03*
Y1088647D03*
X332091Y1085458D03*
X328390Y1091836D03*
X322839Y1095025D03*
X330240D03*
X328390Y1104592D03*
Y1098214D03*
X322839Y1101403D03*
X330240D03*
X335791Y1091836D03*
Y1104592D03*
Y1098214D03*
X324689Y1104592D03*
X326539Y1095025D03*
X324689Y1098214D03*
X326539Y1101403D03*
X324689Y1091836D03*
X333941Y1101403D03*
X332091Y1091836D03*
X333941Y1095025D03*
X332091Y1098214D03*
Y1104592D03*
X322839Y1107781D03*
X330240D03*
X328390Y1110970D03*
Y1117348D03*
X330240Y1114159D03*
X322839D03*
X335791Y1110970D03*
Y1117348D03*
X326539Y1114159D03*
X324689Y1117348D03*
X326539Y1107781D03*
X324689Y1110970D03*
X332091D03*
X333941Y1114159D03*
X332091Y1117348D03*
X333941Y1107781D03*
X330240Y1126915D03*
X322839D03*
X328390Y1123726D03*
X330240Y1120537D03*
X322839D03*
Y1133293D03*
X330240D03*
X328390Y1130103D03*
X335791Y1123726D03*
X335792Y1130105D03*
X326539Y1120537D03*
X324689Y1123726D03*
X326539Y1133293D03*
Y1126915D03*
X324689Y1130103D03*
X333941Y1120537D03*
X332091Y1130103D03*
X333941Y1133293D03*
Y1126915D03*
X332091Y1123726D03*
X328390Y1142859D03*
X322839Y1139670D03*
X328390Y1136481D03*
X330240Y1139670D03*
X328390Y1149237D03*
X330240Y1146048D03*
X322839D03*
X335791Y1136481D03*
Y1142859D03*
Y1149237D03*
X324689Y1136481D03*
X326539Y1139670D03*
X324689Y1142859D03*
X326539Y1146048D03*
X324689Y1149237D03*
X332091Y1136481D03*
X333941Y1139670D03*
X332091Y1149237D03*
X333941Y1146048D03*
X332091Y1142859D03*
X328390Y1155615D03*
X330240Y1152426D03*
X322839D03*
X326539Y1158804D03*
X330240D03*
X333941D03*
X322839D03*
X328390Y1161993D03*
X330240Y1165182D03*
X335791Y1155615D03*
Y1161993D03*
X326539Y1152426D03*
X324689Y1155615D03*
X333941Y1152426D03*
X332091Y1155615D03*
Y1161993D03*
X333941Y1165182D03*
X326539D03*
X324689Y1161993D03*
X330489Y1507295D03*
X335214D03*
X325765D03*
X333489Y1521453D03*
X328765D03*
X324041D03*
X324371Y1514243D03*
X329095D03*
X333820D03*
X325666Y1516970D03*
X330390D03*
X335114D03*
X322516Y1519698D03*
X327240D03*
X331965D03*
X333540Y1536063D03*
X334040Y1528853D03*
X329316D03*
X324592D03*
X324091Y1536063D03*
X328815D03*
X325666Y1530608D03*
X330390D03*
X335114D03*
X322516Y1533336D03*
X327240D03*
X331965D03*
X324041Y1523953D03*
X324592Y1526353D03*
X328765Y1523953D03*
X329316Y1526353D03*
X334040D03*
X333489Y1523953D03*
X325765Y1542641D03*
X330489D03*
X335214D03*
X330686Y1592380D03*
X326426D03*
X324666Y1602380D03*
X332446D03*
X326426Y1624292D03*
X330686D03*
X332446Y1614292D03*
X324666D03*
X331692Y1675383D03*
Y1679920D03*
Y1684454D03*
X323818Y1683857D03*
Y1679320D03*
X331692Y1689556D03*
Y1694093D03*
Y1698627D03*
X323818Y1698030D03*
Y1693493D03*
Y1688391D03*
X331692Y1703729D03*
Y1708266D03*
Y1712800D03*
X323818Y1716737D03*
Y1712203D03*
Y1707666D03*
Y1702564D03*
Y1721840D03*
X331692Y1717903D03*
Y1722440D03*
Y1726974D03*
X323818Y1730911D03*
Y1726377D03*
X343862Y879624D03*
X340162Y879568D03*
X345713Y882813D03*
X336461Y886002D03*
X340162D03*
X347563D03*
X342012Y882813D03*
X347563Y892380D03*
X342012Y889191D03*
X340162Y892380D03*
X343862Y886002D03*
X349414Y889191D03*
X345713D03*
Y895569D03*
X349414D03*
X343862Y892380D03*
X338311Y889191D03*
X336461Y892380D03*
X338311Y895569D03*
X342012D03*
X347563Y898758D03*
Y905135D03*
Y911513D03*
X342012Y901947D03*
X340162Y898758D03*
Y911513D03*
X342012Y908325D03*
X345713D03*
X343862Y898758D03*
X349414Y901947D03*
X345713D03*
X343862Y905135D03*
X349414Y908325D03*
X343862Y911513D03*
X336461D03*
X338311Y901947D03*
X336461Y905135D03*
X338311Y908325D03*
X336461Y898758D03*
X340162Y905135D03*
X347563Y917891D03*
Y924269D03*
X340162Y917891D03*
X342012Y921080D03*
X343862Y917891D03*
X349414Y921080D03*
X345713D03*
X343862Y924269D03*
X345713Y914702D03*
X349414D03*
X338311Y921080D03*
X336461Y924269D03*
X338311Y914702D03*
X336461Y917891D03*
X340162Y924269D03*
X342012Y914702D03*
X347563Y930647D03*
Y937025D03*
X342012Y927458D03*
X340162Y930647D03*
X342012Y940214D03*
X340162Y937025D03*
X349414Y927458D03*
X345713D03*
X343862Y937025D03*
X349414Y940214D03*
X345713D03*
Y933836D03*
X349414D03*
X343862Y930647D03*
X338311Y927458D03*
X336461Y930647D03*
X338311Y940214D03*
Y933836D03*
X336461Y937025D03*
X342012Y933836D03*
X347563Y943403D03*
Y949781D03*
Y956159D03*
X340162Y949781D03*
X342012Y946592D03*
X340162Y956159D03*
X343862Y943403D03*
X349414Y946592D03*
X345713D03*
X343862Y956159D03*
X345713Y952970D03*
X349414D03*
X343862Y949781D03*
X336461Y943403D03*
X338311Y946592D03*
X336461Y949781D03*
X338311Y952970D03*
X336461Y956159D03*
X342012Y952970D03*
X340162Y943403D03*
X347563Y962537D03*
Y968915D03*
X342012Y959348D03*
Y965726D03*
X340162Y968915D03*
X343862Y962537D03*
X349414Y965726D03*
X345713D03*
X349414Y959348D03*
X345713D03*
X343862Y968915D03*
X338311Y965726D03*
X336461Y968915D03*
X338311Y959348D03*
X336461Y962537D03*
X340162D03*
X347563Y975293D03*
Y981671D03*
X345713Y984860D03*
X340162Y975293D03*
X343862Y981671D03*
X342012Y978482D03*
Y984860D03*
X349414D03*
X343862Y975293D03*
X349414Y978482D03*
X345713D03*
Y972104D03*
X349414D03*
X338311Y984860D03*
Y978482D03*
X336461Y981671D03*
X338311Y972104D03*
X336461Y975293D03*
X342012Y972104D03*
X340162Y981671D03*
X347563Y988049D03*
Y994427D03*
Y1000805D03*
X340162Y988049D03*
X342012Y997616D03*
X340162Y994427D03*
X343862D03*
X345713Y997616D03*
X349414D03*
X343862Y1000805D03*
X345713Y991238D03*
X336461Y988049D03*
X338311Y997616D03*
X336461Y1000805D03*
Y994427D03*
X340162Y1000805D03*
X342012Y991238D03*
X338311D03*
X349414D03*
X343862Y988049D03*
X347563Y1007183D03*
X342012Y1010372D03*
X340162Y1007183D03*
X342012Y1003994D03*
X345713Y1010372D03*
X343862Y1007183D03*
X345713Y1003994D03*
X349414D03*
X338311D03*
X336461Y1007183D03*
X338311Y1010372D03*
X349414D03*
X343193Y1028056D03*
X350595D03*
X339492D03*
X346894D03*
X348744Y1031245D03*
X341343D03*
X343193Y1040812D03*
X348744Y1037623D03*
X343193Y1034434D03*
X348744Y1044001D03*
X341343D03*
X350595Y1034434D03*
X346894D03*
X345043Y1037623D03*
X350595Y1040812D03*
X346894D03*
X345043Y1044001D03*
X337642Y1031245D03*
X339492Y1034434D03*
X337642Y1037623D03*
X339492Y1040812D03*
X341343Y1037623D03*
X337642Y1044001D03*
X345043Y1031245D03*
X350595Y1059946D03*
X337642Y1056757D03*
X348744D03*
X343193Y1053568D03*
X341343Y1050379D03*
X348744D03*
X343193Y1059946D03*
X339492D03*
X346894D03*
X350595Y1047190D03*
X345043Y1050379D03*
X346894Y1053568D03*
X337642Y1050379D03*
X339492Y1047190D03*
X341343Y1056757D03*
X343193Y1047190D03*
X339492Y1053568D03*
X345043Y1056757D03*
X346894Y1047190D03*
X350595Y1053568D03*
X341343Y1063135D03*
X348744D03*
X341343Y1069513D03*
X343193Y1072702D03*
X348744Y1069513D03*
X346894Y1072702D03*
X345043Y1063135D03*
X350595Y1066324D03*
X345043Y1069513D03*
X350595Y1072702D03*
X346894Y1066324D03*
X337642Y1063135D03*
X339492Y1066324D03*
X337642Y1069513D03*
X339492Y1072702D03*
X343193Y1066324D03*
Y1079080D03*
X348744Y1075891D03*
X341343Y1082269D03*
X348744D03*
X341343Y1088647D03*
X348744D03*
X345043Y1075891D03*
X350595Y1079080D03*
X346894D03*
X345043Y1082269D03*
X350595Y1085458D03*
X345043Y1088647D03*
X346894Y1085458D03*
X337642Y1075891D03*
X339492Y1079080D03*
X337642Y1082269D03*
X339492Y1085458D03*
X337642Y1088647D03*
X343193Y1085458D03*
X341343Y1075891D03*
X348744Y1095025D03*
X343193Y1091836D03*
X348744Y1101403D03*
X341343D03*
X343193Y1098214D03*
X345043Y1101403D03*
X350595Y1104592D03*
X346894Y1091836D03*
X345043Y1095025D03*
X350595Y1098214D03*
X346894D03*
Y1104592D03*
X350595Y1091836D03*
X339492Y1104592D03*
X337642Y1095025D03*
X339492Y1098214D03*
X337642Y1101403D03*
X339492Y1091836D03*
X341343Y1095025D03*
X343193Y1104592D03*
X341343Y1107781D03*
X348744D03*
X343193Y1110970D03*
Y1117348D03*
X348744Y1114159D03*
X346894Y1110970D03*
X345043Y1114159D03*
X350595Y1117348D03*
X346894D03*
X345043Y1107781D03*
X350595Y1110970D03*
X337642Y1114159D03*
X339492Y1117348D03*
X337642Y1107781D03*
X339492Y1110970D03*
X341343Y1114159D03*
X348744Y1120537D03*
X341343D03*
Y1126915D03*
X348744D03*
Y1133293D03*
X343193Y1130103D03*
X345043Y1120537D03*
X350595Y1123726D03*
X346894Y1130103D03*
X345043Y1133293D03*
Y1126915D03*
X346894Y1123726D03*
X350595Y1130103D03*
X337642Y1120537D03*
X339492Y1123726D03*
X337642Y1133293D03*
Y1126915D03*
X339492Y1130103D03*
X343193Y1123726D03*
X341343Y1133293D03*
Y1139670D03*
X343193Y1136481D03*
X348744Y1139670D03*
X343193Y1149237D03*
X348744Y1146048D03*
X341343D03*
X350595Y1136481D03*
X346894D03*
X345043Y1139670D03*
X350595Y1142859D03*
X346894Y1149237D03*
X345043Y1146048D03*
X346894Y1142859D03*
X350595Y1149237D03*
X339492Y1136481D03*
X337642Y1139670D03*
X339492Y1142859D03*
X337642Y1146048D03*
X339492Y1149237D03*
X343193Y1142859D03*
X348744Y1152426D03*
X337642Y1158804D03*
X341343D03*
X348744D03*
X339492Y1155615D03*
X343193D03*
X346894D03*
X337642Y1165182D03*
X343193Y1161993D03*
X346894D03*
X348744Y1165182D03*
X345043Y1152426D03*
X350595Y1155615D03*
X337642Y1152426D03*
X339492Y1161993D03*
X341343Y1165182D03*
X350595Y1161993D03*
X341343Y1152426D03*
X345043Y1158804D03*
X339938Y1507295D03*
X344663D03*
X349387D03*
X347663Y1521453D03*
X342938D03*
X338214D03*
X338544Y1514243D03*
X343268D03*
X347993D03*
X339839Y1516970D03*
X344563D03*
X349288D03*
X336689Y1519698D03*
X341414D03*
X346138D03*
X350862D03*
X338264Y1536063D03*
X347713D03*
X348214Y1528853D03*
X343489D03*
X338765D03*
X342988Y1536063D03*
X339839Y1530608D03*
X344563D03*
X349288D03*
X336689Y1533336D03*
X341414D03*
X346138D03*
X350862D03*
X338765Y1526353D03*
X338214Y1523953D03*
X347663D03*
X348214Y1526353D03*
X343489D03*
X342938Y1523953D03*
X339938Y1542641D03*
X344663D03*
X349387D03*
X338486Y1592380D03*
X342746D03*
X350546D03*
X336726Y1602380D03*
X344506D03*
X348786D03*
X350546Y1624292D03*
X342746D03*
X338486D03*
X348786Y1614292D03*
X344506D03*
X336726D03*
X347440Y1675383D03*
Y1679920D03*
Y1684454D03*
X339566Y1683857D03*
Y1679320D03*
X347440Y1694093D03*
Y1698627D03*
X339566Y1698030D03*
Y1693493D03*
Y1688391D03*
X347440Y1689556D03*
Y1703729D03*
Y1708266D03*
Y1712800D03*
X339566Y1716737D03*
Y1712203D03*
Y1707666D03*
Y1702564D03*
X347440Y1717903D03*
Y1722440D03*
Y1726974D03*
X339566Y1730911D03*
Y1726377D03*
Y1721840D03*
X351265Y879568D03*
X360516Y876435D03*
X354965Y879624D03*
X356803Y872066D03*
X364217Y876435D03*
X358665Y879624D03*
X351264Y886002D03*
X362366D03*
X356815Y882813D03*
X360516D03*
X353114D03*
X354965Y886002D03*
Y892380D03*
X360516Y889191D03*
Y895569D03*
X353114Y889191D03*
Y895569D03*
X351264Y892380D03*
X358665Y886002D03*
X364217Y889191D03*
X356815D03*
X362366Y892380D03*
X356815Y895569D03*
X364217D03*
X358665Y892380D03*
X354965Y898758D03*
X360516Y901947D03*
X353114D03*
X354965Y911513D03*
Y905135D03*
X360516Y908325D03*
X353114Y908324D03*
X351264Y911513D03*
Y905135D03*
Y898758D03*
X356815Y908325D03*
X362366Y911513D03*
X358665Y898758D03*
X364217Y901947D03*
X356815D03*
X362366Y905135D03*
X358665D03*
X364217Y908325D03*
X358665Y911513D03*
X362366Y898758D03*
X354965Y917891D03*
X360516Y914702D03*
X353114D03*
X354965Y924269D03*
X360516Y921080D03*
X353114D03*
X351264Y924269D03*
Y917891D03*
X358665D03*
X364217Y921080D03*
X356815D03*
X362366Y924269D03*
X358665D03*
X356815Y914702D03*
X364217D03*
X362366Y917891D03*
X354965Y930647D03*
X360516Y927458D03*
Y933836D03*
X353114D03*
Y927458D03*
X354965Y937025D03*
X360516Y940214D03*
X353114D03*
X351264Y930647D03*
Y937025D03*
X364217Y927458D03*
X356815D03*
X362366Y930647D03*
X358665Y937025D03*
X364217Y940214D03*
X356815D03*
Y933836D03*
X364217D03*
X358665Y930647D03*
X362366Y937025D03*
X360516Y946592D03*
X353114D03*
X360516Y952970D03*
X353114D03*
X354965Y956159D03*
Y943403D03*
Y949781D03*
X351264Y943403D03*
Y949781D03*
Y956159D03*
X362366Y943403D03*
X358665D03*
X364217Y946592D03*
X356815D03*
X362366Y949781D03*
X358665Y956159D03*
X356815Y952970D03*
X364217D03*
X358665Y949781D03*
X362366Y956159D03*
X360516Y959348D03*
Y965726D03*
X353114Y959348D03*
Y965726D03*
X354965Y962537D03*
Y968915D03*
X351264D03*
Y962537D03*
X358665D03*
X364217Y965726D03*
X356815D03*
X362366Y968915D03*
X364217Y959348D03*
X356815D03*
X362366Y962537D03*
X358665Y968915D03*
X354965Y975293D03*
Y981671D03*
X360516Y972104D03*
Y978482D03*
X358665Y981671D03*
X353114Y972104D03*
Y978482D03*
X360516Y984860D03*
X356815D03*
X353114D03*
X351264Y981671D03*
Y975293D03*
X364217Y984860D03*
X358665Y975293D03*
X364217Y978482D03*
X356815D03*
X362366Y981671D03*
X356815Y972104D03*
X364217D03*
X362366Y975293D03*
X360516Y997616D03*
Y991238D03*
X353114D03*
Y997616D03*
X354965Y988049D03*
Y994427D03*
Y1000805D03*
X351264Y988049D03*
Y1000805D03*
Y994427D03*
X362366Y988049D03*
X358665Y994427D03*
X356815Y997616D03*
X364217D03*
X362366Y1000805D03*
X358665D03*
X356815Y991238D03*
X362366Y994427D03*
X364217Y991238D03*
X358666Y988049D03*
X354965Y1007183D03*
X360516Y1003994D03*
X353114D03*
X360516Y1010372D03*
X353114D03*
X351264Y1007183D03*
X356815Y1010372D03*
X358665Y1007183D03*
X356815Y1003994D03*
X364217D03*
X362366Y1007183D03*
X364217Y1010372D03*
X354295Y1028056D03*
X361697D03*
X365398D03*
X357996D03*
X361697Y1040812D03*
X356146Y1044001D03*
X354295Y1040812D03*
Y1034434D03*
X356146Y1031245D03*
Y1037623D03*
X361697Y1034434D03*
X352445Y1031245D03*
Y1037623D03*
X363547Y1031245D03*
X365398Y1034434D03*
X357996D03*
X359847Y1037623D03*
X363547D03*
X365398Y1040812D03*
X357996D03*
X359847Y1044001D03*
X363547D03*
X359847Y1031245D03*
X352445Y1044001D03*
X354295Y1047190D03*
X361697D03*
X354295Y1053568D03*
Y1059946D03*
X363547Y1056757D03*
X356146D03*
Y1050379D03*
X361697Y1053568D03*
X365398Y1059946D03*
X361697D03*
X352445Y1056757D03*
Y1050379D03*
X363547D03*
X357996Y1059946D03*
X365398Y1047190D03*
X359847Y1050379D03*
X357996Y1053568D03*
X359847Y1056757D03*
X357996Y1047190D03*
X365398Y1053568D03*
X356146Y1063135D03*
X354295Y1072702D03*
Y1066324D03*
X356146Y1069513D03*
X361697Y1066324D03*
Y1072702D03*
X352445Y1063135D03*
Y1069513D03*
X357996Y1072702D03*
X363547Y1063135D03*
X359847D03*
X365398Y1066324D03*
X363547Y1069513D03*
X359847D03*
X365398Y1072702D03*
X357996Y1066324D03*
X356146Y1075891D03*
X354295Y1079080D03*
X361697D03*
X354295Y1085458D03*
X356146Y1088647D03*
X361697Y1085458D03*
X356146Y1082269D03*
X352445Y1075891D03*
Y1082269D03*
Y1088647D03*
X363547Y1075891D03*
X359847D03*
X365398Y1079080D03*
X357996D03*
X363547Y1082269D03*
X359847D03*
X365398Y1085458D03*
X359847Y1088647D03*
X363547D03*
X357996Y1085458D03*
X354295Y1091836D03*
X361697D03*
X356146Y1095025D03*
X354295Y1104592D03*
Y1098214D03*
X361697Y1104592D03*
X356146Y1101403D03*
X361697Y1098214D03*
X352445Y1095025D03*
Y1101403D03*
X359847D03*
X365398Y1104592D03*
X357996Y1091836D03*
X363547Y1095025D03*
X359847D03*
X365398Y1098214D03*
X357996D03*
X363547Y1101403D03*
X357996Y1104592D03*
X365398Y1091836D03*
X356146Y1107781D03*
X354295Y1110970D03*
X361697D03*
Y1117348D03*
X356146Y1114159D03*
X354295Y1117348D03*
X352445Y1114159D03*
Y1107781D03*
X357996Y1110970D03*
X363547Y1114159D03*
X359847D03*
X365398Y1117348D03*
X357996D03*
X359847Y1107781D03*
X363547D03*
X365398Y1110970D03*
X354295Y1123726D03*
X356146Y1126915D03*
Y1120537D03*
X361697Y1123726D03*
X356146Y1133293D03*
X361697Y1130103D03*
X354296Y1130105D03*
X352445Y1120537D03*
Y1133293D03*
Y1126915D03*
X363547Y1120537D03*
X359847D03*
X365398Y1123726D03*
X357996Y1130103D03*
X363547Y1133293D03*
X359847D03*
Y1126915D03*
X363547D03*
X357996Y1123726D03*
X365398Y1130103D03*
X354295Y1136481D03*
X356146Y1139670D03*
X361697Y1136481D03*
X354295Y1142859D03*
X361697D03*
Y1149237D03*
X356146Y1146048D03*
X354295Y1149237D03*
X352445Y1139670D03*
Y1146048D03*
X365398Y1136481D03*
X357996D03*
X363547Y1139670D03*
X359847D03*
X365398Y1142859D03*
X357996Y1149237D03*
X359847Y1146048D03*
X363547D03*
X357996Y1142859D03*
X365398Y1149237D03*
X363547Y1165182D03*
X356146D03*
X361697Y1161993D03*
X363547Y1158804D03*
X356146D03*
X359847D03*
X352445D03*
X365398Y1155615D03*
X356146Y1152426D03*
X361697Y1155615D03*
X354295D03*
Y1161993D03*
X352445Y1152426D03*
X363547D03*
X359847D03*
X357996Y1155615D03*
X359847Y1165182D03*
X357996Y1161993D03*
X352445Y1165182D03*
X365398Y1161993D03*
X354111Y1507295D03*
X358836D03*
X363560D03*
X361836Y1521453D03*
X357111D03*
X352387D03*
X352717Y1514243D03*
X357442D03*
X362166D03*
X363461Y1516970D03*
X354012D03*
X358736D03*
X365036Y1519698D03*
X355587D03*
X360311D03*
X357162Y1536063D03*
X361886D03*
X362387Y1528853D03*
X357662D03*
X352938D03*
X352437Y1536063D03*
X363461Y1530608D03*
X354012D03*
X358736D03*
X365036Y1533336D03*
X355587D03*
X360311D03*
X362387Y1526353D03*
X361836Y1523953D03*
X352387D03*
X352938Y1526353D03*
X357662D03*
X357111Y1523953D03*
X354111Y1542641D03*
X358836D03*
X363560D03*
X362606Y1592380D03*
X354806D03*
X356566Y1602380D03*
X360846D03*
X354806Y1624292D03*
X360846Y1614292D03*
X356566D03*
X362606Y1624292D03*
X355314Y1683857D03*
Y1679320D03*
Y1688391D03*
Y1698030D03*
Y1693493D03*
Y1716737D03*
Y1712203D03*
Y1707666D03*
Y1702564D03*
Y1730911D03*
Y1726377D03*
Y1721840D03*
X369768Y879624D03*
X373469D03*
X375319Y876435D03*
X377169Y879624D03*
X367917Y876435D03*
X371618D03*
X379020D03*
X369768Y873246D03*
X373469D03*
X377169D03*
X366067Y886002D03*
Y892380D03*
X367917Y889191D03*
X373469Y892380D03*
X367917Y882813D03*
X373469Y886002D03*
X379020Y882813D03*
X377169Y886002D03*
X379020Y895569D03*
X369768Y886002D03*
X375319Y889191D03*
X371618D03*
X377169Y892380D03*
X371618Y895569D03*
X375319D03*
X369768Y892380D03*
X371618Y882813D03*
X375319D03*
X379020Y889191D03*
X367917Y895569D03*
X366067Y898758D03*
Y911513D03*
X367917Y901947D03*
X373469Y898758D03*
X379020Y908325D03*
X373469Y911513D03*
Y905135D03*
X367917Y908324D03*
X371618Y908325D03*
X377169Y911513D03*
X369768Y898758D03*
X375319Y901947D03*
X371618D03*
X377169Y905135D03*
X369768D03*
X375319Y908325D03*
X369768Y911513D03*
X377169Y898758D03*
X366067Y905135D03*
X379020Y901947D03*
X366067Y917891D03*
X373469D03*
X367917Y921080D03*
X373469Y924269D03*
X379020Y921080D03*
X369768Y917891D03*
X375319Y921080D03*
X371618D03*
X377169Y924269D03*
X369768D03*
X371618Y914702D03*
X375319D03*
X377169Y917891D03*
X366067Y924269D03*
X367917Y914702D03*
X379020D03*
X366067Y930647D03*
Y937025D03*
X367917Y927458D03*
X379020Y933836D03*
X373469Y930647D03*
X367917Y940214D03*
X373469Y937025D03*
X379020Y940214D03*
X375319Y927458D03*
X371618D03*
X377169Y930647D03*
X369768Y937025D03*
X375319Y940214D03*
X371618D03*
Y933836D03*
X375319D03*
X369768Y930647D03*
X377169Y937025D03*
X367917Y933836D03*
X379020Y927458D03*
X366067Y949781D03*
Y956159D03*
X367917Y946592D03*
X373469Y943403D03*
Y949781D03*
Y956159D03*
X379020Y952970D03*
X377169Y943403D03*
X369768D03*
X375319Y946592D03*
X371618D03*
X377169Y949781D03*
X369768Y956159D03*
X371618Y952970D03*
X375319D03*
X369768Y949781D03*
X377169Y956159D03*
X366067Y943403D03*
X367917Y952970D03*
X379020Y946592D03*
X366067Y968915D03*
X367917Y959348D03*
Y965726D03*
X373469Y962537D03*
Y968915D03*
X379020Y965726D03*
X369768Y962537D03*
X375319Y965726D03*
X371618D03*
X377169Y968915D03*
X375319Y959348D03*
X371618D03*
X377169Y962537D03*
X369768Y968915D03*
X366067Y962537D03*
X379020Y959348D03*
X366067Y975293D03*
X369768Y981671D03*
X367917Y978482D03*
X373469Y975293D03*
Y981671D03*
X367917Y984860D03*
X379020D03*
X371618D03*
X379020Y978482D03*
X375319Y984860D03*
X369768Y975293D03*
X375319Y978482D03*
X371618D03*
X377169Y981671D03*
X371618Y972104D03*
X375319D03*
X377169Y975293D03*
X366067Y981671D03*
X367917Y972104D03*
X379020D03*
X366067Y994427D03*
Y988049D03*
X367917Y997616D03*
X379020Y991238D03*
X373469Y988049D03*
X379020Y997616D03*
X373469Y994427D03*
Y1000805D03*
X377169Y988049D03*
X369768Y994427D03*
X371618Y997616D03*
X375319D03*
X377169Y1000805D03*
X369768D03*
X371618Y991238D03*
X377169Y994427D03*
X366067Y1000805D03*
X367917Y991238D03*
X375319D03*
X369768Y988049D03*
X366067Y1007183D03*
X373469D03*
X367917Y1003994D03*
X379020D03*
X367917Y1010372D03*
X371618D03*
X369768Y1007183D03*
X371618Y1003994D03*
X375319D03*
X377169Y1007183D03*
X379020Y1010372D03*
X375319D03*
X380201Y1028056D03*
X369099D03*
X376500D03*
X372799D03*
X367248Y1031245D03*
Y1044001D03*
X369099Y1034434D03*
Y1040812D03*
X374650Y1031245D03*
X380201Y1040812D03*
Y1034434D03*
X374650Y1037623D03*
Y1044001D03*
X378351Y1031245D03*
X376500Y1034434D03*
X372799D03*
X370949Y1037623D03*
X378351D03*
X376500Y1040812D03*
X372799D03*
X370949Y1044001D03*
X367248Y1037623D03*
X378351Y1044001D03*
X370949Y1031245D03*
X367248Y1050379D03*
X380201Y1047190D03*
X369099Y1053568D03*
Y1059946D03*
X380201Y1053568D03*
X378351Y1056757D03*
X374650Y1050379D03*
Y1056757D03*
X380201Y1059946D03*
X376500D03*
X378351Y1050379D03*
X372799Y1059946D03*
X376500Y1047190D03*
X370949Y1050379D03*
X372799Y1053568D03*
X367248Y1056757D03*
X369099Y1047190D03*
X370949Y1056757D03*
X372799Y1047190D03*
X376500Y1053568D03*
X367248Y1063135D03*
Y1069513D03*
X374650Y1063135D03*
X369099Y1072702D03*
X380201D03*
X374650Y1069513D03*
X372799Y1072702D03*
X378351Y1063135D03*
X370949D03*
X376500Y1066324D03*
X378351Y1069513D03*
X370949D03*
X376500Y1072702D03*
X372799Y1066324D03*
X369099D03*
X380201D03*
X367248Y1088647D03*
Y1082269D03*
X374650Y1075891D03*
X369099Y1079080D03*
X380201Y1085458D03*
X374650Y1088647D03*
Y1082269D03*
X378351Y1075891D03*
X370949D03*
X376500Y1079080D03*
X372799D03*
X378351Y1082269D03*
X370949D03*
X376500Y1085458D03*
X370949Y1088647D03*
X378351D03*
X372799Y1085458D03*
X367248Y1075891D03*
X369099Y1085458D03*
X380201Y1079080D03*
X367248Y1101403D03*
X369099Y1091836D03*
X374650Y1095025D03*
X369099Y1098214D03*
X380201Y1104592D03*
Y1098214D03*
X374650Y1101403D03*
X370949D03*
X376500Y1104592D03*
X372799Y1091836D03*
X378351Y1095025D03*
X370949D03*
X376500Y1098214D03*
X372799D03*
X378351Y1101403D03*
X372799Y1104592D03*
X376500Y1091836D03*
X380201D03*
X367248Y1095025D03*
X369099Y1104592D03*
X367248Y1107781D03*
X374650D03*
X369099Y1110970D03*
Y1117348D03*
X380201D03*
X374650Y1114159D03*
X372799Y1110970D03*
X378351Y1114159D03*
X370949D03*
X376500Y1117348D03*
X372799D03*
X370949Y1107781D03*
X378351D03*
X376500Y1110970D03*
X367248Y1114159D03*
X380201Y1110970D03*
X367248Y1120537D03*
Y1126915D03*
X374650Y1120537D03*
Y1126915D03*
X380201Y1130103D03*
X374650Y1133293D03*
X369099Y1130103D03*
X378351Y1120537D03*
X370949D03*
X376500Y1123726D03*
X372799Y1130103D03*
X378351Y1133293D03*
X370949D03*
Y1126915D03*
X378351D03*
X372799Y1123726D03*
X376500Y1130103D03*
X369099Y1123726D03*
X367248Y1133293D03*
X380201Y1123726D03*
X367248Y1139670D03*
Y1146048D03*
X380201Y1142859D03*
X374650Y1139670D03*
X369099Y1136481D03*
Y1149237D03*
X374650Y1146048D03*
X376500Y1136481D03*
X372799D03*
X378351Y1139670D03*
X370949D03*
X376500Y1142859D03*
X372799Y1149237D03*
X370949Y1146048D03*
X378351D03*
X372799Y1142859D03*
X376500Y1149237D03*
X380201D03*
X369099Y1142859D03*
X380201Y1136481D03*
X378351Y1165182D03*
X374650D03*
X380201Y1155615D03*
X369099D03*
X372799D03*
X374650Y1152426D03*
X378351Y1158804D03*
X374650D03*
X376500Y1161993D03*
X378351Y1152426D03*
X370949D03*
X376500Y1155615D03*
X367248Y1158804D03*
X370949D03*
X369099Y1161993D03*
X372799D03*
X380201D03*
X367248Y1152426D03*
X377523Y1222274D03*
X372730Y1216782D03*
X367697Y1216624D03*
X377733Y1507295D03*
X368285D03*
X373009D03*
X376009Y1521453D03*
X380734D03*
X366560D03*
X371285D03*
X376339Y1514243D03*
X366890D03*
X371615D03*
X368185Y1516970D03*
X372910D03*
X377634D03*
X369760Y1519698D03*
X374484D03*
X379209D03*
X380784Y1536063D03*
X371335D03*
X376560Y1528853D03*
X367111D03*
X371836D03*
X376059Y1536063D03*
X366610D03*
X368185Y1530608D03*
X372910D03*
X377634D03*
X369760Y1533336D03*
X374484D03*
X379209D03*
X380734Y1523953D03*
X376560Y1526353D03*
X376009Y1523953D03*
X371285D03*
X371836Y1526353D03*
X367111D03*
X366560Y1523953D03*
X377733Y1542641D03*
X368285D03*
X373009D03*
X374666Y1592380D03*
X366866D03*
X380696Y1602380D03*
X368626Y1602286D03*
X372906Y1602380D03*
X374666Y1624292D03*
X380696Y1614292D03*
X372906D03*
X368626D03*
X366866Y1624292D03*
X386421Y876435D03*
X388272Y879624D03*
X384571Y873246D03*
X393823Y876435D03*
X382721D03*
X390122D03*
X380870Y879624D03*
X384571D03*
X380870Y873246D03*
X391973D03*
X395673D03*
Y879624D03*
X391973D03*
X388272Y892380D03*
X384571D03*
X395673D03*
X382721Y882813D03*
Y889191D03*
X380870Y892380D03*
X384571Y886002D03*
X386421Y882813D03*
X393823D03*
X388272Y886002D03*
X390122Y882813D03*
X391973Y892380D03*
X390122Y895569D03*
X386421Y889191D03*
X393823D03*
X391973Y886002D03*
X393823Y895569D03*
X380870Y886002D03*
X382721Y895569D03*
X390122Y889191D03*
X386421Y895569D03*
X395673Y886002D03*
X388272Y911513D03*
Y898758D03*
Y905135D03*
X384571Y911513D03*
Y898758D03*
Y905135D03*
X395673Y898758D03*
Y905135D03*
Y911513D03*
X382721Y901947D03*
X380870Y898758D03*
Y911513D03*
Y905135D03*
X393823Y901947D03*
X391973Y898758D03*
X390122Y901947D03*
X386421D03*
X391973Y905135D03*
Y911513D03*
X390122Y908325D03*
X393823D03*
X386421D03*
X382721D03*
X388272Y924269D03*
Y917891D03*
X384571Y924269D03*
Y917891D03*
X395673Y924269D03*
Y917891D03*
X382721Y914702D03*
X380870Y917891D03*
Y924269D03*
X386421Y914702D03*
X391973Y917891D03*
X393823Y914702D03*
X390122D03*
Y921080D03*
X391973Y924269D03*
X393823Y921080D03*
X382721D03*
X386421D03*
X388272Y930647D03*
X384571D03*
X395673D03*
X382721Y927458D03*
Y933836D03*
X380870Y930647D03*
X386421Y927458D03*
Y933836D03*
X393823Y927458D03*
X390122D03*
X393823Y933836D03*
X391973Y930647D03*
X390122Y933836D03*
Y940214D03*
X393823D03*
X382721D03*
X386421D03*
X380870Y937025D03*
X395673D03*
X388272D03*
X391973D03*
X384571D03*
Y949781D03*
Y943403D03*
Y956159D03*
X395673Y949781D03*
Y943403D03*
Y956159D03*
X388272Y949781D03*
Y943403D03*
Y956159D03*
X382721Y946592D03*
X380870Y943403D03*
Y949781D03*
Y956159D03*
X386421Y946592D03*
X391973Y943403D03*
Y949781D03*
X393823Y946592D03*
X390122D03*
X391973Y956159D03*
X390122Y952970D03*
X393823D03*
X382721D03*
X386421D03*
X382721Y959348D03*
X380870Y962537D03*
Y968915D03*
X393823Y959348D03*
X390122D03*
Y965726D03*
X386421Y959348D03*
X391973Y962537D03*
Y968915D03*
X393823Y965726D03*
X382721D03*
X386421D03*
X395673Y962537D03*
Y968915D03*
X384571Y962537D03*
Y968915D03*
X388272Y962537D03*
Y968915D03*
X386421Y984860D03*
X382721Y972104D03*
X380870Y975293D03*
X393823Y972104D03*
X390122D03*
Y978482D03*
X384571Y981671D03*
X391973D03*
Y975293D03*
X386421Y972104D03*
X393823Y984860D03*
X380870Y981671D03*
X382721Y984860D03*
X388272Y981671D03*
X390122Y984860D03*
X386421Y978482D03*
X393823D03*
X395673Y981671D03*
X382721Y978482D03*
X395673Y975293D03*
X384571D03*
X388272D03*
X391973Y988049D03*
X384571Y994427D03*
Y988049D03*
X391973Y994427D03*
X393823Y991238D03*
X386421D03*
Y997616D03*
X391973Y1000805D03*
X384571D03*
X393823Y997616D03*
X395673Y994427D03*
Y988049D03*
Y1000805D03*
X380870Y988049D03*
Y994427D03*
X382721Y997616D03*
Y991238D03*
X380870Y1000805D03*
X388272Y994427D03*
X390122Y997616D03*
X388272Y988049D03*
X390122Y991238D03*
X388272Y1000805D03*
X386421Y1003994D03*
X382721Y1010372D03*
X390122D03*
X391973Y1007183D03*
X393823Y1003994D03*
X395673Y1007183D03*
X384571D03*
X380870D03*
X382721Y1003994D03*
X388272Y1007183D03*
X390122Y1003994D03*
X393823Y1010372D03*
X386421D03*
X387603Y1028056D03*
X395004D03*
X391303D03*
X383902D03*
X393154Y1044001D03*
X385752Y1031245D03*
Y1037623D03*
Y1044001D03*
X395004Y1040812D03*
X387603Y1034434D03*
Y1040812D03*
X395004Y1034434D03*
X393154Y1031245D03*
Y1037623D03*
X382051Y1031245D03*
Y1037623D03*
Y1044001D03*
X391303Y1034434D03*
X389453Y1037623D03*
X391303Y1040812D03*
X389453Y1044001D03*
Y1031245D03*
X383902Y1040812D03*
Y1034434D03*
X385752Y1063135D03*
X389453D03*
X396855D03*
X395004Y1047190D03*
X387603D03*
Y1053568D03*
X391303Y1059946D03*
X395004Y1053568D03*
X385752Y1050379D03*
X393154Y1056757D03*
Y1050379D03*
X395004Y1059946D03*
X383902D03*
X387603D03*
X389453Y1056757D03*
X382051Y1050379D03*
X391303Y1047190D03*
X383902D03*
X391303Y1053568D03*
X389453Y1050379D03*
X383902Y1053568D03*
X385752Y1056757D03*
X382051D03*
X385752Y1069513D03*
X389453D03*
X396855D03*
Y1075891D03*
X385752D03*
X389453D03*
X382051Y1063135D03*
Y1069513D03*
X393154Y1063135D03*
X395004Y1066324D03*
X387603D03*
X383902D03*
X391303Y1072702D03*
Y1066324D03*
X393154Y1069513D03*
X385752D03*
Y1063135D03*
X389453Y1069513D03*
Y1063135D03*
X395004Y1072702D03*
X383902D03*
X387603D03*
X396855Y1088647D03*
Y1082269D03*
X385752Y1088647D03*
Y1082269D03*
X389453Y1088647D03*
Y1082269D03*
X382051Y1075891D03*
Y1088647D03*
Y1082269D03*
X393154Y1075891D03*
X387603Y1079080D03*
X383902D03*
X391303D03*
X395004D03*
X393154Y1082269D03*
X391303Y1085458D03*
X393154Y1088647D03*
X385752Y1075891D03*
X389453D03*
X385752Y1088647D03*
Y1082269D03*
X389453Y1088647D03*
Y1082269D03*
X395004Y1085458D03*
X383902D03*
X387603D03*
X385752Y1095025D03*
X389453D03*
X396855D03*
X382051D03*
X383902Y1091836D03*
X393154Y1095025D03*
X391303Y1091836D03*
X395004D03*
X387603D03*
X391303Y1098214D03*
Y1104592D03*
X395004D03*
X387603D03*
X383902D03*
X385752Y1095025D03*
X389453D03*
X395004Y1098214D03*
X383902D03*
X387603D03*
X382051Y1101403D03*
X393154D03*
X389453D03*
X385752D03*
X382051Y1107781D03*
Y1114159D03*
X383902Y1110970D03*
X387603D03*
X393154Y1107781D03*
X391303Y1110970D03*
X395004D03*
X391303Y1117348D03*
X393154Y1114159D03*
X389453D03*
Y1107781D03*
X385752Y1114159D03*
Y1107781D03*
X395004Y1117348D03*
X387603D03*
X383902D03*
X391304Y1130105D03*
X382051Y1126915D03*
Y1120537D03*
Y1133293D03*
X383902Y1123726D03*
X387603D03*
X393154Y1126915D03*
X391303Y1123726D03*
X395004D03*
X393154Y1120537D03*
Y1133293D03*
X389453Y1120537D03*
X385752D03*
X389453Y1126915D03*
Y1133293D03*
X385752Y1126915D03*
Y1133293D03*
X395004Y1130103D03*
X387603D03*
X383902D03*
X382051Y1139670D03*
Y1146048D03*
X393154Y1139670D03*
X395004Y1136481D03*
X391303D03*
X383902D03*
X387603D03*
X391303Y1142859D03*
X393154Y1146048D03*
X395004Y1149237D03*
X383902D03*
X387603D03*
X389453Y1139670D03*
Y1146048D03*
X385752Y1139670D03*
Y1146048D03*
X395004Y1142859D03*
X387603D03*
X383902D03*
X391303Y1149237D03*
X389453Y1158804D03*
X391303Y1155615D03*
X395004D03*
X383902D03*
X387603D03*
Y1161993D03*
X382051Y1152426D03*
X383902Y1161993D03*
X391303D03*
X395004D03*
X393154Y1152426D03*
X385752Y1158804D03*
X382051D03*
X393154D03*
X389453Y1152426D03*
X385752D03*
X388805Y1218420D03*
X388647Y1223453D03*
X386461Y1235718D03*
X386303Y1240751D03*
X382458Y1507295D03*
X387182D03*
X393483Y1507355D03*
X391383D03*
X381064Y1514243D03*
X390203Y1521453D03*
X385458D03*
X385788Y1514243D03*
X382359Y1516970D03*
X387083D03*
X383933Y1519698D03*
X388658D03*
X394890Y1514073D03*
X394834Y1516336D03*
X381285Y1528853D03*
X386009D03*
X385508Y1536063D03*
X390839D03*
X382359Y1530608D03*
X387083D03*
X383933Y1533336D03*
X388658D03*
X385458Y1523953D03*
X381285Y1526353D03*
X386009D03*
X395185Y1536640D03*
Y1534540D03*
X395186Y1531618D03*
X395097Y1528698D03*
X382458Y1542641D03*
X387182D03*
X394600Y1538658D03*
X410477Y873246D03*
X397524Y876435D03*
X399374Y873246D03*
Y879624D03*
X404925Y876435D03*
X401225D03*
X403075Y879624D03*
X406776D03*
X403075Y873246D03*
X399374Y892380D03*
X410477D03*
X406776D03*
X397524Y882813D03*
Y889191D03*
X401225Y882813D03*
X408626D03*
X404925D03*
X401225Y895569D03*
X408626Y889191D03*
X404925D03*
X403075Y892380D03*
X397524Y895569D03*
X403075Y886002D03*
X401225Y889191D03*
X408626Y895569D03*
X404925D03*
X406776Y886002D03*
X410477D03*
X399374D03*
Y898758D03*
Y905135D03*
X410477Y898758D03*
Y905135D03*
X406776Y898758D03*
Y905135D03*
X399374Y911513D03*
X410477D03*
X406776D03*
X397524Y901947D03*
X401225D03*
X408626D03*
X404925D03*
X403075Y898758D03*
Y905135D03*
Y911513D03*
X401225Y908324D03*
X397524Y908325D03*
X408626D03*
X404925Y908324D03*
X399374Y924269D03*
Y917891D03*
X410477D03*
Y924269D03*
X406776Y917891D03*
Y924269D03*
X397524Y914702D03*
X401225D03*
X408626D03*
X403075Y917891D03*
X404925Y914702D03*
X401225Y921080D03*
X403075Y924269D03*
X397524Y921080D03*
X408626D03*
X404925D03*
X399374Y930647D03*
X401225Y933836D03*
X408626Y927458D03*
X404925D03*
X403075Y930647D03*
X401225Y940214D03*
X397524Y927458D03*
Y933836D03*
X401225Y927458D03*
X397524Y940214D03*
X410477Y930647D03*
X406776D03*
X408626Y940214D03*
X404925D03*
X403075Y937025D03*
X404925Y933836D03*
X410477Y937025D03*
X408626Y933836D03*
X399374Y937025D03*
X406776D03*
Y949781D03*
Y943403D03*
Y956159D03*
X399374Y949781D03*
Y943403D03*
Y956159D03*
X410477Y949781D03*
Y943403D03*
Y956159D03*
X397524Y946592D03*
X401225D03*
X403075Y943403D03*
X408626Y946592D03*
X403075Y949781D03*
X404925Y946592D03*
X401225Y952970D03*
X403075Y956159D03*
X397524Y952970D03*
X408626D03*
X404925D03*
X397524Y959348D03*
X401225Y965726D03*
Y959348D03*
X408626D03*
X404925D03*
X403075Y962537D03*
Y968915D03*
X397524Y965726D03*
X408626D03*
X404925D03*
X406776Y962537D03*
Y968915D03*
X399374Y962537D03*
Y968915D03*
X410477Y962537D03*
Y968915D03*
X397524Y972104D03*
X401225D03*
X408626D03*
X404925D03*
X399374Y981671D03*
X406776D03*
X401225Y978482D03*
X403075Y975293D03*
X401225Y984860D03*
X408626D03*
X397524Y978482D03*
Y984860D03*
X404925Y978482D03*
X408626D03*
X410477Y981671D03*
X403075D03*
X404925Y984860D03*
X406776Y975293D03*
X399374D03*
X410477D03*
X408626Y991238D03*
X399374Y988049D03*
Y994427D03*
X406776Y988049D03*
X401225Y991238D03*
Y997616D03*
X399374Y1000805D03*
X408614Y997608D03*
X397524Y991238D03*
X410477Y988049D03*
X403075D03*
X404925Y991238D03*
X397524Y997616D03*
X403075Y994427D03*
Y1000805D03*
X397524Y1010372D03*
X399374Y1007183D03*
X401225Y1003994D03*
X410464Y1007175D03*
X404923Y1010366D03*
X401225Y1010372D03*
X397524Y1003994D03*
X406763Y1007175D03*
X403075Y1007183D03*
X398705Y1028056D03*
X409795Y1028064D03*
X406094D03*
X402406Y1028056D03*
X398705Y1034434D03*
X402406Y1040812D03*
X400555Y1031245D03*
Y1037623D03*
Y1044001D03*
X409795Y1034442D03*
Y1040820D03*
X406104D03*
X404256Y1044001D03*
X398705Y1040812D03*
X406094Y1034442D03*
X404256Y1037623D03*
Y1031245D03*
X402406Y1034434D03*
X396855Y1044001D03*
Y1031245D03*
Y1037623D03*
X407957Y1063135D03*
X400555D03*
X411658D03*
X402406Y1047190D03*
X409807D03*
X402406Y1053568D03*
X407957Y1056757D03*
X402406Y1059946D03*
X409807Y1053568D03*
X400555Y1056757D03*
Y1050379D03*
X407957D03*
X398705Y1047190D03*
X406107D03*
X404256Y1050379D03*
X398705Y1059946D03*
Y1053568D03*
X396855Y1050379D03*
Y1056757D03*
X409807Y1059946D03*
X406107D03*
Y1053568D03*
X404256Y1056757D03*
X407957Y1069513D03*
X400555D03*
X411658D03*
Y1075891D03*
X407957D03*
X400555D03*
X398705Y1066324D03*
X404256Y1063135D03*
X402406Y1072702D03*
X404256Y1069513D03*
X406107Y1066324D03*
X409807D03*
X402406D03*
X396855Y1069513D03*
Y1063135D03*
X407957Y1069513D03*
Y1063135D03*
X400555Y1069513D03*
Y1063135D03*
X398705Y1072702D03*
X406107D03*
X409807D03*
X411658Y1088647D03*
Y1082269D03*
X407957Y1088647D03*
Y1082269D03*
X400555Y1088647D03*
Y1082269D03*
X398705Y1079080D03*
X404256Y1075891D03*
X406107Y1079080D03*
X409807D03*
X402406D03*
X404256Y1088647D03*
X402406Y1085458D03*
X404256Y1082269D03*
X396855Y1075891D03*
X407957D03*
X400555D03*
X396855Y1088647D03*
Y1082269D03*
X407957Y1088647D03*
Y1082269D03*
X400555Y1088647D03*
Y1082269D03*
X398705Y1085458D03*
X406107D03*
X409807D03*
X407957Y1095025D03*
X400555D03*
X411658D03*
X398705Y1091836D03*
Y1104592D03*
X404256Y1095025D03*
X406107Y1091836D03*
X409807D03*
X402406D03*
Y1098214D03*
Y1104592D03*
X396855Y1095025D03*
X407957D03*
X400555D03*
X398705Y1098214D03*
X406107D03*
X409807D03*
Y1104592D03*
X407957Y1101403D03*
X404256D03*
X396855D03*
X406107Y1104592D03*
X400555Y1101403D03*
X398705Y1110970D03*
X404256Y1107781D03*
X406107Y1110970D03*
X409807D03*
X402406D03*
X404256Y1114159D03*
X402406Y1117348D03*
X400555Y1114159D03*
Y1107781D03*
X396855Y1114159D03*
Y1107781D03*
X407957Y1114159D03*
X398705Y1117348D03*
X407957Y1107781D03*
X406107Y1117348D03*
X409807D03*
X398705Y1123726D03*
X406107D03*
X409807D03*
X404256Y1120537D03*
X402406Y1123726D03*
X404256Y1126915D03*
Y1133293D03*
X402406Y1130103D03*
X400555Y1120537D03*
Y1126915D03*
X396855Y1120537D03*
Y1126915D03*
X407957Y1120537D03*
Y1126915D03*
X400555Y1133293D03*
X396855D03*
X407957D03*
X398705Y1130103D03*
X406107D03*
X409807D03*
X398705Y1136481D03*
Y1149237D03*
X402406Y1142859D03*
X404256Y1139670D03*
X406107Y1136481D03*
X409807D03*
X402406D03*
X404256Y1146048D03*
X406107Y1149237D03*
X409807D03*
X400555Y1139670D03*
Y1146048D03*
X396855Y1139670D03*
Y1146048D03*
X407957Y1139670D03*
Y1146048D03*
X398705Y1142859D03*
X406107D03*
X409807D03*
X402406Y1149237D03*
X398705Y1155615D03*
Y1161993D03*
X406107Y1155615D03*
X409807D03*
X402406D03*
X400555Y1158804D03*
X409807Y1161993D03*
X400555Y1165182D03*
X404256Y1152426D03*
X406107Y1161993D03*
X402406D03*
X396855Y1158804D03*
X407957D03*
X404256D03*
X400555Y1152426D03*
X396855D03*
X407957D03*
X421579Y873246D03*
X416028Y876435D03*
X412327D03*
X423429D03*
X414177Y873246D03*
X421579Y892380D03*
X417878D03*
X412327Y882813D03*
Y895569D03*
X414177Y892380D03*
X419729Y882813D03*
X416028D03*
X423429Y895569D03*
X425280Y892380D03*
X416028Y889191D03*
X419729D03*
X412327D03*
X425280Y886002D03*
X423429Y889191D03*
X419729Y895569D03*
X416028D03*
X414177Y886002D03*
X421579Y898758D03*
Y905135D03*
X417878Y898758D03*
Y905135D03*
X421579Y911513D03*
X417878D03*
X412327Y901947D03*
X414177Y898758D03*
Y905135D03*
Y911513D03*
X412327Y908325D03*
X423429Y901947D03*
X425280Y898758D03*
X419729Y901947D03*
X416028D03*
X425280Y905135D03*
Y911513D03*
X423429Y908324D03*
X419729Y908325D03*
X416028D03*
X421579Y917891D03*
Y924269D03*
X417878Y917891D03*
Y924269D03*
X414177Y917891D03*
X412327Y914702D03*
X414177Y924269D03*
X412327Y921080D03*
X423429Y914702D03*
X419729D03*
X416028D03*
X425280Y917891D03*
Y924269D03*
X423429Y921080D03*
X416028D03*
X419729D03*
X417878Y937025D03*
X421579D03*
X412327Y927458D03*
Y933836D03*
X414177Y930647D03*
X412327Y940214D03*
X414177Y937025D03*
X423429Y927458D03*
X419729D03*
X423429Y933836D03*
X425280Y930647D03*
X419729Y933836D03*
X416028Y927458D03*
Y933836D03*
X425280Y937025D03*
X423429Y940214D03*
X417878Y930647D03*
X421579D03*
X416028Y940214D03*
X419729D03*
X417878Y943403D03*
Y956159D03*
Y949781D03*
X421579Y943403D03*
Y956159D03*
Y949781D03*
X414177D03*
X412327Y946592D03*
X414177Y943403D03*
X412327Y952970D03*
X414177Y956159D03*
X416028Y946592D03*
X425280Y943403D03*
Y949781D03*
X423429Y946592D03*
X419729D03*
X423429Y952970D03*
X425280Y956159D03*
X416028Y952970D03*
X419729D03*
X412327Y965726D03*
Y959348D03*
X414177Y962537D03*
Y968915D03*
X423429Y965726D03*
X416028Y959348D03*
X423429D03*
X419729D03*
X425280Y962537D03*
Y968915D03*
X419729Y965726D03*
X416028D03*
X417878Y962537D03*
Y968915D03*
X421579Y962537D03*
Y968915D03*
X416028Y972104D03*
X423429D03*
X419729D03*
X416028Y984860D03*
X423429D03*
X412327Y978482D03*
X414177Y981671D03*
Y975293D03*
X412327Y972104D03*
X423429Y978482D03*
X421579Y981671D03*
X425280Y975293D03*
X412327Y984860D03*
X416028Y978482D03*
X419729D03*
X425280Y981671D03*
X417878D03*
X419729Y984860D03*
X417878Y975293D03*
X421579D03*
X414177Y988049D03*
X421579D03*
X423429Y991238D03*
X416028D03*
X423417Y997608D03*
X416015D03*
X417878Y988049D03*
X425280D03*
X412315Y997608D03*
X412327Y991238D03*
X419716Y997608D03*
X419729Y991238D03*
X424598Y1040820D03*
X417197D03*
X413496D03*
X420897D03*
X419059Y1063135D03*
X422760D03*
X413508Y1059946D03*
X417209Y1047190D03*
X424610D03*
Y1053568D03*
X422760Y1056757D03*
X424610Y1059946D03*
X417209Y1053568D03*
X415358Y1056757D03*
Y1050379D03*
X422760D03*
X413508Y1047190D03*
X420910D03*
X419059Y1050379D03*
X411658D03*
X413508Y1053568D03*
X411658Y1056757D03*
X420910Y1053568D03*
X419059Y1056757D03*
X417209Y1059946D03*
X420910D03*
X419059Y1069513D03*
X422760D03*
X419059Y1075891D03*
X422760D03*
X413508Y1072702D03*
Y1066324D03*
X415358Y1063135D03*
X424610Y1072702D03*
Y1066324D03*
X420910D03*
X417209D03*
X415358Y1069513D03*
X419059Y1063135D03*
Y1069513D03*
X422760Y1063135D03*
X411658Y1069513D03*
Y1063135D03*
X422760Y1069513D03*
X417209Y1072702D03*
X420910D03*
X419059Y1082269D03*
Y1088647D03*
X422760Y1082269D03*
Y1088647D03*
X413508Y1079080D03*
Y1085458D03*
X415358Y1075891D03*
X420910Y1079080D03*
X424610D03*
X417209D03*
X424610Y1085458D03*
X415358Y1088647D03*
Y1082269D03*
X419059Y1075891D03*
X422760D03*
X411658D03*
X419059Y1082269D03*
Y1088647D03*
X422760Y1082269D03*
X411658Y1088647D03*
Y1082269D03*
X422760Y1088647D03*
X417209Y1085458D03*
X420910D03*
X419059Y1095025D03*
Y1101403D03*
X422760Y1095025D03*
Y1101403D03*
X413508Y1091836D03*
Y1098214D03*
Y1104592D03*
X415358Y1095025D03*
X420910Y1091836D03*
X424610D03*
X417209D03*
X420910Y1104592D03*
X424610D03*
Y1098214D03*
X417209Y1104592D03*
X415358Y1101403D03*
X419059Y1095025D03*
Y1101403D03*
X422760Y1095025D03*
Y1101403D03*
X411658Y1095025D03*
X420910Y1098214D03*
X417209D03*
X411658Y1101403D03*
X413508Y1110970D03*
Y1117348D03*
X415358Y1107781D03*
X424610Y1110970D03*
X420910D03*
X417209D03*
X424610Y1117348D03*
X415358Y1114159D03*
X422760D03*
X411658D03*
X419059D03*
X411658Y1107781D03*
X422760D03*
X419059D03*
X420910Y1117348D03*
X417209D03*
X415358Y1120537D03*
Y1126915D03*
X424610Y1123726D03*
X420910D03*
X417209D03*
X415358Y1133293D03*
X413508Y1123726D03*
Y1130103D03*
X424611Y1130105D03*
X422760Y1120537D03*
Y1126915D03*
X411658Y1120537D03*
Y1126915D03*
X419059Y1120537D03*
Y1126915D03*
X422760Y1133293D03*
X411658D03*
X419059D03*
X420910Y1130103D03*
X417209D03*
X413508Y1142859D03*
Y1136481D03*
X424610Y1142859D03*
Y1136481D03*
X420910D03*
X415358Y1139670D03*
X417209Y1136481D03*
X420910Y1149237D03*
X417209D03*
X415358Y1146048D03*
X422760Y1139670D03*
Y1146048D03*
X411658Y1139670D03*
Y1146048D03*
X419059Y1139670D03*
Y1146048D03*
X417209Y1142859D03*
X420910D03*
X413508Y1149237D03*
X424610D03*
X413508Y1155615D03*
X411658Y1158804D03*
X424610Y1155615D03*
X420910D03*
X417209D03*
X422760Y1158804D03*
Y1165182D03*
X420910Y1161993D03*
X424610D03*
X415358Y1152426D03*
X413508Y1161993D03*
X417209D03*
X419059Y1158804D03*
X415358D03*
X411658Y1152426D03*
X422760D03*
X419059D03*
X434532Y876435D03*
X432681Y879624D03*
X427130Y876435D03*
X430831Y895569D03*
X427130D03*
X430831Y882813D03*
X427130D03*
X430831Y889191D03*
X427130D03*
X434532Y895569D03*
Y889191D03*
X428981Y892380D03*
X432681D03*
X430831Y901947D03*
Y908325D03*
X427130Y901947D03*
Y908325D03*
X428981Y905135D03*
X434532Y901947D03*
X432681Y905135D03*
X434532Y908325D03*
X428981Y911513D03*
X432681D03*
X428981Y898758D03*
X432681D03*
X430831Y914702D03*
Y921080D03*
X427130Y914702D03*
Y921080D03*
X428981Y917891D03*
X432681D03*
X434532Y914702D03*
Y921080D03*
X428981Y924269D03*
X432681D03*
X430831Y927458D03*
X427130D03*
Y940214D03*
X430831D03*
X428981Y930647D03*
Y937025D03*
X432681Y930647D03*
X434532Y927458D03*
Y933836D03*
X432681Y937025D03*
X434532Y940214D03*
X427130Y933836D03*
X430831D03*
X427130Y946592D03*
Y952970D03*
X430831Y946592D03*
Y952970D03*
X428981Y949781D03*
X432681D03*
X434532Y946592D03*
Y952970D03*
X428981Y943403D03*
Y956159D03*
X432681Y943403D03*
Y956159D03*
X428981Y962537D03*
X432681D03*
X434532Y959348D03*
Y965726D03*
X428981Y968915D03*
X432681D03*
X427130Y959348D03*
Y965726D03*
X430831Y959348D03*
Y965726D03*
X428981Y981671D03*
Y975293D03*
X430831Y984860D03*
X434532Y972104D03*
X432681Y975293D03*
X434532Y978482D03*
X427130Y984860D03*
X432681Y981671D03*
X434532Y984860D03*
X427130Y978482D03*
Y972104D03*
X430831Y978482D03*
Y972104D03*
Y991238D03*
X428981Y988049D03*
X430819Y997608D03*
X432681Y988049D03*
X434532Y991238D03*
X427118Y997608D03*
X427130Y991238D03*
X434519Y997608D03*
X428299Y1040820D03*
X428311Y1059946D03*
X432012D03*
X430162Y1056757D03*
Y1050379D03*
X432012Y1047190D03*
Y1053568D03*
X435713Y1059946D03*
X428311D03*
X432012D03*
X428311Y1047190D03*
X435713D03*
X433862Y1050379D03*
X426461D03*
Y1056757D03*
X428311Y1053568D03*
X433862Y1056757D03*
X435713Y1053568D03*
X428311Y1072702D03*
Y1066324D03*
X432012Y1072702D03*
Y1066324D03*
X426461Y1063135D03*
X430162D03*
X426461Y1069513D03*
X433862Y1063135D03*
X435713Y1072702D03*
Y1066324D03*
X428311Y1072702D03*
Y1066324D03*
X432012Y1072702D03*
Y1066324D03*
X430162Y1069513D03*
X433862D03*
X428311Y1079080D03*
X432012D03*
X428311Y1085458D03*
X432012D03*
X428311Y1091836D03*
X432012D03*
X430162Y1075891D03*
X426461D03*
X430162Y1088647D03*
X426461D03*
Y1082269D03*
X433862Y1075891D03*
X435713Y1079080D03*
Y1085458D03*
X433862Y1088647D03*
X428311Y1079080D03*
X432012D03*
X428311Y1085458D03*
X432012D03*
X430162Y1082269D03*
X433862D03*
X428311Y1098214D03*
X432012D03*
X426461Y1095025D03*
X430162Y1101403D03*
X426461D03*
X435713Y1091836D03*
Y1098214D03*
Y1104592D03*
X433862Y1101403D03*
X428311Y1098214D03*
Y1091836D03*
X432012Y1098214D03*
Y1091836D03*
X430162Y1095025D03*
X428311Y1104592D03*
X433862Y1095025D03*
X432012Y1104592D03*
X430162Y1107781D03*
X426461D03*
Y1114159D03*
X433862Y1107781D03*
X435713Y1110970D03*
Y1117348D03*
X432012D03*
Y1110970D03*
X428311Y1117348D03*
Y1110970D03*
X430162Y1114159D03*
X433862D03*
X426461Y1126915D03*
X430162Y1120537D03*
X426461D03*
X430162Y1133293D03*
X426461D03*
X435713Y1123726D03*
X433862Y1120537D03*
X435713Y1130103D03*
X433862Y1133293D03*
X432012Y1123726D03*
X428311D03*
X432012Y1130103D03*
X428311D03*
X430162Y1126915D03*
X433862D03*
X426461Y1139670D03*
Y1146048D03*
X428311Y1149237D03*
X435713Y1136481D03*
Y1142859D03*
Y1149237D03*
X432012D03*
Y1142859D03*
Y1136481D03*
X428311Y1142859D03*
Y1136481D03*
X430162Y1139670D03*
Y1146048D03*
X433862Y1139670D03*
Y1146048D03*
X430162Y1158804D03*
X435713Y1155615D03*
Y1161993D03*
X433862Y1158804D03*
X432012Y1161993D03*
X428311D03*
X426461Y1152426D03*
X430162D03*
X433862D03*
X432012Y1155615D03*
X426461Y1158804D03*
X428311Y1155615D03*
X445609Y876435D03*
X447460Y879624D03*
X454861Y873246D03*
X453011Y876435D03*
X449310D03*
X451160Y879624D03*
X454861D03*
X451160Y873246D03*
X449310Y895569D03*
X453011D03*
X445609Y882813D03*
Y889191D03*
Y895569D03*
X453011Y882813D03*
X449310Y889191D03*
X453011D03*
X454861Y892380D03*
X451160Y886002D03*
X454861D03*
X451160Y892380D03*
X447460D03*
Y886002D03*
X449310Y882813D03*
Y908325D03*
Y901947D03*
X453011Y908325D03*
Y901947D03*
X445609D03*
Y908325D03*
X454861Y898758D03*
X451160Y905135D03*
X454861D03*
Y911513D03*
X447460Y905135D03*
X451160Y911513D03*
X447460D03*
X451160Y898758D03*
X447460D03*
X449310Y921080D03*
Y914702D03*
X453011Y921080D03*
Y914702D03*
X445609D03*
Y921080D03*
X447460Y917891D03*
X451160D03*
X454861D03*
Y924269D03*
X451160D03*
X447460D03*
X453011Y940214D03*
X449310D03*
Y927458D03*
X453011D03*
X454861Y930647D03*
X447460Y937025D03*
X451160D03*
X454861D03*
X445609Y927458D03*
Y933836D03*
Y940214D03*
X447460Y930647D03*
X451160D03*
X449310Y933836D03*
X453011D03*
Y952970D03*
Y946592D03*
X449310Y952970D03*
Y946592D03*
X445609D03*
Y952970D03*
X447460Y949781D03*
X454861Y943403D03*
X451160Y949781D03*
X454861D03*
Y956159D03*
X451160Y943403D03*
Y956159D03*
X447460Y943403D03*
Y956159D03*
X453011Y959348D03*
Y965726D03*
X449310Y959348D03*
Y965726D03*
X445609Y959348D03*
Y965726D03*
X454861Y962537D03*
X451160D03*
X447460D03*
X454861Y968915D03*
X451160D03*
X447460D03*
X453011Y978482D03*
Y972104D03*
X449310Y978482D03*
Y972104D03*
X445609D03*
Y978482D03*
Y984860D03*
X447460Y981671D03*
X454861D03*
X451160Y975293D03*
X447460D03*
X454861D03*
X453011Y984860D03*
X451160Y981671D03*
X449310Y984860D03*
X445609Y991238D03*
X453011D03*
X454861Y988049D03*
X447460D03*
X445622Y997608D03*
X453023D03*
X449323D03*
X451160Y988049D03*
X449310Y991238D03*
X454204Y1040820D03*
X454192Y1059946D03*
X450491D03*
X446790Y1047190D03*
Y1053568D03*
Y1059946D03*
X454192Y1047190D03*
X448641Y1056757D03*
X454192Y1053568D03*
X448641Y1050379D03*
X454192Y1059946D03*
X450491D03*
Y1047190D03*
X452341Y1056757D03*
X450491Y1053568D03*
X452341Y1050379D03*
X454192Y1066324D03*
Y1072702D03*
X450491Y1066324D03*
Y1072702D03*
X446790Y1066324D03*
Y1072702D03*
X452341Y1063135D03*
X448641D03*
X454192Y1066324D03*
Y1072702D03*
X450491Y1066324D03*
Y1072702D03*
X448641Y1069513D03*
X452341D03*
X454192Y1079080D03*
Y1085458D03*
X450491Y1079080D03*
Y1085458D03*
X454192Y1091836D03*
X450491D03*
X446790Y1079080D03*
Y1085458D03*
X452341Y1075891D03*
X448641D03*
X452341Y1088647D03*
X448641D03*
X454192Y1079080D03*
X450491D03*
X454192Y1085458D03*
X450491D03*
X448641Y1082269D03*
X452341D03*
X454192Y1098214D03*
X450491D03*
X446790Y1091836D03*
Y1098214D03*
Y1104592D03*
X452341Y1101403D03*
X448641D03*
X454192Y1091836D03*
Y1098214D03*
X450491Y1091836D03*
Y1098214D03*
X448641Y1095025D03*
X452341D03*
X450491Y1104592D03*
X454192D03*
X446790Y1110970D03*
Y1117348D03*
X452341Y1107781D03*
X448641D03*
X450491Y1110970D03*
Y1117348D03*
X454192Y1110970D03*
Y1117348D03*
X448641Y1114159D03*
X452341D03*
X446790Y1123726D03*
Y1130103D03*
X448641Y1120537D03*
X452341D03*
Y1133293D03*
X448641D03*
X450491Y1123726D03*
X454192D03*
X450491Y1130103D03*
X454192D03*
X448641Y1126915D03*
X452341D03*
X446790Y1136481D03*
Y1142859D03*
Y1149237D03*
X454192D03*
X450491D03*
Y1136481D03*
Y1142859D03*
X454192Y1136481D03*
Y1142859D03*
X448641Y1139670D03*
X452341D03*
X448641Y1146048D03*
X452341D03*
X450491Y1161993D03*
X446790Y1155615D03*
Y1161993D03*
X454192Y1155615D03*
X452341Y1165182D03*
X454192Y1161993D03*
X452341Y1152426D03*
X448640Y1165182D03*
X448641Y1158804D03*
X452341D03*
X450491Y1155615D03*
X447120Y1507512D03*
X452427Y1507295D03*
X444953Y1507509D03*
X442753D03*
X450703Y1521453D03*
X451033Y1514243D03*
X449861Y1519195D03*
X452328Y1516970D03*
X453903Y1519698D03*
X442918Y1513218D03*
X441660Y1521612D03*
X441259Y1518121D03*
X451254Y1528853D03*
X450752Y1536063D03*
X441752Y1523810D03*
Y1528725D03*
X452328Y1530608D03*
X453903Y1533336D03*
X441706Y1535698D03*
Y1537898D03*
X450703Y1523953D03*
X451254Y1526353D03*
X452427Y1542641D03*
X447224Y1542425D03*
X443153Y1540317D03*
X447224Y1544625D03*
X450139Y1592380D03*
Y1624292D03*
X460412Y876435D03*
X469664Y879624D03*
X462263D03*
X458562D03*
Y873246D03*
X462263D03*
X456712Y876435D03*
X467814D03*
X464113D03*
X465964Y879624D03*
Y873246D03*
X458562Y892380D03*
X469664D03*
X462263D03*
X460412Y889191D03*
X456712Y895569D03*
X467814Y882813D03*
X465964Y892380D03*
X467814Y895569D03*
X464113Y889191D03*
X460412Y882813D03*
X464113D03*
X469664Y886002D03*
X456712Y889191D03*
X460412Y895569D03*
X465964Y886002D03*
X467814Y889191D03*
X464113Y895569D03*
X462263Y886002D03*
X458562D03*
X456712Y882813D03*
X458562Y905135D03*
Y898758D03*
X469664Y905135D03*
Y898758D03*
X462263Y905135D03*
Y898758D03*
X458562Y911513D03*
X469664D03*
X462263D03*
X456712Y908324D03*
X465964Y911513D03*
X456712Y901947D03*
X460412D03*
X465964Y898758D03*
X467814Y901947D03*
X464113D03*
X467814Y908325D03*
X465964Y905135D03*
X460412Y908325D03*
X464113D03*
X458562Y924269D03*
Y917891D03*
X469664Y924269D03*
Y917891D03*
X462263Y924269D03*
Y917891D03*
X460412Y914702D03*
X456712D03*
Y921080D03*
X467814Y914702D03*
X464113D03*
X465964Y917891D03*
X467814Y921080D03*
X465964Y924269D03*
X460412Y921080D03*
X464113D03*
X462263Y937025D03*
X458562D03*
X460412Y927458D03*
X456712D03*
Y933836D03*
X460412D03*
X456712Y940214D03*
X467814Y927458D03*
Y933836D03*
X464113Y927458D03*
Y933836D03*
X467814Y940214D03*
X465964Y937025D03*
X462263Y930647D03*
X458562D03*
X460412Y940214D03*
X469664Y930647D03*
X464113Y940214D03*
X465964Y930647D03*
X469664Y937025D03*
X462263Y956159D03*
Y943403D03*
Y949781D03*
X458562Y956159D03*
Y943403D03*
Y949781D03*
X469664Y956159D03*
Y943403D03*
Y949781D03*
X460412Y946592D03*
X456712D03*
Y952970D03*
X467814Y946592D03*
X464113D03*
X465964Y943403D03*
Y949781D03*
X467814Y952970D03*
X465964Y956159D03*
X460412Y952970D03*
X464113D03*
X462263Y962537D03*
Y968915D03*
X458562Y962537D03*
Y968915D03*
X469664Y962537D03*
Y968915D03*
X456712Y965726D03*
X460412Y959348D03*
X456712D03*
X467814Y965726D03*
Y959348D03*
X465964Y962537D03*
X464113Y959348D03*
X465964Y968915D03*
X460412Y965726D03*
X464113D03*
X462263Y975293D03*
X458562D03*
X469664D03*
X456712Y972104D03*
Y978482D03*
X462263Y981671D03*
X460412Y972104D03*
Y984860D03*
X469664Y981671D03*
X467814Y978482D03*
Y972104D03*
X465964Y975293D03*
X464113Y972104D03*
X467814Y984860D03*
X460412Y978482D03*
X458562Y981671D03*
X456712Y984860D03*
X464113Y978482D03*
X465964Y981671D03*
X464113Y984860D03*
X460412Y991238D03*
X462263Y988049D03*
X469664D03*
X467814Y991238D03*
X467826Y997608D03*
X460425D03*
X458562Y988049D03*
X456724Y997608D03*
X456712Y991238D03*
X464126Y997608D03*
X465964Y988049D03*
X464113Y991238D03*
X469007Y1040820D03*
X461606D03*
X457905D03*
X465307D03*
X463444Y1063135D03*
X459743D03*
X470845D03*
X461593Y1047190D03*
Y1053568D03*
X456042Y1056757D03*
X457893Y1059946D03*
X456042Y1050379D03*
X468995Y1047190D03*
Y1053568D03*
Y1059946D03*
X463444Y1056757D03*
Y1050379D03*
X457893Y1047190D03*
X465294D03*
X459743Y1050379D03*
X465294Y1053568D03*
X467145Y1056757D03*
Y1050379D03*
X457893Y1053568D03*
X461593Y1059946D03*
X459743Y1056757D03*
X465294Y1059946D03*
X463444Y1069513D03*
X459743D03*
X470845D03*
Y1075891D03*
X463444D03*
X459743D03*
X456042Y1063135D03*
Y1069513D03*
X457893Y1072702D03*
Y1066324D03*
X461593D03*
X467145Y1063135D03*
X468995Y1072702D03*
Y1066324D03*
X467145Y1069513D03*
X465294Y1066324D03*
X463444Y1063135D03*
Y1069513D03*
X459743Y1063135D03*
Y1069513D03*
X461593Y1072702D03*
X465294D03*
X470845Y1082269D03*
Y1088647D03*
X463444Y1082269D03*
Y1088647D03*
X459743Y1082269D03*
Y1088647D03*
X456042Y1075891D03*
X461593Y1079080D03*
X457893D03*
X456042Y1088647D03*
X457893Y1085458D03*
X456042Y1082269D03*
X467145Y1075891D03*
X468995Y1079080D03*
X465294D03*
X468995Y1085458D03*
X467145Y1088647D03*
Y1082269D03*
X463444Y1075891D03*
X459743D03*
X463444Y1082269D03*
Y1088647D03*
X459743Y1082269D03*
Y1088647D03*
X461593Y1085458D03*
X465294D03*
X463444Y1101403D03*
Y1095025D03*
X459743Y1101403D03*
Y1095025D03*
X470845D03*
X457893Y1091836D03*
X461593D03*
X456042Y1095025D03*
X457893Y1098214D03*
X456042Y1101403D03*
X457893Y1104592D03*
X461593D03*
X467145Y1095025D03*
X468995Y1091836D03*
X465294D03*
X468995Y1104592D03*
X465294D03*
X468995Y1098214D03*
X467145Y1101403D03*
X463444D03*
Y1095025D03*
X459743Y1101403D03*
Y1095025D03*
X461593Y1098214D03*
X465294D03*
X456042Y1107781D03*
X457893Y1110970D03*
X461593D03*
X457893Y1117348D03*
X456042Y1114159D03*
X468995Y1110970D03*
X465294D03*
X467145Y1107781D03*
Y1114159D03*
X468995Y1117348D03*
X459743Y1114159D03*
X463444D03*
X459743Y1107781D03*
X461593Y1117348D03*
X463444Y1107781D03*
X465294Y1117348D03*
X456042Y1126915D03*
X461593Y1123726D03*
X457893D03*
X456042Y1120537D03*
Y1133293D03*
X468995Y1123726D03*
X467145Y1120537D03*
X465294Y1123726D03*
X467145Y1126915D03*
X468995Y1130103D03*
X467145Y1133293D03*
X457893Y1130104D03*
X459743Y1126915D03*
Y1120537D03*
X463444Y1126915D03*
Y1120537D03*
X459743Y1133293D03*
X463444D03*
X461593Y1130103D03*
X465294D03*
X456042Y1139670D03*
X461593Y1136481D03*
X457893D03*
Y1142859D03*
X456042Y1146048D03*
X461593Y1149237D03*
X468995Y1142859D03*
X467145Y1139670D03*
X468995Y1136481D03*
X465294D03*
X467145Y1146048D03*
X465294Y1149237D03*
X459743Y1146048D03*
Y1139670D03*
X463444Y1146048D03*
Y1139670D03*
X461593Y1142859D03*
X457893Y1149237D03*
X465294Y1142859D03*
X468995Y1149237D03*
X467145Y1165182D03*
X459743Y1158804D03*
Y1152426D03*
X465294Y1155615D03*
X468995Y1161993D03*
X465294D03*
X467145Y1152426D03*
X457893Y1161993D03*
X456042Y1152426D03*
X459743Y1165182D03*
X456042Y1158804D03*
X457893Y1155615D03*
X456042Y1165182D03*
X461593Y1161993D03*
Y1155615D03*
X463444Y1152426D03*
Y1158804D03*
X467145D03*
X468995Y1155615D03*
X463444Y1165182D03*
X457152Y1507295D03*
X461876D03*
X466600D03*
X469600Y1521453D03*
X464876D03*
X460152D03*
X455427D03*
X455757Y1514243D03*
X460482D03*
X465206D03*
X469931D03*
X457052Y1516970D03*
X461777D03*
X466501D03*
X458627Y1519698D03*
X463351D03*
X468076D03*
X469651Y1536063D03*
X470151Y1528853D03*
X465427D03*
X460703D03*
X455978D03*
X464926Y1536063D03*
X460202D03*
X455477D03*
X457052Y1530608D03*
X461777D03*
X466501D03*
X458627Y1533336D03*
X463351D03*
X468076D03*
X464876Y1523953D03*
X460703Y1526353D03*
X455978D03*
X465427D03*
X455427Y1523953D03*
X460152D03*
X469600D03*
X470151Y1526353D03*
X466600Y1542641D03*
X457152D03*
X461876D03*
X469999Y1592380D03*
X457939D03*
X462199D03*
X463959Y1602380D03*
X456179D03*
X468239D03*
X457939Y1624292D03*
X463959Y1614292D03*
X456179D03*
X468239D03*
X469999Y1624292D03*
X462199D03*
X471515Y876435D03*
X480767Y873246D03*
Y879624D03*
X482617Y876435D03*
X484467Y873246D03*
X473365D03*
X477066D03*
X484467Y879624D03*
X477066D03*
X473365D03*
X475215Y876435D03*
X478916D03*
X480767Y892380D03*
X484467D03*
X473365D03*
X478916Y882813D03*
X475215D03*
X471515D03*
X478916Y895569D03*
X477066Y892380D03*
X475215Y889191D03*
X471515D03*
X482617Y882813D03*
Y889191D03*
X484467Y886002D03*
X480767D03*
X473365D03*
X477066D03*
X475215Y895569D03*
X471515D03*
X478916Y889191D03*
X482617Y895569D03*
X480767Y898758D03*
Y905135D03*
X484467Y898758D03*
X473365Y905135D03*
Y898758D03*
X484467Y905135D03*
X480767Y911513D03*
X484467D03*
X473365D03*
X478916Y901947D03*
X471515D03*
X475215D03*
X477066Y898758D03*
X478916Y908325D03*
X477066Y905135D03*
Y911513D03*
X482617Y901947D03*
X475215Y908325D03*
X471515D03*
X482617D03*
X480767Y917891D03*
Y924269D03*
X484467Y917891D03*
Y924269D03*
X473365D03*
Y917891D03*
X478916Y914702D03*
X477066Y917891D03*
X475215Y914702D03*
X471515D03*
X478916Y921080D03*
X477066Y924269D03*
X482617Y914702D03*
X475215Y921080D03*
X471515D03*
X482617D03*
X480767Y930647D03*
X484467D03*
X478916Y927458D03*
Y933836D03*
X475215Y927458D03*
X471515D03*
X477066Y930647D03*
X478916Y940214D03*
X482617Y927458D03*
Y933836D03*
X473365Y930647D03*
X471515Y940214D03*
X475215D03*
X482617D03*
X477066Y937025D03*
X480767D03*
X475215Y933836D03*
X471515D03*
X484467Y937025D03*
X473365D03*
X484467Y956159D03*
Y943403D03*
Y949781D03*
X473365Y956159D03*
Y943403D03*
Y949781D03*
X480767Y956159D03*
Y943403D03*
Y949781D03*
X478916Y946592D03*
X477066Y943403D03*
X475215Y946592D03*
X471515D03*
X477066Y949781D03*
X478916Y952970D03*
X477066Y956159D03*
X482617Y946592D03*
X475215Y952970D03*
X471515D03*
X482617D03*
X484467Y962537D03*
Y968915D03*
X473365Y962537D03*
Y968915D03*
X480767Y962537D03*
Y968915D03*
X478916Y965726D03*
Y959348D03*
X475215D03*
X471515D03*
X477066Y962537D03*
Y968915D03*
X482617Y959348D03*
X475215Y965726D03*
X471515D03*
X482617D03*
X484467Y975293D03*
X473365D03*
X480767D03*
X478916Y978482D03*
Y972104D03*
X477066Y981671D03*
Y975293D03*
X475215Y972104D03*
X471515D03*
X475215Y984860D03*
X484467Y981671D03*
X482617Y972104D03*
Y984860D03*
X475215Y978482D03*
X471515D03*
X473365Y981671D03*
X471515Y984860D03*
X478916D03*
X482617Y978482D03*
X480767Y981671D03*
X477066Y994427D03*
X475215Y991238D03*
X477066Y988049D03*
Y1000805D03*
X484467Y994427D03*
Y988049D03*
X482617Y991238D03*
Y997616D03*
X484467Y1000805D03*
X473365Y988049D03*
X471527Y997608D03*
X471515Y991238D03*
X478916Y997616D03*
Y991238D03*
X480767Y994427D03*
Y988049D03*
Y1000805D03*
X477066Y1007183D03*
X484467D03*
X482617Y1010372D03*
Y1003994D03*
X478916D03*
Y1010372D03*
X480767Y1007183D03*
X480097Y1028056D03*
X483798D03*
X478247Y1037623D03*
Y1044001D03*
X480097Y1034434D03*
X483798Y1040812D03*
X481948Y1031245D03*
X476400Y1040820D03*
X472708D03*
X481948Y1044001D03*
Y1037623D03*
X480097Y1040812D03*
X483798Y1034434D03*
X478247Y1031245D03*
X474546Y1063135D03*
X481948D03*
X485649D03*
X476397Y1047190D03*
Y1053568D03*
X470845Y1056757D03*
X478247D03*
X470845Y1050379D03*
X478247D03*
X483798Y1047190D03*
Y1053568D03*
X480097Y1059946D03*
X472696Y1047190D03*
X480097D03*
X474546Y1050379D03*
Y1056757D03*
X472696Y1053568D03*
Y1059946D03*
X476397D03*
X483798D03*
X481948Y1056757D03*
X480097Y1053568D03*
X481948Y1050379D03*
X474546Y1069513D03*
X481948D03*
X485649D03*
Y1075891D03*
X474546D03*
X481948D03*
X478247Y1063135D03*
X472696Y1066324D03*
X476397D03*
X478247Y1069513D03*
X483798Y1066324D03*
X480097Y1072702D03*
Y1066324D03*
X474546Y1063135D03*
Y1069513D03*
X481948Y1063135D03*
Y1069513D03*
X470845Y1063135D03*
Y1069513D03*
X476397Y1072702D03*
X472696D03*
X483798D03*
X485649Y1082269D03*
Y1088647D03*
X474546Y1082269D03*
Y1088647D03*
X481948Y1082269D03*
Y1088647D03*
X478247Y1075891D03*
X476397Y1079080D03*
X472696D03*
X478247Y1088647D03*
Y1082269D03*
X483798Y1079080D03*
X480097D03*
Y1085458D03*
X474546Y1075891D03*
X481948D03*
X470845D03*
X474546Y1082269D03*
Y1088647D03*
X481948Y1082269D03*
Y1088647D03*
X470845Y1082269D03*
Y1088647D03*
X472696Y1085458D03*
X476397D03*
X483798D03*
X474546Y1095025D03*
X481948D03*
X485649D03*
X480097Y1104592D03*
X483798D03*
X480097Y1098214D03*
X478247Y1095025D03*
X472696Y1091836D03*
X476397D03*
X480097D03*
X483798D03*
X474546Y1095025D03*
X481948D03*
X470845D03*
X472696Y1098214D03*
X476397D03*
X483798D03*
X478247Y1101403D03*
X472696Y1104592D03*
X481948Y1101403D03*
X476397Y1104592D03*
X470845Y1101403D03*
X474546D03*
X472696Y1110970D03*
X476397D03*
X478247Y1107781D03*
Y1114159D03*
X483798Y1110970D03*
X480097D03*
Y1117348D03*
X481948Y1114159D03*
X470845D03*
X481948Y1107781D03*
X474546Y1114159D03*
X470845Y1107781D03*
X474546D03*
X476397Y1117348D03*
X472696D03*
X483798D03*
X476397Y1123726D03*
X472696D03*
X478247Y1120537D03*
Y1126915D03*
Y1133293D03*
X483798Y1123726D03*
X480097D03*
Y1130103D03*
X481948Y1126915D03*
Y1120537D03*
X470845Y1126915D03*
Y1120537D03*
X474546Y1126915D03*
Y1120537D03*
X470845Y1133293D03*
X481948D03*
X474546D03*
X472696Y1130103D03*
X483798D03*
X476396D03*
X478247Y1139670D03*
X476397Y1136481D03*
X472696D03*
X476397Y1149237D03*
X472696D03*
X478247Y1146048D03*
X483798Y1136481D03*
X480097D03*
Y1142859D03*
X483798Y1149237D03*
X481948Y1146048D03*
Y1139670D03*
X470845Y1146048D03*
Y1139670D03*
X474546Y1146048D03*
Y1139670D03*
X472696Y1142859D03*
X476397D03*
X483798D03*
X480097Y1149237D03*
X476397Y1155615D03*
X474546Y1152426D03*
X470845Y1158804D03*
X481948D03*
X483798Y1155615D03*
X480097Y1161993D03*
X476397D03*
X478247Y1152426D03*
X470846Y1165182D03*
X481948D03*
X483798Y1161993D03*
X472696Y1155615D03*
X481948Y1152426D03*
X478247Y1158804D03*
X474546D03*
X478247Y1165182D03*
X480097Y1155615D03*
X474546Y1165182D03*
X470845Y1152426D03*
X472696Y1161993D03*
X471325Y1507295D03*
X476049D03*
X480774D03*
X483774Y1521453D03*
X479049D03*
X474325D03*
X474655Y1514243D03*
X479379D03*
X484104D03*
X471225Y1516970D03*
X475950D03*
X480674D03*
X472800Y1519698D03*
X477525D03*
X482249D03*
X483824Y1536063D03*
X474375D03*
X484325Y1528853D03*
X479600D03*
X474876D03*
X479099Y1536063D03*
X471225Y1530608D03*
X475950D03*
X480674D03*
X472800Y1533336D03*
X477525D03*
X482249D03*
X474325Y1523953D03*
X474876Y1526353D03*
X483774Y1523953D03*
X484325Y1526353D03*
X479049Y1523953D03*
X479600Y1526353D03*
X476049Y1542641D03*
X471325D03*
X480774D03*
X482059Y1592380D03*
X474259D03*
X476019Y1602380D03*
X480299D03*
X482059Y1624292D03*
X476019Y1614292D03*
X474259Y1624292D03*
X480299Y1614292D03*
X499271Y879624D03*
X493719Y876435D03*
X491869Y879624D03*
X488168Y873246D03*
Y879624D03*
X486318Y876435D03*
X490019D03*
X497420D03*
X495570Y879624D03*
X491869Y892380D03*
X495570D03*
X493719Y882813D03*
X490019D03*
X486318D03*
X493719Y889191D03*
X486318D03*
X490019Y895569D03*
X488168Y892380D03*
X497420Y889191D03*
X499271Y892380D03*
X495570Y886002D03*
X491869D03*
X488168D03*
X490019Y889191D03*
X493719Y895569D03*
X486318D03*
X499271Y886002D03*
X497420Y895569D03*
Y882813D03*
X491869Y905135D03*
Y898758D03*
Y911513D03*
X495570Y905135D03*
Y898758D03*
Y911513D03*
X493719Y901947D03*
X486318D03*
X490019D03*
X488168Y898758D03*
Y905135D03*
Y911513D03*
X497420Y901947D03*
X499271Y898758D03*
Y905135D03*
Y911513D03*
X490019Y908324D03*
X493719Y908325D03*
X486318D03*
X497420D03*
X491869Y917891D03*
Y924269D03*
X495570Y917891D03*
Y924269D03*
X493719Y914702D03*
X488168Y917891D03*
X490019Y914702D03*
X486318D03*
X490019Y921080D03*
X488168Y924269D03*
X499271Y917891D03*
X497420Y914702D03*
X499271Y924269D03*
X493719Y921080D03*
X486318D03*
X497420D03*
X491869Y930647D03*
X495570D03*
X493719Y927458D03*
X486318D03*
X490019D03*
X493719Y933836D03*
X490019D03*
X486318D03*
X488168Y930647D03*
X490019Y940214D03*
X497420Y927458D03*
Y933836D03*
X499271Y930647D03*
X493719Y940214D03*
X486318D03*
X497420D03*
X499271Y937025D03*
X488168D03*
X491869D03*
X495570D03*
Y956159D03*
Y943403D03*
Y949781D03*
X491869Y956159D03*
Y943403D03*
Y949781D03*
X488168Y943403D03*
X493719Y946592D03*
X490019D03*
X486318D03*
X488168Y949781D03*
X490019Y952970D03*
X488168Y956159D03*
X497420Y946592D03*
X499271Y943403D03*
Y949781D03*
Y956159D03*
X486318Y952970D03*
X493719D03*
X497420D03*
X495570Y962537D03*
Y968915D03*
X491869Y962537D03*
Y968915D03*
X490019Y965726D03*
X493719Y959348D03*
X490019D03*
X486318D03*
X488168Y962537D03*
Y968915D03*
X499271Y962537D03*
X497420Y959348D03*
X499271Y968915D03*
X493719Y965726D03*
X486318D03*
X497420D03*
X495570Y975293D03*
X491869D03*
Y981671D03*
X490019Y978482D03*
X493719Y972104D03*
X488168Y975293D03*
X490019Y972104D03*
X486318D03*
X490019Y984860D03*
X497420Y972104D03*
X499271Y975293D03*
Y981671D03*
X497420Y984860D03*
X493719Y978482D03*
X486318D03*
X488168Y981671D03*
X493719Y984860D03*
X486318D03*
X495570Y981671D03*
X497420Y978482D03*
X491869Y994427D03*
Y988049D03*
X490019Y997616D03*
Y991238D03*
X491869Y1000805D03*
X497420Y991238D03*
Y997616D03*
X499271Y988049D03*
Y994427D03*
Y1000805D03*
X488168Y988049D03*
Y994427D03*
X486318Y997616D03*
X493719D03*
X486318Y991238D03*
X493719D03*
X488168Y1000805D03*
X495570Y994427D03*
Y988049D03*
Y1000805D03*
X491869Y1007183D03*
X490019Y1010372D03*
Y1003994D03*
X497420Y1010372D03*
Y1003994D03*
X499271Y1007183D03*
X488168D03*
X486318Y1003994D03*
Y1010372D03*
X493719Y1003994D03*
Y1010372D03*
X495570Y1007183D03*
X494901Y1028056D03*
X487499D03*
X491200D03*
X498601D03*
X485649Y1044001D03*
X494901Y1034434D03*
X491200Y1040812D03*
X487499Y1034434D03*
X489349Y1031245D03*
X493050Y1037623D03*
X485649D03*
X493050Y1044001D03*
X496751Y1031245D03*
X498601Y1040812D03*
X494901D03*
X489349Y1044001D03*
X487499Y1040812D03*
X489349Y1037623D03*
X496751Y1044001D03*
Y1037623D03*
X485649Y1031245D03*
X493050D03*
X491200Y1034434D03*
X498601D03*
X496751Y1063135D03*
X493050D03*
X496751Y1050379D03*
X491200Y1047190D03*
X493050Y1056757D03*
X491200Y1059946D03*
Y1053568D03*
X485649Y1056757D03*
X493050Y1050379D03*
X485649D03*
X498601Y1047190D03*
Y1053568D03*
X494901Y1047190D03*
X487499D03*
X489349Y1050379D03*
X494901Y1059946D03*
Y1053568D03*
X487499Y1059946D03*
X489349Y1056757D03*
X487499Y1053568D03*
X496751Y1056757D03*
X498601Y1059946D03*
X496751Y1069513D03*
X493050D03*
X496751Y1075891D03*
X493050D03*
X489349Y1063135D03*
X494901Y1066324D03*
X491200D03*
X487499D03*
X491200Y1072702D03*
X489349Y1069513D03*
X498601Y1066324D03*
X485649Y1063135D03*
Y1069513D03*
X496751Y1063135D03*
Y1069513D03*
X493050Y1063135D03*
Y1069513D03*
X494901Y1072702D03*
X487499D03*
X498601D03*
X496751Y1082269D03*
Y1088647D03*
X493050Y1082269D03*
Y1088647D03*
X489349Y1082269D03*
X498601Y1079080D03*
X494901D03*
X489349Y1075891D03*
X487499Y1079080D03*
X491200D03*
Y1085458D03*
X489349Y1088647D03*
X485649Y1075891D03*
X496751D03*
X493050D03*
X485649Y1082269D03*
Y1088647D03*
X496751Y1082269D03*
Y1088647D03*
X493050Y1082269D03*
Y1088647D03*
X494901Y1085458D03*
X487499D03*
X498601D03*
X496751Y1095025D03*
X493050D03*
X494901Y1091836D03*
X487499D03*
X491200D03*
X489349Y1095025D03*
X494901Y1104592D03*
X491200Y1098214D03*
Y1104592D03*
X487499D03*
X498601Y1091836D03*
Y1104592D03*
X496751Y1101403D03*
X485649Y1095025D03*
X496751D03*
X493050D03*
X494901Y1098214D03*
X487499D03*
X498601D03*
X493050Y1101403D03*
X485649D03*
X489349D03*
X491200Y1110970D03*
X489349Y1114159D03*
X491200Y1117348D03*
X498601Y1110970D03*
X494901D03*
X489349Y1107781D03*
X487499Y1110970D03*
X493050Y1107781D03*
Y1114159D03*
X485649D03*
X496751Y1107781D03*
Y1114159D03*
X485649Y1107781D03*
X494901Y1117348D03*
X487499D03*
X498601D03*
X494901Y1123726D03*
X489349Y1126915D03*
X491200Y1123726D03*
X487499D03*
X489349Y1120537D03*
X491200Y1130103D03*
X489349Y1133293D03*
X498601Y1123726D03*
X493050Y1120537D03*
X485649Y1126915D03*
Y1120537D03*
X496751D03*
X493050Y1133293D03*
Y1126915D03*
X496751Y1133293D03*
Y1126915D03*
X485649Y1133293D03*
X487499Y1130103D03*
X494901D03*
X498601D03*
X494901Y1136481D03*
X489349Y1139670D03*
X491200Y1136481D03*
X487499D03*
X491200Y1142859D03*
X494901Y1149237D03*
X489349Y1146048D03*
X487499Y1149237D03*
X498601Y1136481D03*
Y1149237D03*
X493050Y1146048D03*
Y1139670D03*
X485649Y1146048D03*
Y1139670D03*
X496751Y1146048D03*
Y1139670D03*
X494901Y1142859D03*
X487499D03*
X491200Y1149237D03*
X498601Y1142859D03*
X487499Y1155615D03*
X485649Y1152426D03*
X493050Y1158804D03*
X498601Y1155615D03*
X496751Y1152426D03*
X498601Y1161993D03*
X487499D03*
X491200D03*
X489349Y1152426D03*
X493050Y1165182D03*
X485649Y1158804D03*
Y1165182D03*
X496751D03*
Y1158804D03*
X489349D03*
X491200Y1155615D03*
X493050Y1152426D03*
X494901Y1161993D03*
Y1155615D03*
X489349Y1165182D03*
X485498Y1507295D03*
X490222D03*
X499671D03*
X494947D03*
X497947Y1521453D03*
X493222D03*
X488498D03*
X488828Y1514243D03*
X493553D03*
X498277D03*
X499572Y1516970D03*
X485399D03*
X490123D03*
X494847D03*
X486973Y1519698D03*
X491698D03*
X496422D03*
X497997Y1536063D03*
X493273D03*
X498498Y1528853D03*
X493773D03*
X489049D03*
X488548Y1536063D03*
X499572Y1530608D03*
X485399D03*
X490123D03*
X494847D03*
X486973Y1533336D03*
X491698D03*
X496422D03*
X497947Y1523953D03*
X498498Y1526353D03*
X488498Y1523953D03*
X489049Y1526353D03*
X493222Y1523953D03*
X493773Y1526353D03*
X494947Y1542641D03*
X485498D03*
X490222D03*
X499671D03*
X498379Y1592380D03*
X486319D03*
X494119D03*
X488079Y1602380D03*
X492359D03*
X498379Y1624292D03*
X488079Y1614292D03*
X486319Y1624292D03*
X494119D03*
X492359Y1614292D03*
X497440Y1684454D03*
Y1679920D03*
Y1675383D03*
Y1698627D03*
Y1694093D03*
Y1689556D03*
Y1712800D03*
Y1708266D03*
Y1703729D03*
Y1726974D03*
Y1722440D03*
Y1717903D03*
X510373Y879624D03*
X502971D03*
X501133Y872118D03*
X514074Y879624D03*
X508523Y876435D03*
X506672Y879624D03*
X512223Y876435D03*
X501121D03*
X508523Y882813D03*
X506672Y886002D03*
X502971D03*
X504822Y882813D03*
X506672Y892380D03*
X501121Y895569D03*
X512223Y882813D03*
X514074Y886002D03*
X512223Y889191D03*
X514074Y892380D03*
X510373Y886002D03*
X504822Y889191D03*
X508523D03*
X502971Y892380D03*
X508523Y895569D03*
X504822D03*
X510373Y892380D03*
X501121Y889191D03*
X512223Y895569D03*
X501121Y882813D03*
X506672Y898758D03*
Y905135D03*
Y911513D03*
X501121Y908325D03*
X512223Y901947D03*
X514074Y898758D03*
Y911513D03*
X512223Y908325D03*
X508523D03*
X502971Y911513D03*
X510373Y898758D03*
X504822Y901947D03*
X508523D03*
X502971Y905135D03*
X510373D03*
X504822Y908325D03*
X510373Y911513D03*
X502971Y898758D03*
X514074Y905135D03*
X501121Y901947D03*
X506672Y917891D03*
X501121Y921080D03*
X506672Y924269D03*
X514074Y917891D03*
X512223Y921080D03*
X510373Y917891D03*
X504822Y921080D03*
X508523D03*
X502971Y924269D03*
X510373D03*
X508523Y914702D03*
X504822D03*
X502971Y917891D03*
X512223Y914702D03*
X514074Y924269D03*
X501121Y914702D03*
X506672Y930647D03*
X501121Y933836D03*
X506672Y937025D03*
X501121Y940214D03*
X512223Y927458D03*
X514074Y930647D03*
X512223Y940214D03*
X514074Y937025D03*
X504822Y927458D03*
X508523D03*
X502971Y930647D03*
X510373Y937025D03*
X504822Y940214D03*
X508523D03*
Y933836D03*
X504822D03*
X510373Y930647D03*
X502971Y937025D03*
X512223Y933836D03*
X501121Y927458D03*
X506672Y943403D03*
Y949781D03*
X501121Y952970D03*
X506672Y956159D03*
X514074Y949781D03*
X512223Y946592D03*
X514074Y956159D03*
X502971Y943403D03*
X510373D03*
X504822Y946592D03*
X508523D03*
X502971Y949781D03*
X510373Y956159D03*
X508523Y952970D03*
X504822D03*
X510373Y949781D03*
X502971Y956159D03*
X514074Y943403D03*
X512223Y952970D03*
X501121Y946592D03*
X506672Y962537D03*
X501121Y965726D03*
X506672Y968915D03*
X512223Y959348D03*
Y965726D03*
X514074Y968915D03*
X510373Y962537D03*
X504822Y965726D03*
X508523D03*
X502971Y968915D03*
X504822Y959348D03*
X508523D03*
X502971Y962537D03*
X510373Y968915D03*
X514074Y962537D03*
X501121Y959348D03*
X510373Y981671D03*
X506672Y975293D03*
Y981671D03*
X501121Y978482D03*
X508523Y984860D03*
X514074Y975293D03*
X512223Y978482D03*
Y984860D03*
X504822D03*
X510373Y975293D03*
X504822Y978482D03*
X508523D03*
X502971Y981671D03*
X508523Y972104D03*
X504822D03*
X502971Y975293D03*
X514074Y981671D03*
X512223Y972104D03*
X501121D03*
Y984860D03*
X506672Y988049D03*
Y994427D03*
Y1000805D03*
X514074Y988049D03*
Y994427D03*
X512223Y997616D03*
X502971Y988049D03*
X510373Y994427D03*
X508523Y997616D03*
X504822D03*
X502971Y1000805D03*
X510373D03*
Y988049D03*
X504822Y991238D03*
X501121Y997616D03*
Y991238D03*
X512223D03*
X514074Y1000805D03*
X502971Y994427D03*
X508523Y991238D03*
X506672Y1007183D03*
X514074D03*
X512223Y1003994D03*
X508523Y1010372D03*
X510373Y1007183D03*
X508523Y1003994D03*
X504822D03*
X502971Y1007183D03*
X501121Y1010372D03*
X512223D03*
X501121Y1003994D03*
X504822Y1010372D03*
X502302Y1028056D03*
X513405D03*
X506003D03*
X509704D03*
X507853Y1037623D03*
X500452D03*
X502302Y1034434D03*
X507853Y1044001D03*
X500452D03*
X507853Y1031245D03*
X513405Y1034434D03*
Y1040812D03*
X504153Y1031245D03*
X506003Y1034434D03*
X509704D03*
X511554Y1037623D03*
X504153D03*
X506003Y1040812D03*
X509704D03*
X504153Y1044001D03*
X502302Y1040812D03*
X500452Y1031245D03*
X511554Y1044001D03*
Y1031245D03*
X507853Y1056757D03*
Y1050379D03*
X500452Y1056757D03*
X504153D03*
X500452Y1050379D03*
X502302Y1059946D03*
X506003D03*
X513405Y1053568D03*
Y1059946D03*
X504153Y1050379D03*
X509704Y1059946D03*
X506003Y1047190D03*
X511554Y1050379D03*
X509704Y1053568D03*
X502302Y1047190D03*
Y1053568D03*
X513405Y1047190D03*
X511554Y1056757D03*
X509704Y1047190D03*
X506003Y1053568D03*
X507853Y1063135D03*
X500452D03*
X507853Y1069513D03*
X500452D03*
X502302Y1072702D03*
X513405D03*
X509704D03*
X504153Y1063135D03*
X511554D03*
X506003Y1066324D03*
X504153Y1069513D03*
X511554D03*
X506003Y1072702D03*
X509704Y1066324D03*
X513405D03*
X502302D03*
X507853Y1075891D03*
X500452D03*
X507853Y1088647D03*
X500452D03*
X502302Y1085458D03*
X507853Y1082269D03*
X500452D03*
X513405Y1079080D03*
X504153Y1075891D03*
X511554D03*
X506003Y1079080D03*
X509704D03*
X504153Y1082269D03*
X511554D03*
X506003Y1085458D03*
X511554Y1088647D03*
X504153D03*
X509704Y1085458D03*
X513405D03*
X502302Y1079080D03*
X507853Y1095025D03*
X500452D03*
X502302Y1098214D03*
X507853Y1101403D03*
X502302Y1104592D03*
X513405Y1091836D03*
Y1098214D03*
X511554Y1101403D03*
X506003Y1104592D03*
X509704Y1091836D03*
X504153Y1095025D03*
X511554D03*
X506003Y1098214D03*
X509704D03*
X504153Y1101403D03*
X509704Y1104592D03*
X506003Y1091836D03*
X513405Y1104592D03*
X502302Y1091836D03*
X500452Y1101403D03*
X507853Y1107781D03*
X500452D03*
X507853Y1114159D03*
X502302Y1117348D03*
X500452Y1114159D03*
X513405Y1110970D03*
Y1117348D03*
X509704Y1110970D03*
X504153Y1114159D03*
X511554D03*
X506003Y1117348D03*
X509704D03*
X511554Y1107781D03*
X504153D03*
X506003Y1110970D03*
X502302D03*
X507853Y1120537D03*
X500452D03*
X507853Y1126915D03*
X500452D03*
X507853Y1133293D03*
X500452D03*
X502302Y1130103D03*
X513405Y1130104D03*
X504153Y1120537D03*
X511554D03*
X506003Y1123726D03*
X509704Y1130103D03*
X504153Y1133293D03*
X511554D03*
Y1126915D03*
X504153D03*
X509704Y1123726D03*
X506003Y1130103D03*
X513405Y1123726D03*
X502302D03*
X507853Y1139670D03*
X500452D03*
X502302Y1142859D03*
X507853Y1146048D03*
X500452D03*
X513405Y1136481D03*
Y1149237D03*
X506003Y1136481D03*
X509704D03*
X504153Y1139670D03*
X511554D03*
X506003Y1142859D03*
X509704Y1149237D03*
X511554Y1146048D03*
X504153D03*
X509704Y1142859D03*
X506003Y1149237D03*
X513405Y1142859D03*
X502302Y1136481D03*
Y1149237D03*
X511554Y1165182D03*
X509704Y1155615D03*
X507853Y1152426D03*
X502302Y1155615D03*
X507853Y1158804D03*
X504153D03*
X513405Y1155615D03*
X504153Y1152426D03*
X511554D03*
X506003Y1155615D03*
X513405Y1161993D03*
X511554Y1158804D03*
X509704Y1161993D03*
X502302D03*
X500452Y1152426D03*
X506003Y1161993D03*
X500452Y1158804D03*
Y1165182D03*
X507853D03*
X504153D03*
X504396Y1507295D03*
X509120D03*
X513844D03*
X512120Y1521453D03*
X507396D03*
X502671D03*
X503001Y1514243D03*
X507726D03*
X512450D03*
X504296Y1516970D03*
X509021D03*
X513745D03*
X501147Y1519698D03*
X505871D03*
X510595D03*
X507446Y1536063D03*
X512671Y1528853D03*
X507947D03*
X503222D03*
X512170Y1536063D03*
X502721D03*
X504296Y1530608D03*
X509021D03*
X513745D03*
X501147Y1533336D03*
X505871D03*
X510595D03*
X507947Y1526353D03*
X507396Y1523953D03*
X512120D03*
X512671Y1526353D03*
X503222D03*
X502671Y1523953D03*
X513844Y1542641D03*
X504396D03*
X509120D03*
X510439Y1592380D03*
X506179D03*
X512199Y1602380D03*
X500139D03*
X504419D03*
X512199Y1614292D03*
X500139D03*
X506179Y1624292D03*
X510439D03*
X504419Y1614292D03*
X505314Y1679320D03*
Y1683857D03*
X513188Y1684454D03*
Y1679920D03*
Y1675383D03*
X505314Y1688391D03*
Y1693493D03*
Y1698030D03*
X513188Y1698627D03*
Y1694093D03*
Y1689556D03*
X505314Y1707666D03*
Y1712203D03*
X513188Y1712800D03*
Y1708266D03*
Y1703729D03*
X505314Y1716737D03*
Y1702564D03*
Y1721840D03*
Y1726377D03*
Y1730911D03*
X513188Y1726974D03*
Y1722440D03*
Y1717903D03*
X525176Y879624D03*
X515924Y876435D03*
X525176Y873246D03*
X521475Y879624D03*
X519625Y876435D03*
X517775Y879624D03*
X521475Y873246D03*
X517775D03*
X527027Y876435D03*
X528877Y879624D03*
X525176Y886002D03*
X523326Y882813D03*
X517775Y886002D03*
X519625Y882813D03*
X527027Y895569D03*
Y889191D03*
X525176Y892380D03*
X519625Y889191D03*
Y895569D03*
X528877Y886002D03*
Y892380D03*
X521475Y886002D03*
X515924Y889191D03*
X523326D03*
X517775Y892380D03*
X523326Y895569D03*
X515924D03*
X521475Y892380D03*
X515924Y882813D03*
X527027D03*
Y901947D03*
X525176Y898758D03*
X519625Y901947D03*
X525176Y905135D03*
Y911513D03*
X519625Y908325D03*
X527027Y908324D03*
X528877Y911513D03*
Y905135D03*
Y898758D03*
X523326Y908325D03*
X517775Y911513D03*
X521475Y898758D03*
X515924Y901947D03*
X523326D03*
X517775Y905135D03*
X521475D03*
X515924Y908325D03*
X521475Y911513D03*
X517775Y898758D03*
X525176Y917891D03*
X519625Y914702D03*
X527027D03*
Y921080D03*
X525176Y924269D03*
X519625Y921080D03*
X528877Y924269D03*
Y917891D03*
X521475D03*
X515924Y921080D03*
X523326D03*
X517775Y924269D03*
X521475D03*
X523326Y914702D03*
X515924D03*
X517775Y917891D03*
X525176Y937025D03*
X527027Y927458D03*
Y933836D03*
X525176Y930647D03*
X519625Y927458D03*
Y933836D03*
X527027Y940214D03*
X519625D03*
X528877Y930647D03*
Y937025D03*
X515924Y927458D03*
X523326D03*
X517775Y930647D03*
X521475Y937025D03*
X515924Y940214D03*
X523326D03*
Y933836D03*
X515924D03*
X521475Y930647D03*
X517775Y937025D03*
X527027Y946592D03*
X519625D03*
X525176Y943403D03*
Y949781D03*
X527027Y952970D03*
X525176Y956159D03*
X519625Y952970D03*
X528877Y943403D03*
Y949781D03*
Y956159D03*
X517775Y943403D03*
X521475D03*
X515924Y946592D03*
X523326D03*
X517775Y949781D03*
X521475Y956159D03*
X523326Y952970D03*
X515924D03*
X521475Y949781D03*
X517775Y956159D03*
X527027Y959348D03*
Y965726D03*
X525176Y962537D03*
X519625Y959348D03*
Y965726D03*
X525176Y968915D03*
X528877D03*
Y962537D03*
X521475D03*
X515924Y965726D03*
X523326D03*
X517775Y968915D03*
X515924Y959348D03*
X523326D03*
X517775Y962537D03*
X521475Y968915D03*
Y981671D03*
X519625Y978482D03*
X527027Y984860D03*
X523326D03*
X519625D03*
X527027Y972104D03*
Y978482D03*
X525176Y975293D03*
Y981671D03*
X519625Y972104D03*
X528877Y981671D03*
Y975293D03*
X515924Y984860D03*
X521475Y975293D03*
X515924Y978482D03*
X523326D03*
X517775Y981671D03*
X523326Y972104D03*
X515924D03*
X517775Y975293D03*
X527027Y991238D03*
Y997616D03*
X525176Y988049D03*
Y994427D03*
X519625Y991238D03*
Y997616D03*
X525176Y1000805D03*
X528877Y988049D03*
Y1000805D03*
X517775Y988049D03*
X521475Y994427D03*
X523326Y997616D03*
X515924D03*
X517775Y1000805D03*
X521475D03*
Y988049D03*
X515924Y991238D03*
X517775Y994427D03*
X523326Y991238D03*
X528877Y994427D03*
X527027Y1010372D03*
Y1003994D03*
X525176Y1007183D03*
X519625Y1010372D03*
Y1003994D03*
X528877Y1007183D03*
X523326Y1010372D03*
X521475Y1007183D03*
X523326Y1003994D03*
X515924D03*
X517775Y1007183D03*
X515924Y1010372D03*
X520806Y1028056D03*
X528208D03*
X517105D03*
X524507D03*
X526357Y1037623D03*
Y1044001D03*
Y1031245D03*
X515255D03*
X520806Y1040812D03*
Y1034434D03*
X515255Y1044001D03*
X528208Y1040812D03*
Y1034434D03*
X518956Y1031245D03*
X517105Y1034434D03*
X524507D03*
X522657Y1037623D03*
X518956D03*
X517105Y1040812D03*
X524507D03*
X518956Y1044001D03*
X515255Y1037623D03*
X522656Y1044001D03*
Y1031245D03*
X520806Y1047190D03*
X526357Y1050379D03*
Y1056757D03*
X520806Y1053568D03*
X515255Y1050379D03*
X518956Y1056757D03*
X520806Y1059946D03*
X517105D03*
X528208Y1047190D03*
Y1053568D03*
Y1059946D03*
X518956Y1050379D03*
X524507Y1059946D03*
X517105Y1047190D03*
X522657Y1050379D03*
X524507Y1053568D03*
X515255Y1056757D03*
X522656D03*
X524507Y1047190D03*
X517105Y1053568D03*
X526357Y1063135D03*
X515255D03*
X526357Y1069513D03*
X520806Y1066324D03*
Y1072702D03*
X515255Y1069513D03*
X528208Y1066324D03*
Y1072702D03*
X524507D03*
X518956Y1063135D03*
X522657D03*
X517105Y1066324D03*
X518956Y1069513D03*
X522657D03*
X517105Y1072702D03*
X524507Y1066324D03*
X526357Y1075891D03*
X520806Y1079080D03*
X526357Y1088647D03*
Y1082269D03*
X520806Y1085458D03*
X515255Y1088647D03*
Y1082269D03*
X528208Y1079080D03*
Y1085458D03*
X518956Y1075891D03*
X522657D03*
X517105Y1079080D03*
X524507D03*
X518956Y1082269D03*
X522657D03*
X517105Y1085458D03*
X522657Y1088647D03*
X518956D03*
X524507Y1085458D03*
X515255Y1075891D03*
X526357Y1095025D03*
X520806Y1091836D03*
X526357Y1101403D03*
X520806Y1104592D03*
Y1098214D03*
X515255Y1101403D03*
X528208Y1091836D03*
Y1104592D03*
Y1098214D03*
X522657Y1101403D03*
X517105Y1104592D03*
X524507Y1091836D03*
X518956Y1095025D03*
X522657D03*
X517105Y1098214D03*
X524507D03*
X518956Y1101403D03*
X524507Y1104592D03*
X517105Y1091836D03*
X515255Y1095025D03*
X526357Y1107781D03*
X520806Y1110970D03*
X515255Y1107781D03*
X526357Y1114159D03*
X520806Y1117348D03*
X528208Y1110970D03*
Y1117348D03*
X524507Y1110970D03*
X518956Y1114159D03*
X522657D03*
X517105Y1117348D03*
X524507D03*
X522657Y1107781D03*
X518956D03*
X517105Y1110970D03*
X515255Y1114159D03*
X528208Y1130104D03*
X526357Y1120537D03*
Y1126915D03*
X520806Y1123726D03*
X515255Y1120537D03*
Y1126915D03*
X526357Y1133293D03*
X520806Y1130103D03*
X528208Y1123726D03*
X518956Y1120537D03*
X522657D03*
X517105Y1123726D03*
X524507Y1130103D03*
X518956Y1133293D03*
X522657D03*
Y1126915D03*
X518956D03*
X524507Y1123726D03*
X517105Y1130103D03*
X515255Y1133293D03*
Y1139670D03*
X520806Y1142859D03*
X526357Y1139670D03*
X520806Y1136481D03*
X526357Y1146048D03*
X520806Y1149237D03*
X515255Y1146048D03*
X528208Y1136481D03*
Y1142859D03*
Y1149237D03*
X517105Y1136481D03*
X524507D03*
X518956Y1139670D03*
X522657D03*
X517105Y1142859D03*
X524507Y1149237D03*
X522657Y1146048D03*
X518956D03*
X524507Y1142859D03*
X517105Y1149237D03*
X528208Y1161993D03*
X526357Y1152426D03*
Y1158804D03*
X520806Y1155615D03*
X517105D03*
X522657Y1158804D03*
X515255D03*
X517105Y1161993D03*
X528208Y1155615D03*
X518956Y1152426D03*
X522657D03*
X524507Y1155615D03*
X515255Y1152426D03*
X524507Y1161993D03*
X520806D03*
X518956Y1158804D03*
X526370Y1165290D03*
X515268D03*
X518969D03*
X522670D03*
X518569Y1507295D03*
X523293D03*
X529594Y1507355D03*
X527494D03*
X517175Y1514243D03*
X526314Y1521453D03*
X521569D03*
X516845D03*
X521899Y1514243D03*
X518470Y1516970D03*
X523194D03*
X515320Y1519698D03*
X520044D03*
X524769D03*
X516895Y1536063D03*
X522120Y1528853D03*
X517396D03*
X521619Y1536063D03*
X526950D03*
X518470Y1530608D03*
X523194D03*
X515320Y1533336D03*
X520044D03*
X524769D03*
X521569Y1523953D03*
X522120Y1526353D03*
X517396D03*
X516845Y1523953D03*
X523293Y1542641D03*
X518569D03*
X518239Y1592380D03*
X522499D03*
X524259Y1602380D03*
X528539D03*
X516479D03*
X524259Y1614292D03*
X518239Y1624292D03*
X522499D03*
X528539Y1614292D03*
X516479D03*
X521062Y1679320D03*
Y1683857D03*
X528936Y1684454D03*
Y1679920D03*
Y1675383D03*
X521062Y1688391D03*
Y1693493D03*
Y1698030D03*
X528936Y1698627D03*
Y1694093D03*
Y1689556D03*
X521062Y1716737D03*
Y1702564D03*
Y1707666D03*
Y1712203D03*
X528936Y1712800D03*
Y1708266D03*
Y1703729D03*
X521062Y1721840D03*
Y1726377D03*
Y1730911D03*
X528936Y1726974D03*
Y1722440D03*
Y1717903D03*
X534428Y876435D03*
X539979Y879624D03*
X532578D03*
X541830Y876435D03*
X543680Y879624D03*
X530727Y876435D03*
X532578Y873246D03*
X538129Y889191D03*
X539979Y892380D03*
X532578D03*
X543680Y886002D03*
X538129Y882813D03*
X532578Y886002D03*
X534428Y882813D03*
X536279Y886002D03*
X530727Y889191D03*
X534428D03*
Y895569D03*
X530727D03*
X536279Y892380D03*
X541830Y889191D03*
X543680Y892380D03*
X541830Y895569D03*
X538129D03*
X539979Y886002D03*
X530727Y882813D03*
X541830D03*
X538129Y901947D03*
X539979Y898758D03*
X532578D03*
X539979Y911513D03*
X538129Y908325D03*
X532578Y905135D03*
Y911513D03*
X534428Y908325D03*
X536279Y898758D03*
X530727Y901947D03*
X534428D03*
X536279Y905135D03*
X530727Y908325D03*
X536279Y911513D03*
X543680D03*
X541830Y901947D03*
X543680Y905135D03*
X541830Y908325D03*
X543680Y898758D03*
X539979Y905135D03*
Y917891D03*
X532578D03*
X538129Y921080D03*
X532578Y924269D03*
X536279Y917891D03*
X530727Y921080D03*
X534428D03*
X536279Y924269D03*
X534428Y914702D03*
X530727D03*
X541830Y921080D03*
X543680Y924269D03*
X541830Y914702D03*
X543680Y917891D03*
X539979Y924269D03*
X538129Y914702D03*
Y927458D03*
X539979Y930647D03*
X532578D03*
X539979Y937025D03*
X538129Y940214D03*
X532578Y937025D03*
X530727Y927458D03*
X534428D03*
X536279Y937025D03*
X530727Y940214D03*
X534428D03*
Y933836D03*
X530727D03*
X536279Y930647D03*
X541830Y927458D03*
X543680Y930647D03*
X541830Y940214D03*
Y933836D03*
X543680Y937025D03*
X538129Y933836D03*
X539979Y949781D03*
X538129Y946592D03*
X532578Y943403D03*
Y949781D03*
X539979Y956159D03*
X532578D03*
X536279Y943403D03*
X530727Y946592D03*
X534428D03*
X536279Y956159D03*
X534428Y952970D03*
X530727D03*
X536279Y949781D03*
X543680Y943403D03*
X541830Y946592D03*
X543680Y949781D03*
X541830Y952970D03*
X543680Y956159D03*
X538129Y952970D03*
X539979Y943403D03*
X538129Y959348D03*
Y965726D03*
X532578Y962537D03*
X539979Y968915D03*
X532578D03*
X536279Y962537D03*
X530727Y965726D03*
X534428D03*
X530727Y959348D03*
X534428D03*
X536279Y968915D03*
X541830Y965726D03*
X543680Y968915D03*
X541830Y959348D03*
X543680Y962537D03*
X539979D03*
Y975293D03*
X532578D03*
X538129Y978482D03*
X536279Y981671D03*
X532578D03*
X538129Y984860D03*
X534428D03*
X530727D03*
X536279Y975293D03*
X530727Y978482D03*
X534428D03*
Y972104D03*
X530727D03*
X541830Y984860D03*
Y978482D03*
X543680Y981671D03*
X541830Y972104D03*
X543680Y975293D03*
X538129Y972104D03*
X539979Y981671D03*
X532578Y994427D03*
X539979Y988049D03*
X532578D03*
X539979Y994427D03*
X538129Y997616D03*
X532578Y1000805D03*
X536279Y994427D03*
X534428Y997616D03*
X530727D03*
X536279Y1000805D03*
Y988049D03*
X530727Y991238D03*
X543680Y988049D03*
X541830Y997616D03*
X543680Y1000805D03*
X541830Y991238D03*
X539979Y1000805D03*
X538129Y991238D03*
X543680Y994427D03*
X534428Y991238D03*
X539978Y1007184D03*
X538129Y1003994D03*
X532578Y1007183D03*
X534428Y1010372D03*
X536279Y1007183D03*
X534428Y1003994D03*
X530727D03*
X541830D03*
X543680Y1007183D03*
X538129Y1010372D03*
X530727D03*
X541830D03*
X539310Y1028056D03*
X531908D03*
X543011D03*
X535609D03*
X541160Y1031245D03*
X533759D03*
X539310Y1034434D03*
Y1040812D03*
X533759Y1037623D03*
X541160Y1044001D03*
X533759D03*
X530058Y1031245D03*
X531908Y1034434D03*
X535609D03*
X537460Y1037623D03*
X530058D03*
X531908Y1040812D03*
X535609D03*
X530058Y1044001D03*
X543011Y1034434D03*
Y1040812D03*
X541160Y1037623D03*
X537460Y1044001D03*
Y1031245D03*
X543011Y1059946D03*
X530058Y1056757D03*
X541160Y1050379D03*
X539310Y1053568D03*
X533759Y1050379D03*
Y1056757D03*
X539310Y1059946D03*
X531908D03*
X530058Y1050379D03*
X535609Y1059946D03*
X531908Y1047190D03*
X537460Y1050379D03*
X535609Y1053568D03*
X543011Y1047190D03*
X541160Y1056757D03*
X539310Y1047190D03*
X543011Y1053568D03*
X537460Y1056757D03*
X535609Y1047190D03*
X531908Y1053568D03*
X541160Y1063135D03*
X533759D03*
X541160Y1069513D03*
X539310Y1072702D03*
X533759Y1069513D03*
X535609Y1072702D03*
X530058Y1063135D03*
X537460D03*
X531908Y1066324D03*
X530058Y1069513D03*
X537460D03*
X531908Y1072702D03*
X535609Y1066324D03*
X543011D03*
Y1072702D03*
X539310Y1066324D03*
X533759Y1075891D03*
X539310Y1079080D03*
X541160Y1088647D03*
X533759D03*
X541160Y1082269D03*
X533759D03*
X530058Y1075891D03*
X537460D03*
X531908Y1079080D03*
X535609D03*
X530058Y1082269D03*
X537460D03*
X531908Y1085458D03*
X537460Y1088647D03*
X530058D03*
X535609Y1085458D03*
X543011Y1079080D03*
Y1085458D03*
X539310D03*
X541160Y1075891D03*
X539310Y1091836D03*
X533759Y1095025D03*
X539310Y1098214D03*
X541160Y1101403D03*
X533759D03*
X537460D03*
X531908Y1104592D03*
X535609Y1091836D03*
X530058Y1095025D03*
X537460D03*
X531908Y1098214D03*
X535609D03*
X530058Y1101403D03*
X535609Y1104592D03*
X531908Y1091836D03*
X543011Y1104592D03*
Y1098214D03*
Y1091836D03*
X541160Y1095025D03*
X539310Y1104592D03*
X541160Y1107781D03*
X533759D03*
X539310Y1110970D03*
Y1117348D03*
X533759Y1114159D03*
X535609Y1110970D03*
X530058Y1114159D03*
X537460D03*
X531908Y1117348D03*
X535609D03*
X537460Y1107781D03*
X530058D03*
X531908Y1110970D03*
X543011Y1117348D03*
Y1110970D03*
X541160Y1114159D03*
Y1120537D03*
X533759D03*
X541160Y1126915D03*
X533759D03*
X539310Y1130103D03*
X533759Y1133293D03*
X530058Y1120537D03*
X537460D03*
X531908Y1123726D03*
X535609Y1130103D03*
X530058Y1133293D03*
X537460D03*
Y1126915D03*
X530058D03*
X535609Y1123726D03*
X531908Y1130103D03*
X543011Y1123726D03*
Y1130103D03*
X539310Y1123726D03*
X541160Y1133293D03*
Y1139670D03*
X539310Y1136481D03*
X533759Y1139670D03*
Y1146048D03*
X541160D03*
X539310Y1149237D03*
X531908Y1136481D03*
X535609D03*
X530058Y1139670D03*
X537460D03*
X531908Y1142859D03*
X535609Y1149237D03*
X537460Y1146048D03*
X530058D03*
X535609Y1142859D03*
X531908Y1149237D03*
X543011Y1136481D03*
Y1142859D03*
Y1149237D03*
X539310Y1142859D03*
X543011Y1155615D03*
X533759Y1158804D03*
X530058D03*
X539310Y1155615D03*
X535609D03*
X533759Y1152426D03*
X543011Y1161993D03*
X530058Y1152426D03*
X537460D03*
X531908Y1155615D03*
X541160Y1152426D03*
X531908Y1161993D03*
X535609D03*
X539310D03*
X537460Y1158804D03*
X541160D03*
X533772Y1165290D03*
X530071D03*
X531001Y1514073D03*
X530945Y1516336D03*
X532310Y1536640D03*
X531926Y1534540D03*
X531537Y1531618D03*
X531208Y1528698D03*
X530711Y1538658D03*
X542359Y1592380D03*
X530299D03*
X534559D03*
X536319Y1602380D03*
X540599D03*
X542359Y1624292D03*
X536319Y1614292D03*
X530299Y1624292D03*
X534559D03*
X540599Y1614292D03*
X536810Y1679320D03*
Y1683857D03*
X544684Y1684454D03*
Y1679920D03*
Y1675383D03*
X536810Y1688391D03*
Y1693493D03*
Y1698030D03*
X544684Y1698627D03*
Y1694093D03*
Y1689556D03*
X536810Y1716737D03*
Y1702564D03*
Y1707666D03*
Y1712203D03*
X544684Y1712800D03*
Y1708266D03*
Y1703729D03*
X536810Y1721840D03*
Y1726377D03*
Y1730911D03*
X544684Y1726974D03*
Y1722440D03*
Y1717903D03*
X545531Y876435D03*
X552932D03*
X556633D03*
X551082Y879624D03*
X545543Y872085D03*
X554783Y879624D03*
Y886002D03*
X549231Y882813D03*
X558483Y892380D03*
X545531Y889191D03*
Y895569D03*
X552932Y889191D03*
X551082Y892380D03*
X552932Y895569D03*
X558483Y886002D03*
X545531Y882813D03*
X551082Y886002D03*
X556633Y889191D03*
X554783Y892380D03*
X556633Y895569D03*
X547381Y886002D03*
X549231Y889191D03*
Y895569D03*
X547381Y892380D03*
X556633Y882813D03*
X552932D03*
X558483Y898758D03*
X545531Y901947D03*
X552932D03*
X551082Y898758D03*
X558483Y905135D03*
Y911513D03*
X551082Y905135D03*
Y911513D03*
X552932Y908325D03*
X545531Y908324D03*
X554783Y911513D03*
X556633Y901947D03*
X554783Y905135D03*
X556633Y908325D03*
X554783Y898758D03*
X549231Y908325D03*
X547381Y898758D03*
X549231Y901947D03*
X547381Y905135D03*
Y911513D03*
X558483Y917891D03*
X551082D03*
X552932Y914702D03*
X545531D03*
X558483Y924269D03*
X551082D03*
X552932Y921080D03*
X545531D03*
X556633D03*
X554783Y924269D03*
X556633Y914702D03*
X554783Y917891D03*
X547381D03*
X549231Y921080D03*
X547381Y924269D03*
X549231Y914702D03*
X558483Y930647D03*
X545531Y927458D03*
Y933836D03*
X552932Y927458D03*
Y933836D03*
X551082Y930647D03*
X558483Y937025D03*
X545531Y940214D03*
X551082Y937025D03*
X552932Y940214D03*
X556633Y927458D03*
X554783Y930647D03*
X556633Y940214D03*
Y933836D03*
X554783Y937025D03*
X549231Y927458D03*
X547381Y937025D03*
X549231Y940214D03*
Y933836D03*
X547381Y930647D03*
X558483Y943403D03*
Y949781D03*
X545531Y946592D03*
X551082Y943403D03*
Y949781D03*
X552932Y946592D03*
X558483Y956159D03*
X545531Y952970D03*
X552932D03*
X551082Y956159D03*
X554783Y943403D03*
X556633Y946592D03*
X554783Y949781D03*
X556633Y952970D03*
X554783Y956159D03*
X547381Y943403D03*
X549231Y946592D03*
X547381Y956159D03*
X549231Y952970D03*
X547381Y949781D03*
X558483Y962537D03*
X545531Y959348D03*
Y965726D03*
X552932Y959348D03*
X551082Y962537D03*
X552932Y965726D03*
X558483Y968915D03*
X551082D03*
X556633Y965726D03*
X554783Y968915D03*
X556633Y959348D03*
X554783Y962537D03*
X547381D03*
X549231Y965726D03*
Y959348D03*
X547381Y968915D03*
X558483Y975293D03*
Y981671D03*
X545531Y972104D03*
Y978482D03*
X547381Y981671D03*
X551082Y975293D03*
X552932Y972104D03*
X551082Y981671D03*
X552932Y978482D03*
Y984860D03*
X549231D03*
X545531D03*
X556633D03*
Y978482D03*
X554783Y981671D03*
X556633Y972104D03*
X554783Y975293D03*
X547381D03*
X549231Y978482D03*
Y972104D03*
X558483Y988049D03*
Y994427D03*
X552932Y991238D03*
X551082Y994427D03*
X552932Y997616D03*
X545531Y991238D03*
Y997616D03*
X551082Y988049D03*
X558483Y1000805D03*
X551082D03*
X554783Y988049D03*
X556633Y997616D03*
X554783Y1000805D03*
X556633Y991238D03*
X547381Y994427D03*
X549231Y997616D03*
X547381Y1000805D03*
Y988049D03*
X554782Y994427D03*
X549231Y991238D03*
X558483Y1007183D03*
X545531Y1010372D03*
Y1003994D03*
X552932Y1010372D03*
X551082Y1007183D03*
X552932Y1003994D03*
X556633D03*
X554783Y1007183D03*
X549231Y1010372D03*
X547381Y1007183D03*
X549231Y1003994D03*
X556633Y1010372D03*
X554113Y1028056D03*
X546712D03*
X557814D03*
X550412D03*
X546712Y1040812D03*
Y1034434D03*
X552263Y1031245D03*
X554113Y1040812D03*
X552263Y1037623D03*
X554113Y1034434D03*
X552263Y1044001D03*
X559664Y1031245D03*
Y1037623D03*
Y1044001D03*
X555964Y1031245D03*
X557814Y1034434D03*
X555964Y1037623D03*
X557814Y1040812D03*
X555964Y1044001D03*
X544861Y1031245D03*
X550412Y1034434D03*
X548562Y1037623D03*
X544861D03*
X550412Y1040812D03*
X544861Y1044001D03*
X548562D03*
Y1031245D03*
X546712Y1047190D03*
X554113D03*
X544861Y1056757D03*
X546712Y1053568D03*
Y1059946D03*
X552263Y1056757D03*
X555964D03*
X554113Y1053568D03*
X552263Y1050379D03*
X554113Y1059946D03*
X557814D03*
X559664Y1050379D03*
Y1056757D03*
X555964Y1050379D03*
X557814Y1047190D03*
X544861Y1050379D03*
X550412Y1059946D03*
X548562Y1050379D03*
X550412Y1053568D03*
X557814D03*
X548562Y1056757D03*
X550412Y1047190D03*
X552263Y1063135D03*
X546712Y1072702D03*
Y1066324D03*
X552263Y1069513D03*
X554113Y1066324D03*
Y1072702D03*
X559664Y1063135D03*
Y1069513D03*
X555964Y1063135D03*
X557814Y1066324D03*
X555964Y1069513D03*
X557814Y1072702D03*
X550412D03*
X544861Y1063135D03*
X548562D03*
X544861Y1069513D03*
X548562D03*
X550412Y1066324D03*
X552263Y1075891D03*
X546712Y1079080D03*
X554113D03*
X546712Y1085458D03*
X552263Y1088647D03*
X554113Y1085458D03*
X552263Y1082269D03*
X559664Y1075891D03*
Y1088647D03*
Y1082269D03*
X555964Y1075891D03*
X557814Y1079080D03*
X555964Y1082269D03*
X557814Y1085458D03*
X555964Y1088647D03*
X544861Y1075891D03*
X548562D03*
X550412Y1079080D03*
X544861Y1082269D03*
X548562D03*
Y1088647D03*
X544861D03*
X550412Y1085458D03*
X546712Y1091836D03*
X554113D03*
X552263Y1095025D03*
Y1101403D03*
X554113Y1098214D03*
X546712Y1104592D03*
Y1098214D03*
X554113Y1104592D03*
X559664Y1095025D03*
Y1101403D03*
X557814Y1104592D03*
X555964Y1095025D03*
X557814Y1098214D03*
X555964Y1101403D03*
X557814Y1091836D03*
X548562Y1101403D03*
X550412Y1091836D03*
X544861Y1095025D03*
X548562D03*
X550412Y1098214D03*
X544861Y1101403D03*
X550412Y1104592D03*
X552263Y1107781D03*
X554113Y1110970D03*
X546712D03*
X554113Y1117348D03*
X552263Y1114159D03*
X546712Y1117348D03*
X559664Y1107781D03*
Y1114159D03*
X555964D03*
X557814Y1117348D03*
X555964Y1107781D03*
X557814Y1110970D03*
X550412D03*
X544861Y1114159D03*
X548562D03*
X550412Y1117348D03*
X548562Y1107781D03*
X544861D03*
X546712Y1123726D03*
X554113D03*
X552263Y1120537D03*
Y1126915D03*
Y1133293D03*
X554113Y1130103D03*
X559664Y1120537D03*
Y1126915D03*
Y1133293D03*
X546712Y1130104D03*
X555964Y1120537D03*
X557814Y1123726D03*
X555964Y1133293D03*
Y1126915D03*
X557814Y1130103D03*
X544861Y1120537D03*
X548562D03*
X550412Y1130103D03*
X544861Y1133293D03*
X548562D03*
Y1126915D03*
X544861D03*
X550412Y1123726D03*
X552263Y1139670D03*
X554113Y1136481D03*
X546712D03*
X554113Y1142859D03*
X546712D03*
Y1149237D03*
X552263Y1146048D03*
X554113Y1149237D03*
X559664Y1139670D03*
Y1146048D03*
X557814Y1136481D03*
X555964Y1139670D03*
X557814Y1142859D03*
X555964Y1146048D03*
X557814Y1149237D03*
X550412Y1136481D03*
X544861Y1139670D03*
X548562D03*
X550412Y1149237D03*
X548562Y1146048D03*
X544861D03*
X550412Y1142859D03*
X546712Y1161993D03*
X555964Y1165182D03*
X554113Y1155615D03*
X552263Y1152426D03*
X555964Y1158804D03*
X552263D03*
X548562D03*
X546712Y1155615D03*
X554113Y1161993D03*
X559664Y1152426D03*
Y1158804D03*
X555964Y1152426D03*
X557814Y1155615D03*
X544861Y1152426D03*
X548562D03*
X550412Y1155615D03*
X557814Y1161993D03*
X544861Y1158804D03*
X558679Y1592380D03*
X546619D03*
X554419D03*
X548379Y1602380D03*
X552659D03*
X558679Y1624292D03*
X548379Y1614292D03*
X546619Y1624292D03*
X554419D03*
X552659Y1614292D03*
X552558Y1679320D03*
Y1683857D03*
Y1688391D03*
Y1693493D03*
Y1698030D03*
Y1716737D03*
Y1702564D03*
Y1707666D03*
Y1712203D03*
Y1721840D03*
Y1726377D03*
Y1730911D03*
X562184Y879624D03*
X569586Y873246D03*
X562184D03*
X565885Y879624D03*
X564034Y876435D03*
X573286Y879624D03*
X571436Y876435D03*
X569586Y879624D03*
X560334Y882813D03*
X564034D03*
X569586Y886002D03*
X571436Y882813D03*
Y889191D03*
X564034D03*
X565885Y892380D03*
X571436Y895569D03*
X562184Y886002D03*
X560334Y889191D03*
Y895569D03*
X562184Y892380D03*
X564034Y895569D03*
X565885Y886002D03*
X567735Y882813D03*
X564034Y901947D03*
X571436D03*
X565885Y898758D03*
X564034Y908325D03*
X571436D03*
X565885Y911513D03*
X560334Y908325D03*
X562184Y898758D03*
X560334Y901947D03*
X562184Y905135D03*
Y911513D03*
X565885Y905135D03*
Y917891D03*
X571436Y914702D03*
X564034Y921080D03*
X571436D03*
X562184Y917891D03*
X560334Y921080D03*
X562184Y924269D03*
X560334Y914702D03*
X565885Y924269D03*
X564034Y914702D03*
Y927458D03*
X571436D03*
X565885Y930647D03*
X571436Y933836D03*
X565885Y937025D03*
X564034Y940214D03*
X571436D03*
X560334Y927458D03*
X562184Y937025D03*
X560334Y940214D03*
Y933836D03*
X562184Y930647D03*
X564034Y933836D03*
X565885Y949781D03*
X564034Y946592D03*
X571436D03*
Y952970D03*
X565885Y956159D03*
X562184Y943403D03*
X560334Y946592D03*
X562184Y956159D03*
X560334Y952970D03*
X562184Y949781D03*
X564034Y952970D03*
X565885Y943403D03*
X564034Y959348D03*
X571436D03*
X564034Y965726D03*
X571436D03*
X565885Y968915D03*
X562184Y962537D03*
X560334Y965726D03*
Y959348D03*
X562184Y968915D03*
X565885Y962537D03*
X562184Y981671D03*
X565885Y975293D03*
X571436Y972104D03*
X564034Y978482D03*
X571436D03*
X567735Y984860D03*
X560334D03*
X564034D03*
X571436D03*
X562184Y975293D03*
X560334Y978482D03*
Y972104D03*
X565885Y981671D03*
X564034Y972104D03*
X569586Y988049D03*
X571436Y991238D03*
X565885Y994427D03*
X564034Y997616D03*
X571436D03*
X565885Y988049D03*
X562184Y994427D03*
X560334Y997616D03*
X562184Y1000805D03*
Y988049D03*
X565885Y1000805D03*
X564034Y991238D03*
X560334D03*
X571436Y1010372D03*
X565885Y1007183D03*
X564034Y1003994D03*
X571436D03*
X560334Y1010372D03*
X562184Y1007183D03*
X560334Y1003994D03*
X564034Y1010372D03*
X567735D03*
X565216Y1028056D03*
X572617D03*
X568916D03*
X561515D03*
X567066Y1031245D03*
X565215Y1034434D03*
Y1040812D03*
X572617Y1034434D03*
Y1040812D03*
X567066Y1044001D03*
X561515Y1034434D03*
X563365Y1037623D03*
X561515Y1040812D03*
X567066Y1037623D03*
X563365Y1044001D03*
Y1031245D03*
X565215Y1059946D03*
X572617Y1047190D03*
X567066Y1050379D03*
X572617Y1053568D03*
X570767Y1056757D03*
X565215Y1053568D03*
X572617Y1059946D03*
X568916D03*
X561515D03*
X563365Y1050379D03*
X561515Y1053568D03*
X567066Y1056757D03*
X565215Y1047190D03*
X563365Y1056757D03*
X561515Y1047190D03*
X567066Y1063135D03*
X572617Y1066324D03*
Y1072702D03*
X567066Y1069513D03*
X565215Y1072702D03*
X561515D03*
X563365Y1063135D03*
Y1069513D03*
X561515Y1066324D03*
X565215D03*
Y1079080D03*
X572617D03*
X567066Y1088647D03*
X572617Y1085458D03*
X567066Y1082269D03*
X563365Y1075891D03*
X561515Y1079080D03*
X563365Y1082269D03*
Y1088647D03*
X561515Y1085458D03*
X565215D03*
X567066Y1075891D03*
X572617Y1091836D03*
X565215D03*
X572617Y1104592D03*
Y1098214D03*
X567066Y1101403D03*
X565215Y1098214D03*
X563365Y1101403D03*
X561515Y1091836D03*
X563365Y1095025D03*
X561515Y1098214D03*
Y1104592D03*
X565215D03*
X567066Y1095025D03*
Y1107781D03*
X572617Y1110970D03*
X565215D03*
X572617Y1117348D03*
X565215D03*
X561515Y1110970D03*
X563365Y1114159D03*
X561515Y1117348D03*
X563365Y1107781D03*
X567066Y1114159D03*
X572617Y1123726D03*
X567066Y1120537D03*
Y1126915D03*
X572617Y1130103D03*
X565215D03*
X563365Y1120537D03*
X561515Y1130103D03*
X563365Y1133293D03*
Y1126915D03*
X561515Y1123726D03*
X567066Y1133293D03*
X565215Y1123726D03*
X572617Y1136481D03*
X565215Y1149237D03*
X572617D03*
X567066Y1146048D03*
X572617Y1142859D03*
X567066Y1139670D03*
X565215Y1136481D03*
X561515D03*
X563365Y1139670D03*
X561515Y1149237D03*
X563365Y1146048D03*
X561515Y1142859D03*
X565215D03*
X567066Y1158804D03*
X574467D03*
X565215Y1155615D03*
X568916D03*
X572617D03*
X561515D03*
X565215Y1161993D03*
X563365Y1152426D03*
Y1158804D03*
X567066Y1152426D03*
X572617Y1161993D03*
X570767Y1165182D03*
X567066D03*
X568916Y1161993D03*
X570815Y1507509D03*
X573066Y1507460D03*
X570980Y1513218D03*
X569722Y1521612D03*
X569321Y1518121D03*
X569814Y1523810D03*
Y1528725D03*
X569768Y1535698D03*
Y1537898D03*
X571215Y1540317D03*
X570739Y1592380D03*
X566479D03*
X572499Y1602380D03*
X560439D03*
X564719D03*
X572499Y1614292D03*
X570739Y1624292D03*
X560439Y1614292D03*
X566479Y1624292D03*
X564719Y1614292D03*
X572243Y1683857D03*
X564369Y1684454D03*
Y1679920D03*
Y1675383D03*
X572243Y1679320D03*
X564369Y1694093D03*
Y1689556D03*
X572243Y1688391D03*
Y1693493D03*
Y1698030D03*
X564369Y1698627D03*
X572243Y1702564D03*
Y1707666D03*
Y1712203D03*
X564369Y1712800D03*
Y1708266D03*
Y1703729D03*
X572243Y1716737D03*
Y1726377D03*
Y1730911D03*
X564369Y1726974D03*
Y1722440D03*
Y1717903D03*
X572243Y1721840D03*
X576987Y879624D03*
X575137Y882813D03*
X576987Y886002D03*
Y892380D03*
Y898758D03*
X577728Y906182D03*
Y912560D03*
Y918938D03*
Y925316D03*
Y931694D03*
Y938072D03*
Y944450D03*
Y950828D03*
Y957206D03*
Y963584D03*
Y969962D03*
Y976340D03*
Y982718D03*
Y989096D03*
Y995474D03*
Y1008230D03*
Y1001852D03*
X578909Y1030198D03*
Y1036576D03*
Y1042954D03*
Y1049332D03*
Y1055710D03*
Y1062088D03*
Y1074844D03*
Y1068466D03*
Y1087600D03*
Y1081222D03*
Y1093978D03*
Y1100356D03*
Y1106734D03*
Y1113112D03*
Y1119490D03*
Y1125868D03*
Y1132246D03*
Y1138623D03*
Y1145001D03*
Y1151379D03*
X578168Y1158804D03*
X575182Y1507514D03*
X580489Y1507295D03*
X585214D03*
X588214Y1521453D03*
X583489D03*
X578765D03*
X579095Y1514243D03*
X583819D03*
X588544D03*
X577923Y1519195D03*
X580390Y1516970D03*
X585114D03*
X581965Y1519698D03*
X586689D03*
X588765Y1528853D03*
X584040D03*
X579316D03*
X588264Y1536063D03*
X583539D03*
X578814D03*
X580390Y1530608D03*
X585114D03*
X581965Y1533336D03*
X586689D03*
X588765Y1526353D03*
X588214Y1523953D03*
X578765D03*
X583489D03*
X579316Y1526353D03*
X584040D03*
X585214Y1542641D03*
X580489D03*
X575286Y1542425D03*
Y1544625D03*
X578539Y1592380D03*
X582799D03*
X584559Y1602380D03*
X588839D03*
X576779D03*
X584559Y1614292D03*
X582799Y1624292D03*
X578539D03*
X588839Y1614292D03*
X576779D03*
X587991Y1679320D03*
Y1683857D03*
X580117Y1684454D03*
Y1679920D03*
Y1675383D03*
X587991Y1688391D03*
Y1693493D03*
Y1698030D03*
X580117Y1698627D03*
Y1694093D03*
Y1689556D03*
X587991Y1716737D03*
Y1702564D03*
Y1707666D03*
Y1712203D03*
X580117Y1712800D03*
Y1708266D03*
Y1703729D03*
X587991Y1721840D03*
Y1726377D03*
Y1730911D03*
X580117Y1726974D03*
Y1722440D03*
Y1717903D03*
X589938Y1507295D03*
X594662D03*
X599387D03*
X604111D03*
X602387Y1521453D03*
X597662D03*
X592938D03*
X593268Y1514243D03*
X597993D03*
X602717D03*
X589839Y1516970D03*
X594563D03*
X599287D03*
X604012D03*
X591413Y1519698D03*
X596138D03*
X600862D03*
X602437Y1536063D03*
X597713D03*
X602938Y1528853D03*
X598213D03*
X593489D03*
X592988Y1536063D03*
X589839Y1530608D03*
X594563D03*
X599287D03*
X604012D03*
X591413Y1533336D03*
X596138D03*
X600862D03*
X602387Y1523953D03*
X602938Y1526353D03*
X592938Y1523953D03*
X593489Y1526353D03*
X598213D03*
X597662Y1523953D03*
X589938Y1542641D03*
X604111D03*
X599387D03*
X594662D03*
X602659Y1592380D03*
X590599D03*
X594859D03*
X596619Y1602380D03*
X600899D03*
X602659Y1624292D03*
X596619Y1614292D03*
X594859Y1624292D03*
X590599D03*
X600899Y1614292D03*
X603739Y1679320D03*
Y1683857D03*
X595865Y1684454D03*
Y1679920D03*
Y1675383D03*
X603739Y1688391D03*
Y1693493D03*
Y1698030D03*
X595865Y1698627D03*
Y1694093D03*
Y1689556D03*
X603739Y1716737D03*
Y1702564D03*
Y1707666D03*
Y1712203D03*
X595865Y1712800D03*
Y1708266D03*
Y1703729D03*
X603739Y1721840D03*
Y1726377D03*
Y1730911D03*
X595865Y1726974D03*
Y1722440D03*
Y1717903D03*
X608836Y1507295D03*
X613560D03*
X618284D03*
X616560Y1521453D03*
X611836D03*
X607111D03*
X607441Y1514243D03*
X612166D03*
X616890D03*
X608736Y1516970D03*
X613461D03*
X618185D03*
X605587Y1519698D03*
X610311D03*
X615035D03*
X611886Y1536063D03*
X617111Y1528853D03*
X612387D03*
X607662D03*
X607161Y1536063D03*
X616610D03*
X608736Y1530608D03*
X613461D03*
X618185D03*
X605587Y1533336D03*
X610311D03*
X615035D03*
X616560Y1523953D03*
X617111Y1526353D03*
X607111Y1523953D03*
X607662Y1526353D03*
X612387D03*
X611836Y1523953D03*
X613560Y1542641D03*
X618284D03*
X608836D03*
X618979Y1592380D03*
X614719D03*
X606919D03*
X608679Y1602380D03*
X612959D03*
X618979Y1624292D03*
X608679Y1614292D03*
X606919Y1624292D03*
X614719D03*
X612959Y1614292D03*
X611613Y1684454D03*
Y1679920D03*
Y1675383D03*
Y1698627D03*
Y1694093D03*
Y1689556D03*
Y1712800D03*
Y1708266D03*
Y1703729D03*
Y1726974D03*
Y1722440D03*
Y1717903D03*
X623009Y1507295D03*
X627733D03*
X632458D03*
X630733Y1521453D03*
X626009D03*
X621284D03*
X621615Y1514243D03*
X626339D03*
X631063D03*
X627634Y1516970D03*
X632358D03*
X622909D03*
X629209Y1519698D03*
X633933D03*
X619760D03*
X624484D03*
X626059Y1536063D03*
X621335D03*
X631284Y1528853D03*
X626560D03*
X621835D03*
X630783Y1536063D03*
X627634Y1530608D03*
X632358D03*
X622909D03*
X629209Y1533336D03*
X633933D03*
X619760D03*
X624484D03*
X626009Y1523953D03*
X626560Y1526353D03*
X631284D03*
X630733Y1523953D03*
X621835Y1526353D03*
X621284Y1523953D03*
X632458Y1542641D03*
X627733D03*
X623009D03*
X631039Y1592380D03*
X626779D03*
X632799Y1602286D03*
X620739Y1602380D03*
X625019D03*
X631039Y1624292D03*
X632799Y1614292D03*
X626779Y1624292D03*
X620739Y1614292D03*
X625019D03*
X619487Y1679320D03*
Y1683857D03*
Y1688391D03*
Y1693493D03*
Y1698030D03*
Y1716737D03*
Y1702564D03*
Y1707666D03*
Y1712203D03*
Y1721840D03*
Y1726377D03*
Y1730911D03*
X637182Y1507295D03*
X641906D03*
X646631D03*
X645237Y1514243D03*
X644907Y1521453D03*
X640182D03*
X635458D03*
X635788Y1514243D03*
X640512D03*
X637083Y1516970D03*
X641807D03*
X646532D03*
X638657Y1519698D03*
X643382D03*
X648106D03*
X644957Y1536063D03*
X635508D03*
X645458Y1528853D03*
X640733D03*
X636009D03*
X640232Y1536063D03*
X637083Y1530608D03*
X641807D03*
X646532D03*
X638657Y1533336D03*
X643382D03*
X648106D03*
X644907Y1523953D03*
X640733Y1526353D03*
X640182Y1523953D03*
X635458D03*
X636009Y1526353D03*
X645458D03*
X646631Y1542641D03*
X641906D03*
X637182D03*
X638839Y1592380D03*
X644869Y1602380D03*
X637079D03*
X644869Y1614292D03*
X638839Y1624292D03*
X637079Y1614292D03*
X651355Y1507295D03*
X657656Y1507355D03*
X655556D03*
X654376Y1521453D03*
X649631D03*
X649961Y1514243D03*
X651256Y1516970D03*
X652831Y1519698D03*
X659063Y1514073D03*
X659007Y1516336D03*
X650182Y1528853D03*
X649681Y1536063D03*
X655012D03*
X651256Y1530608D03*
X652831Y1533336D03*
X650182Y1526353D03*
X649631Y1523953D03*
X659358Y1536640D03*
Y1534540D03*
X659359Y1531618D03*
X659270Y1528698D03*
X662353Y1534413D03*
X660877Y1530158D03*
X651355Y1542641D03*
X658773Y1538658D03*
X1184959Y1551121D03*
X1185452Y1556810D03*
Y1561725D03*
X1185360Y1554612D03*
X1185406Y1568698D03*
Y1570898D03*
X1190820Y1540512D03*
X1194733Y1547243D03*
X1196127Y1540295D03*
X1199457Y1547243D03*
X1193561Y1552195D03*
X1196028Y1549970D03*
X1197603Y1552698D03*
X1188653Y1540509D03*
X1186453D03*
X1186618Y1546218D03*
X1199127Y1554453D03*
X1194403D03*
X1199678Y1561853D03*
X1194954D03*
X1196028Y1563608D03*
X1197603Y1566336D03*
X1194403Y1556953D03*
X1199678Y1559353D03*
X1194954D03*
X1199127Y1556953D03*
X1199177Y1569063D03*
X1196127Y1575641D03*
X1194452Y1569063D03*
X1190924Y1575425D03*
X1186853Y1573317D03*
X1190924Y1577625D03*
X1193839Y1625380D03*
X1199879Y1635380D03*
Y1647292D03*
X1193839Y1657292D03*
X1200852Y1540295D03*
X1204182Y1547243D03*
X1205576Y1540295D03*
X1208906Y1547243D03*
X1210300Y1540295D03*
X1213631Y1547243D03*
X1215025Y1540295D03*
X1200752Y1549970D03*
X1205477D03*
X1210201D03*
X1214925D03*
X1202327Y1552698D03*
X1207051D03*
X1211776D03*
X1213300Y1554453D03*
X1208576D03*
X1203852D03*
X1213851Y1561853D03*
X1209127D03*
X1204403D03*
X1200752Y1563608D03*
X1205477D03*
X1210201D03*
X1214925D03*
X1202327Y1566336D03*
X1207051D03*
X1211776D03*
X1208576Y1556953D03*
X1204403Y1559353D03*
X1209127D03*
X1203852Y1556953D03*
X1213300D03*
X1213851Y1559353D03*
X1213351Y1569063D03*
X1210300Y1575641D03*
X1208626Y1569063D03*
X1203902D03*
X1200852Y1575641D03*
X1205576D03*
X1215025D03*
X1205899Y1625380D03*
X1201639D03*
X1213699D03*
X1207659Y1635380D03*
X1211939D03*
X1207659Y1647292D03*
X1211939D03*
X1201639Y1657292D03*
X1205899D03*
X1213699D03*
X1218355Y1547243D03*
X1219749Y1540295D03*
X1223079Y1547243D03*
X1227804D03*
X1229198Y1540295D03*
X1224474D03*
X1219650Y1549970D03*
X1224374D03*
X1229099D03*
X1216500Y1552698D03*
X1221225D03*
X1225949D03*
X1227474Y1554453D03*
X1222749D03*
X1218025D03*
X1228025Y1561853D03*
X1223300D03*
X1218576D03*
X1219650Y1563608D03*
X1224374D03*
X1229099D03*
X1216500Y1566336D03*
X1221225D03*
X1225949D03*
X1218025Y1556953D03*
X1218576Y1559353D03*
X1227474Y1556953D03*
X1228025Y1559353D03*
X1222749Y1556953D03*
X1223300Y1559353D03*
X1227524Y1569063D03*
X1218075D03*
X1222799D03*
X1219749Y1575641D03*
X1224474D03*
X1229198D03*
X1217959Y1625380D03*
X1225759D03*
X1230019D03*
X1223999Y1635380D03*
X1219719D03*
X1223999Y1647292D03*
X1219719D03*
X1217959Y1657292D03*
X1230019D03*
X1225759D03*
X1232528Y1547243D03*
X1233922Y1540295D03*
X1237253Y1547243D03*
X1241977D03*
X1243371Y1540295D03*
X1238647D03*
X1243272Y1549970D03*
X1233823D03*
X1238547D03*
X1244847Y1552698D03*
X1230673D03*
X1235398D03*
X1240122D03*
X1241647Y1554453D03*
X1236922D03*
X1232198D03*
X1242198Y1561853D03*
X1237473D03*
X1232749D03*
X1243272Y1563608D03*
X1233823D03*
X1238547D03*
X1244847Y1566336D03*
X1230673D03*
X1235398D03*
X1240122D03*
X1241647Y1556953D03*
X1242198Y1559353D03*
X1232198Y1556953D03*
X1232749Y1559353D03*
X1236922Y1556953D03*
X1237473Y1559353D03*
X1241697Y1569063D03*
X1236973D03*
X1238647Y1575641D03*
X1232248Y1569063D03*
X1233922Y1575641D03*
X1243371D03*
X1237819Y1625380D03*
X1242079D03*
X1231779Y1635380D03*
X1236059D03*
X1243839D03*
X1236059Y1647292D03*
X1231779D03*
X1243839D03*
X1237819Y1657292D03*
X1242079D03*
X1241140Y1684454D03*
Y1679920D03*
Y1675383D03*
Y1698627D03*
Y1694093D03*
Y1689556D03*
Y1712800D03*
Y1708266D03*
Y1703729D03*
Y1726974D03*
Y1722440D03*
Y1717903D03*
X1246701Y1547243D03*
X1248096Y1540295D03*
X1251426Y1547243D03*
X1252820Y1540295D03*
X1256150Y1547243D03*
X1257544Y1540295D03*
X1247996Y1549970D03*
X1252721D03*
X1257445D03*
X1249571Y1552698D03*
X1254295D03*
X1259020D03*
X1255820Y1554453D03*
X1251096D03*
X1246371D03*
X1256371Y1561853D03*
X1251647D03*
X1246922D03*
X1247996Y1563608D03*
X1252721D03*
X1257445D03*
X1249571Y1566336D03*
X1254295D03*
X1259020D03*
X1251647Y1559353D03*
X1251096Y1556953D03*
X1255820D03*
X1256371Y1559353D03*
X1246371Y1556953D03*
X1246922Y1559353D03*
X1251146Y1569063D03*
X1257544Y1575641D03*
X1255870Y1569063D03*
X1246421D03*
X1248096Y1575641D03*
X1252820D03*
X1249879Y1625380D03*
X1254139D03*
X1248119Y1635380D03*
X1255899D03*
X1260179D03*
X1248119Y1647292D03*
X1255899D03*
X1260179D03*
X1254139Y1657292D03*
X1249879D03*
X1249014Y1679320D03*
Y1683857D03*
X1256888Y1684454D03*
Y1679920D03*
Y1675383D03*
X1249014Y1688391D03*
Y1693493D03*
Y1698030D03*
X1256888Y1698627D03*
Y1694093D03*
Y1689556D03*
Y1703729D03*
X1249014Y1716737D03*
Y1702564D03*
Y1707666D03*
Y1712203D03*
X1256888Y1712800D03*
Y1708266D03*
X1249014Y1721840D03*
Y1726377D03*
Y1730911D03*
X1256888Y1726974D03*
Y1722440D03*
Y1717903D03*
X1260875Y1547243D03*
X1262269Y1540295D03*
X1265599Y1547243D03*
X1266993Y1540295D03*
X1262170Y1549970D03*
X1266894D03*
X1263744Y1552698D03*
X1268469D03*
X1273294Y1540355D03*
X1271194D03*
X1274701Y1547073D03*
X1274645Y1549336D03*
X1270014Y1554453D03*
X1265269D03*
X1260545D03*
X1265820Y1561853D03*
X1261096D03*
X1262170Y1563608D03*
X1266894D03*
X1263744Y1566336D03*
X1268469D03*
X1265269Y1556953D03*
X1265820Y1559353D03*
X1261096D03*
X1260545Y1556953D03*
X1274996Y1567540D03*
X1274997Y1564618D03*
X1274908Y1561698D03*
X1260595Y1569063D03*
X1270650D03*
X1266993Y1575641D03*
X1265319Y1569063D03*
X1262269Y1575641D03*
X1274411Y1571658D03*
X1274996Y1569640D03*
X1266199Y1625380D03*
X1261939D03*
X1273999D03*
X1267959Y1635380D03*
X1272239D03*
X1267959Y1647292D03*
X1272239D03*
X1266199Y1657292D03*
X1261939D03*
X1273999D03*
X1264762Y1679320D03*
Y1683857D03*
X1272636Y1684454D03*
Y1679920D03*
Y1675383D03*
X1264762Y1688391D03*
Y1693493D03*
Y1698030D03*
X1272636Y1698627D03*
Y1694093D03*
Y1689556D03*
X1264762Y1716737D03*
Y1702564D03*
Y1707666D03*
Y1712203D03*
X1272636Y1712800D03*
Y1708266D03*
Y1703729D03*
X1264762Y1721840D03*
Y1726377D03*
Y1730911D03*
X1272636Y1726974D03*
Y1722440D03*
Y1717903D03*
X1286697Y873245D03*
Y879623D03*
X1279296D03*
X1288549Y876434D03*
X1284847Y895568D03*
Y882812D03*
X1286697Y886001D03*
X1281146Y882812D03*
X1279296Y886001D03*
X1284847Y889190D03*
X1279296Y892379D03*
X1284847Y901946D03*
X1279296Y898757D03*
X1284847Y908324D03*
X1278555Y906181D03*
Y912559D03*
X1284847Y914701D03*
X1278555Y918937D03*
X1284847Y921079D03*
X1278555Y925315D03*
X1284847Y927457D03*
Y933835D03*
X1278555Y931693D03*
Y938071D03*
X1284847Y940213D03*
Y946591D03*
X1278555Y950827D03*
X1284847Y952969D03*
X1278555Y944449D03*
X1284847Y959347D03*
X1278555Y957205D03*
X1284847Y965725D03*
X1278555Y963583D03*
Y969961D03*
X1284847Y972103D03*
X1278555Y976339D03*
X1284847Y978481D03*
X1278555Y982717D03*
X1284847Y984859D03*
X1288548D03*
X1278555Y995473D03*
X1284847Y991237D03*
X1286697Y988048D03*
X1278555Y989095D03*
X1284847Y997615D03*
Y1010371D03*
Y1003993D03*
X1278555Y1008229D03*
Y1001851D03*
X1288548Y1010371D03*
X1279736Y1030197D03*
X1286028Y1028055D03*
X1289729D03*
X1286028Y1034433D03*
Y1040811D03*
X1279736Y1042953D03*
Y1036575D03*
X1286028Y1047189D03*
Y1053567D03*
X1287878Y1056756D03*
X1289729Y1059945D03*
X1286028D03*
X1279736Y1055709D03*
Y1049331D03*
Y1062087D03*
Y1068465D03*
Y1074843D03*
X1286028Y1066323D03*
Y1072701D03*
Y1079079D03*
X1279736Y1081221D03*
Y1087599D03*
X1286028Y1085457D03*
X1279736Y1093977D03*
X1286028Y1091835D03*
X1279736Y1100355D03*
X1286028Y1098213D03*
Y1104591D03*
X1279736Y1106733D03*
X1286028Y1110969D03*
X1279736Y1113111D03*
Y1119489D03*
X1286028Y1117347D03*
X1279736Y1125867D03*
X1286028Y1123725D03*
Y1130102D03*
X1279736Y1132245D03*
Y1138622D03*
X1286028Y1136480D03*
Y1142858D03*
X1279736Y1145000D03*
X1286028Y1149236D03*
X1279736Y1151378D03*
Y1157756D03*
X1289729Y1155614D03*
X1286028D03*
X1284178Y1158803D03*
X1287878Y1165181D03*
X1278259Y1625380D03*
X1286059D03*
X1280019Y1635380D03*
X1284299D03*
X1280019Y1647292D03*
X1284299D03*
X1278259Y1657292D03*
X1286059D03*
X1280510Y1679320D03*
Y1683857D03*
X1288384Y1684454D03*
Y1679920D03*
Y1675383D03*
X1280510Y1688391D03*
Y1693493D03*
Y1698030D03*
X1288384Y1698627D03*
Y1694093D03*
Y1689556D03*
X1280510Y1716737D03*
Y1702564D03*
Y1707666D03*
Y1712203D03*
X1288384Y1712800D03*
Y1708266D03*
Y1703729D03*
X1280510Y1721840D03*
Y1726377D03*
Y1730911D03*
X1288384Y1726974D03*
Y1722440D03*
Y1717903D03*
X1297800Y879623D03*
X1299650Y876434D03*
X1290398Y873245D03*
X1301500Y879623D03*
X1303351Y876434D03*
X1294099Y879623D03*
X1295949Y876434D03*
X1290399Y879623D03*
X1303351Y882812D03*
Y895568D03*
X1290398Y886001D03*
Y892379D03*
X1292249Y882812D03*
X1297800Y886001D03*
X1301500D03*
X1295949Y882812D03*
X1292249Y889190D03*
X1303351D03*
X1297800Y892379D03*
X1294099Y886001D03*
X1299650Y889190D03*
X1295949D03*
X1301500Y892379D03*
X1295949Y895568D03*
X1299650D03*
X1294099Y892379D03*
X1292249Y895568D03*
X1299650Y882812D03*
X1290398Y898757D03*
Y911512D03*
X1292249Y901946D03*
X1297800Y898757D03*
X1303351Y901946D03*
X1292249Y908324D03*
X1297800Y905134D03*
Y911512D03*
X1303351Y908324D03*
X1295949D03*
X1301500Y911512D03*
X1294099Y898757D03*
X1299650Y901946D03*
X1295949D03*
X1301500Y905134D03*
X1294099D03*
X1299650Y908324D03*
X1294099Y911512D03*
X1301500Y898757D03*
X1290398Y905134D03*
Y917890D03*
X1297800D03*
X1303351Y914701D03*
Y921079D03*
X1297800Y924268D03*
X1292249Y921079D03*
X1294099Y917890D03*
X1299650Y921079D03*
X1295949D03*
X1301500Y924268D03*
X1294099D03*
X1295949Y914701D03*
X1299650D03*
X1301500Y917890D03*
X1292249Y914701D03*
X1290398Y924268D03*
X1297800Y930646D03*
X1303351Y927457D03*
Y933835D03*
X1292249Y927457D03*
X1303351Y940213D03*
X1297800Y937024D03*
X1292249Y940213D03*
X1290398Y930646D03*
Y937024D03*
X1299650Y927457D03*
X1295949D03*
X1301500Y930646D03*
X1294099Y937024D03*
X1299650Y940213D03*
X1295949D03*
Y933835D03*
X1299650D03*
X1294099Y930646D03*
X1301500Y937024D03*
X1292249Y933835D03*
X1290398Y949780D03*
Y956158D03*
X1297800Y949780D03*
X1303351Y946591D03*
X1292249D03*
X1297800Y943402D03*
X1303351Y952969D03*
X1297800Y956158D03*
X1301500Y943402D03*
X1294099D03*
X1299650Y946591D03*
X1295949D03*
X1301500Y949780D03*
X1294099Y956158D03*
X1295949Y952969D03*
X1299650D03*
X1294099Y949780D03*
X1301500Y956158D03*
X1292249Y952969D03*
X1290398Y943402D03*
Y968914D03*
X1297800Y962536D03*
X1303351Y959347D03*
Y965725D03*
X1292249Y959347D03*
Y965725D03*
X1297800Y968914D03*
X1294099Y962536D03*
X1299650Y965725D03*
X1295949D03*
X1301500Y968914D03*
X1299650Y959347D03*
X1295949D03*
X1301500Y962536D03*
X1294099Y968914D03*
X1290398Y962536D03*
Y975292D03*
X1297800Y981670D03*
Y975292D03*
X1303351Y972103D03*
Y978481D03*
X1294099Y981670D03*
X1292249Y978481D03*
X1303351Y984859D03*
X1295949D03*
X1292249D03*
X1299650D03*
X1294099Y975292D03*
X1299650Y978481D03*
X1295949D03*
X1301500Y981670D03*
X1295949Y972103D03*
X1299650D03*
X1301500Y975292D03*
X1292249Y972103D03*
X1290398Y981670D03*
Y988048D03*
Y994426D03*
X1297800D03*
Y988048D03*
X1303351Y991237D03*
Y997615D03*
X1292249D03*
X1297800Y1000804D03*
X1301500Y988048D03*
X1294099Y994426D03*
X1295949Y997615D03*
X1299650D03*
X1301500Y1000804D03*
X1294099D03*
X1295949Y991237D03*
X1301500Y994426D03*
X1292249Y991237D03*
X1290398Y1000804D03*
X1299650Y991237D03*
X1294099Y988048D03*
X1290398Y1007182D03*
X1292249Y1010371D03*
X1297800Y1007182D03*
X1303351Y1010371D03*
Y1003993D03*
X1292249D03*
X1295949Y1010371D03*
X1294099Y1007182D03*
X1295949Y1003993D03*
X1299650D03*
X1301500Y1007182D03*
X1299650Y1010371D03*
X1304532Y1028055D03*
X1293430D03*
X1300831D03*
X1297130D03*
X1293430Y1034433D03*
Y1040811D03*
X1298981Y1044000D03*
Y1037622D03*
X1304532Y1034433D03*
Y1040811D03*
X1298981Y1031244D03*
X1291579D03*
Y1044000D03*
X1302681Y1031244D03*
X1300831Y1034433D03*
X1297130D03*
X1295280Y1037622D03*
X1302681D03*
X1300831Y1040811D03*
X1297130D03*
X1295280Y1044000D03*
X1291579Y1037622D03*
X1302682Y1044000D03*
X1295280Y1031244D03*
X1304532Y1047189D03*
X1291579Y1050378D03*
X1293430Y1053567D03*
Y1059945D03*
X1304532Y1053567D03*
X1298981Y1050378D03*
X1302681Y1056756D03*
X1298981D03*
X1300831Y1059945D03*
X1304532D03*
X1302681Y1050378D03*
X1297130Y1059945D03*
X1300831Y1047189D03*
X1295280Y1050378D03*
X1297130Y1053567D03*
X1291579Y1056756D03*
X1293430Y1047189D03*
X1295280Y1056756D03*
X1297130Y1047189D03*
X1300831Y1053567D03*
X1298981Y1063134D03*
X1291579D03*
Y1069512D03*
X1293430Y1072701D03*
X1304532D03*
Y1066323D03*
X1298981Y1069512D03*
X1297130Y1072701D03*
X1302681Y1063134D03*
X1295280D03*
X1300831Y1066323D03*
X1302681Y1069512D03*
X1295280D03*
X1300831Y1072701D03*
X1297130Y1066323D03*
X1293430D03*
X1298981Y1075890D03*
X1293430Y1079079D03*
X1304532D03*
Y1085457D03*
X1298981Y1088646D03*
X1291579Y1082268D03*
X1298981D03*
X1291579Y1088646D03*
X1302681Y1075890D03*
X1295280D03*
X1300831Y1079079D03*
X1297130D03*
X1302681Y1082268D03*
X1295280D03*
X1300831Y1085457D03*
X1295280Y1088646D03*
X1302681D03*
X1297130Y1085457D03*
X1293430D03*
X1291579Y1075890D03*
X1293430Y1091835D03*
X1304532D03*
X1298981Y1095024D03*
X1293430Y1098213D03*
X1298981Y1101402D03*
X1304532Y1098213D03*
Y1104591D03*
X1291579Y1101402D03*
X1295280D03*
X1300831Y1104591D03*
X1297130Y1091835D03*
X1302681Y1095024D03*
X1295280D03*
X1300831Y1098213D03*
X1297130D03*
X1302681Y1101402D03*
X1297130Y1104591D03*
X1300831Y1091835D03*
X1293430Y1104591D03*
X1291579Y1095024D03*
X1298981Y1107780D03*
X1291579D03*
X1293430Y1110969D03*
X1304532D03*
X1293430Y1117347D03*
X1298981Y1114158D03*
X1304532Y1117347D03*
X1297130Y1110969D03*
X1302681Y1114158D03*
X1295280D03*
X1300831Y1117347D03*
X1297130D03*
X1295280Y1107780D03*
X1302681D03*
X1300831Y1110969D03*
X1291579Y1114158D03*
Y1120536D03*
X1298981D03*
X1304532Y1123725D03*
X1291579Y1126914D03*
X1298981D03*
X1304532Y1130102D03*
X1298981Y1133292D03*
X1293430Y1130102D03*
X1302681Y1120536D03*
X1295280D03*
X1300831Y1123725D03*
X1297130Y1130102D03*
X1302681Y1133292D03*
X1295280D03*
Y1126914D03*
X1302681D03*
X1297130Y1123725D03*
X1300831Y1130102D03*
X1291579Y1133292D03*
X1293430Y1123725D03*
X1304532Y1136480D03*
X1298981Y1139669D03*
X1291579D03*
X1293430Y1136480D03*
X1304532Y1142858D03*
X1291579Y1146047D03*
X1293430Y1149236D03*
X1298981Y1146047D03*
X1304532Y1149236D03*
X1300831Y1136480D03*
X1297130D03*
X1302681Y1139669D03*
X1295280D03*
X1300831Y1142858D03*
X1297130Y1149236D03*
X1295280Y1146047D03*
X1302681D03*
X1297130Y1142858D03*
X1300831Y1149236D03*
X1293430Y1142858D03*
X1291579Y1158803D03*
X1293430Y1155614D03*
X1304532D03*
X1298981Y1152425D03*
X1297130Y1155614D03*
X1302681Y1158803D03*
X1298981D03*
X1304532Y1161992D03*
X1297130D03*
X1302681Y1152425D03*
X1295280D03*
X1300831Y1155614D03*
X1295280Y1158803D03*
X1291579Y1152425D03*
X1300831Y1161992D03*
X1302682Y1165181D03*
X1298119Y1625380D03*
X1290319D03*
X1302379D03*
X1292079Y1635380D03*
X1296359D03*
X1304139D03*
X1296359Y1647292D03*
X1292079D03*
X1304139D03*
X1298119Y1657292D03*
X1290319D03*
X1302379D03*
X1296258Y1679320D03*
Y1683857D03*
Y1688391D03*
Y1693493D03*
Y1698030D03*
Y1716737D03*
Y1702564D03*
Y1707666D03*
Y1712203D03*
Y1721840D03*
Y1726377D03*
Y1730911D03*
X1318154Y876434D03*
X1305201Y879623D03*
X1312603D03*
X1316304D03*
X1314453Y876434D03*
X1308902Y873245D03*
Y879623D03*
X1307052Y876434D03*
X1310752Y895568D03*
X1307052Y882812D03*
X1305201Y886001D03*
Y892379D03*
X1310752Y882812D03*
X1312603Y886001D03*
X1316304D03*
X1318154Y882812D03*
X1310752Y889190D03*
X1318154D03*
X1316304Y892379D03*
X1308902Y886001D03*
X1314453Y889190D03*
X1307052D03*
X1312603Y892379D03*
X1307052Y895568D03*
X1314453D03*
X1308902Y892379D03*
X1318154Y895568D03*
X1305201Y898757D03*
Y905134D03*
Y911512D03*
X1310752Y901946D03*
X1318154D03*
X1316304Y898757D03*
Y911512D03*
X1318154Y908324D03*
X1310752Y908323D03*
X1307052Y908324D03*
X1312603Y911512D03*
X1308902Y898757D03*
X1314453Y901946D03*
X1307052D03*
X1312603Y905134D03*
X1308902D03*
X1314453Y908324D03*
X1308902Y911512D03*
X1312603Y898757D03*
X1316304Y905134D03*
X1305201Y917890D03*
Y924268D03*
X1310752Y914701D03*
X1316304Y917890D03*
X1318154Y921079D03*
X1310752D03*
X1308902Y917890D03*
X1314453Y921079D03*
X1307052D03*
X1312603Y924268D03*
X1308902D03*
X1307052Y914701D03*
X1314453D03*
X1312603Y917890D03*
X1316304Y924268D03*
X1318154Y914701D03*
X1305201Y930646D03*
Y937024D03*
X1310752Y927457D03*
Y933835D03*
X1318154Y927457D03*
X1316304Y930646D03*
Y937024D03*
X1310752Y940213D03*
X1318154D03*
X1314453Y927457D03*
X1307052D03*
X1312603Y930646D03*
X1308902Y937024D03*
X1314453Y940213D03*
X1307052D03*
Y933835D03*
X1314453D03*
X1308902Y930646D03*
X1312603Y937024D03*
X1318154Y933835D03*
X1305201Y943402D03*
Y949780D03*
Y956158D03*
X1310752Y946591D03*
X1316304Y949780D03*
X1318154Y946591D03*
X1310752Y952969D03*
X1316304Y956158D03*
X1312603Y943402D03*
X1308902D03*
X1314453Y946591D03*
X1307052D03*
X1312603Y949780D03*
X1308902Y956158D03*
X1307052Y952969D03*
X1314453D03*
X1308902Y949780D03*
X1312603Y956158D03*
X1318154Y952969D03*
X1316304Y943402D03*
X1318154Y959347D03*
Y965725D03*
X1316304Y968914D03*
X1305201Y962536D03*
Y968914D03*
X1310752Y959347D03*
Y965725D03*
X1308902Y962536D03*
X1314453Y965725D03*
X1307052D03*
X1312603Y968914D03*
X1314453Y959347D03*
X1307052D03*
X1312603Y962536D03*
X1308902Y968914D03*
X1316304Y962536D03*
X1305201Y975292D03*
Y981670D03*
X1307052Y984859D03*
X1310752Y972103D03*
Y978481D03*
X1316304Y975292D03*
X1318154Y978481D03*
X1308902Y981670D03*
X1310752Y984859D03*
X1318154D03*
X1314453D03*
X1308902Y975292D03*
X1314453Y978481D03*
X1307052D03*
X1312603Y981670D03*
X1307052Y972103D03*
X1314453D03*
X1312603Y975292D03*
X1316304Y981670D03*
X1318154Y972103D03*
X1305201Y988048D03*
Y994426D03*
Y1000804D03*
X1310752Y991237D03*
Y997615D03*
X1316304Y988048D03*
X1318154Y997615D03*
X1316304Y994426D03*
X1312603Y988048D03*
X1308902Y994426D03*
X1307052Y997615D03*
X1314453D03*
X1312603Y1000804D03*
X1308902D03*
X1307052Y991237D03*
X1312603Y994426D03*
X1316304Y1000804D03*
X1318154Y991237D03*
X1314453D03*
X1308902Y988048D03*
X1305201Y1007182D03*
X1310752Y1003993D03*
Y1010371D03*
X1318154D03*
X1316304Y1007182D03*
X1318154Y1003993D03*
X1307052Y1010371D03*
X1308902Y1007182D03*
X1307052Y1003993D03*
X1314453D03*
X1312603Y1007182D03*
X1314453Y1010371D03*
X1311933Y1028055D03*
X1319335D03*
X1315634D03*
X1308233D03*
X1306382Y1044000D03*
Y1037622D03*
Y1031244D03*
X1319335Y1034433D03*
X1311933Y1040811D03*
X1319335D03*
X1317485Y1031244D03*
Y1044000D03*
X1311933Y1034433D03*
X1313784Y1031244D03*
X1315634Y1034433D03*
X1308233D03*
X1310083Y1037622D03*
X1313784D03*
X1315634Y1040811D03*
X1308233D03*
X1310083Y1044000D03*
X1317485Y1037622D03*
X1313784Y1044000D03*
X1310083Y1031244D03*
X1306382Y1050378D03*
Y1056756D03*
X1311933Y1047189D03*
X1313784Y1056756D03*
X1311933Y1059945D03*
X1315634D03*
X1319335D03*
X1317485Y1050378D03*
X1319335Y1053567D03*
X1311933D03*
X1313784Y1050378D03*
X1308233Y1059945D03*
X1315634Y1047189D03*
X1310083Y1050378D03*
X1308233Y1053567D03*
X1317485Y1056756D03*
X1319335Y1047189D03*
X1310083Y1056756D03*
X1308233Y1047189D03*
X1315634Y1053567D03*
X1306382Y1063134D03*
Y1069512D03*
X1317485Y1063134D03*
X1319335Y1072701D03*
X1317485Y1069512D03*
X1311933Y1066323D03*
Y1072701D03*
X1308233D03*
X1313784Y1063134D03*
X1310083D03*
X1315634Y1066323D03*
X1313784Y1069512D03*
X1310083D03*
X1315634Y1072701D03*
X1308233Y1066323D03*
X1319335D03*
X1306382Y1075890D03*
Y1088646D03*
Y1082268D03*
X1319335Y1079079D03*
X1311933D03*
Y1085457D03*
X1317485Y1088646D03*
Y1082268D03*
X1313784Y1075890D03*
X1310083D03*
X1315634Y1079079D03*
X1308233D03*
X1313784Y1082268D03*
X1310083D03*
X1315634Y1085457D03*
X1310083Y1088646D03*
X1313784D03*
X1308233Y1085457D03*
X1319335D03*
X1317485Y1075890D03*
X1306382Y1095024D03*
Y1101402D03*
X1319335Y1091835D03*
X1311933D03*
Y1098213D03*
X1319335D03*
X1317485Y1101402D03*
X1311933Y1104591D03*
X1310083Y1101402D03*
X1315634Y1104591D03*
X1308233Y1091835D03*
X1313784Y1095024D03*
X1310083D03*
X1315634Y1098213D03*
X1308233D03*
X1313784Y1101402D03*
X1308233Y1104591D03*
X1315634Y1091835D03*
X1319335Y1104591D03*
X1317485Y1095024D03*
X1306382Y1107780D03*
Y1114158D03*
X1317485Y1107780D03*
X1319335Y1110969D03*
X1311933D03*
Y1117347D03*
X1319335D03*
X1308233Y1110969D03*
X1313784Y1114158D03*
X1310083D03*
X1315634Y1117347D03*
X1308233D03*
X1310083Y1107780D03*
X1313784D03*
X1315634Y1110969D03*
X1317485Y1114158D03*
X1306382Y1120536D03*
Y1126914D03*
Y1133292D03*
X1317485Y1120536D03*
X1311933Y1123725D03*
X1317485Y1126914D03*
X1319335Y1130102D03*
X1311933Y1130103D03*
X1313784Y1120536D03*
X1310083D03*
X1315634Y1123725D03*
X1308233Y1130102D03*
X1313784Y1133292D03*
X1310083D03*
Y1126914D03*
X1313784D03*
X1308233Y1123725D03*
X1315634Y1130102D03*
X1317485Y1133292D03*
X1319335Y1123725D03*
X1306382Y1139669D03*
Y1146047D03*
X1319335Y1136480D03*
X1317485Y1139669D03*
X1311933Y1136480D03*
Y1142858D03*
X1317485Y1146047D03*
X1319335Y1149236D03*
X1311933D03*
X1315634Y1136480D03*
X1308233D03*
X1313784Y1139669D03*
X1310083D03*
X1315634Y1142858D03*
X1308233Y1149236D03*
X1310083Y1146047D03*
X1313784D03*
X1308233Y1142858D03*
X1315634Y1149236D03*
X1319335Y1142858D03*
X1317485Y1158803D03*
X1313784D03*
X1319335Y1161992D03*
X1311933D03*
X1306382Y1165181D03*
X1313784D03*
X1306382Y1152425D03*
Y1158803D03*
X1319335Y1155614D03*
X1315634D03*
X1311933D03*
X1310083Y1158803D03*
X1313784Y1152425D03*
X1310083D03*
X1308233Y1155614D03*
X1317485Y1152425D03*
X1308233Y1161992D03*
X1310083Y1165181D03*
X1317485D03*
X1315634Y1161992D03*
X1318882Y1540514D03*
X1316766Y1540460D03*
X1314515Y1540509D03*
X1314680Y1546218D03*
X1313021Y1551121D03*
X1313514Y1556810D03*
Y1561725D03*
X1313422Y1554612D03*
X1318986Y1575425D03*
X1313468Y1568698D03*
Y1570898D03*
X1318986Y1577625D03*
X1314915Y1573317D03*
X1310179Y1625380D03*
X1314439D03*
X1308419Y1635380D03*
X1316199D03*
X1308419Y1647292D03*
X1316199D03*
X1310179Y1657292D03*
X1314439D03*
X1315943Y1679320D03*
Y1683857D03*
X1308069Y1684454D03*
Y1679920D03*
Y1675383D03*
X1315943Y1688391D03*
Y1693493D03*
Y1698030D03*
X1308069Y1698627D03*
Y1694093D03*
Y1689556D03*
X1315943Y1716737D03*
Y1702564D03*
Y1707666D03*
Y1712203D03*
X1308069Y1712800D03*
Y1708266D03*
Y1703729D03*
X1315943Y1721840D03*
Y1726377D03*
Y1730911D03*
X1308069Y1726974D03*
Y1722440D03*
Y1717903D03*
X1323705Y879623D03*
X1327406D03*
X1321855Y876434D03*
X1320004Y879623D03*
X1331107Y873245D03*
X1325556Y876434D03*
X1331107Y879623D03*
X1332957Y876434D03*
X1329256D03*
X1334807Y879623D03*
X1321855Y882812D03*
X1323705Y886001D03*
X1329256Y882812D03*
X1332957D03*
X1331107Y886001D03*
X1327406D03*
X1323705Y892379D03*
X1329256Y889190D03*
X1331107Y892379D03*
X1329256Y895568D03*
X1320004Y886001D03*
X1325556Y889190D03*
X1321855D03*
X1327406Y892379D03*
X1321855Y895568D03*
X1325556D03*
X1320004Y892379D03*
X1334807Y886001D03*
X1332957Y889190D03*
Y895568D03*
X1334807Y892379D03*
X1323705Y898757D03*
X1331107D03*
X1329256Y901946D03*
X1331107Y911512D03*
X1323705D03*
Y905134D03*
X1331107D03*
X1329256Y908323D03*
X1321855Y908324D03*
X1327406Y911512D03*
X1320004Y898757D03*
X1325556Y901946D03*
X1321855D03*
X1327406Y905134D03*
X1320004D03*
X1325556Y908324D03*
X1320004Y911512D03*
X1327406Y898757D03*
X1332957Y908324D03*
X1334807Y898757D03*
X1332957Y901946D03*
X1334807Y905134D03*
Y911512D03*
X1329256Y914701D03*
X1323705Y917890D03*
X1331107D03*
X1323705Y924268D03*
X1329256Y921079D03*
X1331107Y924268D03*
X1320004Y917890D03*
X1325556Y921079D03*
X1321855D03*
X1327406Y924268D03*
X1320004D03*
X1321855Y914701D03*
X1325556D03*
X1327406Y917890D03*
X1334807D03*
X1332957Y921079D03*
X1334807Y924268D03*
X1332957Y914701D03*
X1331107Y930646D03*
X1329256Y933835D03*
X1323705Y930646D03*
X1329256Y927457D03*
X1331107Y937024D03*
X1329256Y940213D03*
X1323705Y937024D03*
X1325556Y927457D03*
X1321855D03*
X1327406Y930646D03*
X1320004Y937024D03*
X1325556Y940213D03*
X1321855D03*
Y933835D03*
X1325556D03*
X1320004Y930646D03*
X1327406Y937024D03*
X1332957Y927457D03*
X1334807Y937024D03*
X1332957Y940213D03*
Y933835D03*
X1334807Y930646D03*
X1331107Y943402D03*
X1329256Y946591D03*
X1331107Y949780D03*
X1323705Y943402D03*
Y949780D03*
X1329256Y952969D03*
X1331107Y956158D03*
X1323705D03*
X1327406Y943402D03*
X1320004D03*
X1325556Y946591D03*
X1321855D03*
X1327406Y949780D03*
X1320004Y956158D03*
X1321855Y952969D03*
X1325556D03*
X1320004Y949780D03*
X1327406Y956158D03*
X1334807Y943402D03*
X1332957Y946591D03*
X1334807Y956158D03*
X1332957Y952969D03*
X1334807Y949780D03*
X1329256Y959347D03*
X1331107Y962536D03*
X1329256Y965725D03*
X1323705Y962536D03*
X1331107Y968914D03*
X1323705D03*
X1320004Y962536D03*
X1325556Y965725D03*
X1321855D03*
X1327406Y968914D03*
X1325556Y959347D03*
X1321855D03*
X1327406Y962536D03*
X1320004Y968914D03*
X1334807Y962536D03*
X1332957Y965725D03*
Y959347D03*
X1334807Y968914D03*
X1320004Y981670D03*
X1321855Y984859D03*
X1323705Y975292D03*
Y981670D03*
X1329256Y972103D03*
X1331107Y975292D03*
X1329256Y978481D03*
X1331107Y981670D03*
X1334807D03*
X1329256Y984859D03*
X1332957D03*
X1325556D03*
X1320004Y975292D03*
X1325556Y978481D03*
X1321855D03*
X1327406Y981670D03*
X1321855Y972103D03*
X1325556D03*
X1327406Y975292D03*
X1334807D03*
X1332957Y978481D03*
Y972103D03*
X1323705Y1000804D03*
Y988048D03*
Y994426D03*
X1329256Y997615D03*
X1331107Y988048D03*
X1329256Y991237D03*
X1331107Y994426D03*
Y1000804D03*
X1327406Y988048D03*
X1320004Y994426D03*
X1321855Y997615D03*
X1325556D03*
X1327406Y1000804D03*
X1320004D03*
X1321855Y991237D03*
X1327406Y994426D03*
X1334807D03*
X1332957Y997615D03*
X1334807Y1000804D03*
X1332957Y991237D03*
X1334808Y988048D03*
X1325556Y991237D03*
X1320004Y988048D03*
X1323705Y1007182D03*
X1329256Y1003993D03*
X1331107Y1007182D03*
X1329256Y1010371D03*
X1321855D03*
X1320004Y1007182D03*
X1321855Y1003993D03*
X1325556D03*
X1327406Y1007182D03*
X1332957Y1010371D03*
X1334807Y1007182D03*
X1332957Y1003993D03*
X1325556Y1010371D03*
X1330437Y1028055D03*
X1326737D03*
X1334138D03*
X1323036D03*
X1324886Y1031244D03*
X1332288D03*
X1324886Y1044000D03*
Y1037622D03*
X1332288Y1044000D03*
X1330437Y1034433D03*
X1332288Y1037622D03*
X1330437Y1040811D03*
X1328587Y1031244D03*
X1326737Y1034433D03*
X1323036D03*
X1321185Y1037622D03*
X1328587D03*
X1326737Y1040811D03*
X1323036D03*
X1321185Y1044000D03*
X1334138Y1034433D03*
Y1040811D03*
X1328587Y1044000D03*
X1321185Y1031244D03*
X1330437Y1047189D03*
X1324886Y1050378D03*
Y1056756D03*
X1332288Y1050378D03*
X1330437Y1053567D03*
X1328587Y1056756D03*
X1332288D03*
X1326737Y1059945D03*
X1330437D03*
X1328587Y1050378D03*
X1323036Y1059945D03*
X1326737Y1047189D03*
X1321185Y1050378D03*
X1323036Y1053567D03*
X1334138Y1059945D03*
Y1053567D03*
Y1047189D03*
X1321185Y1056756D03*
X1323036Y1047189D03*
X1326737Y1053567D03*
X1332288Y1063134D03*
X1324886D03*
Y1069512D03*
X1330437Y1066323D03*
X1332288Y1069512D03*
X1330437Y1072701D03*
X1323036D03*
X1328587Y1063134D03*
X1321185D03*
X1326737Y1066323D03*
X1328587Y1069512D03*
X1321185D03*
X1326737Y1072701D03*
X1323036Y1066323D03*
X1334138Y1072701D03*
Y1066323D03*
X1324886Y1075890D03*
X1332288D03*
X1330437Y1079079D03*
X1324886Y1088646D03*
X1330437Y1085457D03*
X1332288Y1088646D03*
X1324886Y1082268D03*
X1332288D03*
X1328587Y1075890D03*
X1321185D03*
X1326737Y1079079D03*
X1323036D03*
X1328587Y1082268D03*
X1321185D03*
X1326737Y1085457D03*
X1321185Y1088646D03*
X1328587D03*
X1323036Y1085457D03*
X1334138Y1079079D03*
Y1085457D03*
X1330437Y1091835D03*
X1324886Y1095024D03*
X1332288D03*
X1324886Y1101402D03*
X1330437Y1098213D03*
X1332288Y1101402D03*
X1330437Y1104591D03*
X1321185Y1101402D03*
X1326737Y1104591D03*
X1323036Y1091835D03*
X1328587Y1095024D03*
X1321185D03*
X1326737Y1098213D03*
X1323036D03*
X1328587Y1101402D03*
X1323036Y1104591D03*
X1326737Y1091835D03*
X1334138D03*
Y1098213D03*
Y1104591D03*
X1324886Y1107780D03*
X1332288D03*
X1330437Y1110969D03*
X1324886Y1114158D03*
X1332288D03*
X1330437Y1117347D03*
X1323036Y1110969D03*
X1328587Y1114158D03*
X1321185D03*
X1326737Y1117347D03*
X1323036D03*
X1321185Y1107780D03*
X1328587D03*
X1326737Y1110969D03*
X1334138D03*
Y1117347D03*
X1324886Y1120536D03*
X1332288D03*
X1330437Y1123725D03*
X1324886Y1126914D03*
X1332288D03*
X1324886Y1133292D03*
X1332288D03*
X1330439Y1130102D03*
X1328587Y1120536D03*
X1321185D03*
X1326737Y1123725D03*
X1323036Y1130102D03*
X1328587Y1133292D03*
X1321185D03*
Y1126914D03*
X1328587D03*
X1323036Y1123725D03*
X1326737Y1130102D03*
X1334138D03*
Y1123725D03*
X1324886Y1139669D03*
X1330437Y1136480D03*
X1332288Y1139669D03*
X1330437Y1142858D03*
X1332288Y1146047D03*
X1330437Y1149236D03*
X1324886Y1146047D03*
X1326737Y1136480D03*
X1323036D03*
X1328587Y1139669D03*
X1321185D03*
X1326737Y1142858D03*
X1323036Y1149236D03*
X1321185Y1146047D03*
X1328587D03*
X1323036Y1142858D03*
X1326737Y1149236D03*
X1334138Y1136480D03*
Y1149236D03*
Y1142858D03*
X1332288Y1165181D03*
X1323036Y1155614D03*
Y1161992D03*
X1332288Y1152425D03*
X1330437Y1155614D03*
X1324886Y1152425D03*
X1332288Y1158803D03*
X1328587D03*
X1324886D03*
X1330437Y1161992D03*
X1324886Y1165181D03*
X1328587Y1152425D03*
X1321185D03*
X1326737Y1155614D03*
X1334138D03*
X1321185Y1158803D03*
X1334138Y1161992D03*
X1322795Y1547243D03*
X1324189Y1540295D03*
X1327519Y1547243D03*
X1328914Y1540295D03*
X1332244Y1547243D03*
X1333638Y1540295D03*
X1321623Y1552195D03*
X1324090Y1549970D03*
X1328814D03*
X1333539D03*
X1325665Y1552698D03*
X1330389D03*
X1331914Y1554453D03*
X1327189D03*
X1322465D03*
X1332465Y1561853D03*
X1327740D03*
X1323016D03*
X1324090Y1563608D03*
X1328814D03*
X1333539D03*
X1325665Y1566336D03*
X1330389D03*
X1332465Y1559353D03*
X1331914Y1556953D03*
X1322465D03*
X1327189D03*
X1323016Y1559353D03*
X1327740D03*
X1333638Y1575641D03*
X1331964Y1569063D03*
X1328914Y1575641D03*
X1327239Y1569063D03*
X1324189Y1575641D03*
X1322514Y1569063D03*
X1326499Y1625380D03*
X1322239D03*
X1334299D03*
X1320479Y1635380D03*
X1328259D03*
X1332539D03*
X1328259Y1647292D03*
X1320479D03*
X1332539D03*
X1322239Y1657292D03*
X1326499D03*
X1334299D03*
X1331691Y1679320D03*
Y1683857D03*
X1323817Y1684454D03*
Y1679920D03*
Y1675383D03*
X1331691Y1688391D03*
Y1693493D03*
Y1698030D03*
X1323817Y1698627D03*
Y1694093D03*
Y1689556D03*
X1331691Y1716737D03*
Y1702564D03*
Y1707666D03*
Y1712203D03*
X1323817Y1712800D03*
Y1708266D03*
Y1703729D03*
X1331691Y1721840D03*
Y1726377D03*
Y1730911D03*
X1323817Y1726974D03*
Y1722440D03*
Y1717903D03*
X1336658Y876434D03*
X1345910Y879623D03*
X1349611D03*
X1344059Y876434D03*
X1347760D03*
X1340359D03*
X1338508Y886001D03*
X1336658Y882812D03*
Y889190D03*
Y895568D03*
X1342209Y886001D03*
X1349611D03*
X1344059Y882812D03*
Y889190D03*
X1342209Y892379D03*
X1349611D03*
X1345910Y886001D03*
X1347760Y889190D03*
Y895568D03*
X1345910Y892379D03*
X1340359Y889190D03*
X1338508Y892379D03*
X1340359Y895568D03*
X1347760Y882812D03*
X1344059Y895568D03*
X1336658Y901946D03*
Y908324D03*
X1342209Y898757D03*
X1349611D03*
X1344059Y901946D03*
X1349611Y905134D03*
X1342209Y911512D03*
X1349611D03*
X1344059Y908323D03*
X1347760Y908324D03*
X1345910Y898757D03*
X1347760Y901946D03*
X1345910Y905134D03*
Y911512D03*
X1338508D03*
X1340359Y901946D03*
X1338508Y905134D03*
X1340359Y908324D03*
X1338508Y898757D03*
X1342209Y905134D03*
X1336658Y914701D03*
Y921079D03*
X1342209Y917890D03*
X1349611D03*
X1344059Y921079D03*
X1349611Y924268D03*
X1345910Y917890D03*
X1347760Y921079D03*
X1345910Y924268D03*
X1347760Y914701D03*
X1340359Y921079D03*
X1338508Y924268D03*
X1340359Y914701D03*
X1338508Y917890D03*
X1344059Y914701D03*
X1342209Y924268D03*
X1336658Y933835D03*
Y927457D03*
Y940213D03*
X1344059Y927457D03*
X1342209Y930646D03*
X1349611D03*
X1344059Y940213D03*
X1342209Y937024D03*
X1349611D03*
X1347760Y927457D03*
X1345910Y937024D03*
X1347760Y940213D03*
Y933835D03*
X1345910Y930646D03*
X1340359Y927457D03*
X1338508Y930646D03*
X1340359Y940213D03*
Y933835D03*
X1338508Y937024D03*
X1344059Y933835D03*
X1349611Y943402D03*
X1344059Y946591D03*
X1349611Y949780D03*
X1342209D03*
X1349611Y956158D03*
X1342209D03*
X1336658Y946591D03*
Y952969D03*
X1345910Y943402D03*
X1347760Y946591D03*
X1345910Y956158D03*
X1347760Y952969D03*
X1345910Y949780D03*
X1338508Y943402D03*
X1340359Y946591D03*
X1338508Y949780D03*
X1340359Y952969D03*
X1338508Y956158D03*
X1342209Y943402D03*
X1344059Y952969D03*
X1336658Y965725D03*
Y959347D03*
X1344059D03*
X1349611Y962536D03*
X1344059Y965725D03*
X1349611Y968914D03*
X1342209D03*
X1345910Y962536D03*
X1347760Y965725D03*
Y959347D03*
X1345910Y968914D03*
X1340359Y965725D03*
X1338508Y968914D03*
X1340359Y959347D03*
X1338508Y962536D03*
X1342209D03*
X1336658Y972103D03*
Y978481D03*
Y984859D03*
X1349611Y975292D03*
X1342209D03*
X1344059Y978481D03*
X1349611Y981670D03*
X1345910D03*
X1344059Y984859D03*
X1347760D03*
X1345910Y975292D03*
X1347760Y978481D03*
Y972103D03*
X1340359Y984859D03*
Y978481D03*
X1338508Y981670D03*
X1340359Y972103D03*
X1338508Y975292D03*
X1342209Y981670D03*
X1344059Y972103D03*
X1336658Y997615D03*
Y991237D03*
X1349611Y988048D03*
Y994426D03*
X1342209D03*
X1344059Y997615D03*
X1342209Y988048D03*
X1349611Y1000804D03*
X1345910Y994426D03*
X1347760Y997615D03*
X1345910Y1000804D03*
X1347760Y991237D03*
X1338508Y988048D03*
X1340359Y997615D03*
X1338508Y1000804D03*
Y994426D03*
X1344059Y991237D03*
X1342209Y1000804D03*
X1340359Y991237D03*
X1345910Y988048D03*
X1336658Y1010371D03*
X1344059D03*
X1336658Y1003993D03*
X1344059D03*
X1342209Y1007182D03*
X1349611D03*
X1347760Y1010371D03*
X1345910Y1007182D03*
X1347760Y1003993D03*
X1340359D03*
X1338508Y1007182D03*
X1340359Y1010371D03*
X1337839Y1028055D03*
X1345241D03*
X1341540D03*
X1348941D03*
X1337839Y1040811D03*
Y1034433D03*
X1343390Y1031244D03*
Y1044000D03*
X1345241Y1040811D03*
Y1034433D03*
X1348941D03*
X1347091Y1037622D03*
X1348941Y1040811D03*
X1347091Y1044000D03*
X1339689Y1031244D03*
X1341540Y1034433D03*
X1335989Y1037622D03*
X1339689D03*
X1341540Y1040811D03*
X1335989Y1044000D03*
X1343390Y1037622D03*
X1339689Y1044000D03*
X1335989Y1031244D03*
X1347091D03*
X1337839Y1047189D03*
Y1053567D03*
Y1059945D03*
X1339689Y1056756D03*
X1343390Y1050378D03*
X1345241Y1053567D03*
X1341540Y1059945D03*
X1345241D03*
X1348941D03*
X1347091Y1050378D03*
X1348941Y1053567D03*
X1339689Y1050378D03*
X1341540Y1047189D03*
X1335989Y1050378D03*
X1345241Y1047189D03*
X1343390Y1056756D03*
X1335989D03*
X1341540Y1053567D03*
X1347091Y1056756D03*
X1348941Y1047189D03*
X1337839Y1072701D03*
Y1066323D03*
X1343390Y1063134D03*
Y1069512D03*
X1345241Y1072701D03*
X1348941D03*
X1347091Y1063134D03*
Y1069512D03*
X1348941Y1066323D03*
X1339689Y1063134D03*
X1335989D03*
X1341540Y1066323D03*
X1339689Y1069512D03*
X1335989D03*
X1341540Y1072701D03*
X1345241Y1066323D03*
X1337839Y1079079D03*
Y1085457D03*
X1345241Y1079079D03*
X1343390Y1088646D03*
Y1082268D03*
X1347091Y1075890D03*
X1348941Y1079079D03*
X1347091Y1082268D03*
Y1088646D03*
X1348941Y1085457D03*
X1339689Y1075890D03*
X1335989D03*
X1341540Y1079079D03*
X1339689Y1082268D03*
X1335989D03*
X1341540Y1085457D03*
X1335989Y1088646D03*
X1339689D03*
X1343390Y1075890D03*
X1345241Y1085457D03*
X1337839Y1091835D03*
Y1098213D03*
Y1104591D03*
X1345241Y1091835D03*
X1343390Y1101402D03*
X1345241Y1098213D03*
X1347091Y1101402D03*
X1348941Y1091835D03*
X1347091Y1095024D03*
X1348941Y1098213D03*
Y1104591D03*
X1335989Y1101402D03*
X1341540Y1104591D03*
X1339689Y1095024D03*
X1335989D03*
X1341540Y1098213D03*
X1339689Y1101402D03*
X1341540Y1091835D03*
X1343390Y1095024D03*
X1345241Y1104591D03*
X1337839Y1110969D03*
Y1117347D03*
X1343390Y1107780D03*
X1345241Y1110969D03*
Y1117347D03*
X1348941Y1110969D03*
X1347091Y1114158D03*
X1348941Y1117347D03*
X1347091Y1107780D03*
X1339689Y1114158D03*
X1335989D03*
X1341540Y1117347D03*
X1335989Y1107780D03*
X1339689D03*
X1341540Y1110969D03*
X1343390Y1114158D03*
X1337839Y1123725D03*
Y1130102D03*
X1343390Y1120536D03*
Y1126914D03*
X1345241Y1130102D03*
X1347091Y1120536D03*
X1348941Y1130102D03*
X1347091Y1133292D03*
Y1126914D03*
X1348941Y1123725D03*
X1339689Y1120536D03*
X1335989D03*
X1341540Y1123725D03*
X1339689Y1133292D03*
X1335989D03*
Y1126914D03*
X1339689D03*
X1341540Y1130102D03*
X1343390Y1133292D03*
X1345241Y1123725D03*
X1337839Y1136480D03*
Y1142858D03*
Y1149236D03*
X1343390Y1139669D03*
X1345241Y1136480D03*
Y1149236D03*
X1343390Y1146047D03*
X1348941Y1136480D03*
X1347091Y1139669D03*
X1348941Y1149236D03*
X1347091Y1146047D03*
X1348941Y1142858D03*
X1341540Y1136480D03*
X1339689Y1139669D03*
X1335989D03*
X1341540Y1142858D03*
X1335989Y1146047D03*
X1339689D03*
X1341540Y1149236D03*
X1345241Y1142858D03*
X1337839Y1155614D03*
X1335989Y1158803D03*
X1337839Y1161992D03*
X1341540Y1155614D03*
X1339689Y1158803D03*
X1348941Y1155614D03*
X1345241D03*
X1339689Y1165181D03*
X1347091Y1152425D03*
X1339689D03*
X1335989D03*
X1347091Y1158803D03*
X1348941Y1161992D03*
X1345241D03*
X1343390Y1152425D03*
X1335989Y1165181D03*
X1343390Y1158803D03*
X1341540Y1161992D03*
X1336968Y1547243D03*
X1338362Y1540295D03*
X1341693Y1547243D03*
X1343087Y1540295D03*
X1346417Y1547243D03*
X1347811Y1540295D03*
X1338263Y1549970D03*
X1342987D03*
X1347712D03*
X1335113Y1552698D03*
X1339838D03*
X1344562D03*
X1349287D03*
X1346087Y1554453D03*
X1341362D03*
X1336638D03*
X1346638Y1561853D03*
X1341913D03*
X1337189D03*
X1338263Y1563608D03*
X1342987D03*
X1347712D03*
X1335113Y1566336D03*
X1339838D03*
X1344562D03*
X1349287D03*
X1346087Y1556953D03*
X1346638Y1559353D03*
X1336638Y1556953D03*
X1337189Y1559353D03*
X1341913D03*
X1341362Y1556953D03*
X1346137Y1569063D03*
X1341413D03*
X1347811Y1575641D03*
X1343087D03*
X1338362D03*
X1336688Y1569063D03*
X1338559Y1625380D03*
X1346359D03*
X1340319Y1635380D03*
X1344599D03*
X1340319Y1647292D03*
X1344599D03*
X1338559Y1657292D03*
X1346359D03*
X1347439Y1679320D03*
Y1683857D03*
X1339565Y1684454D03*
Y1679920D03*
Y1675383D03*
X1347439Y1688391D03*
Y1693493D03*
Y1698030D03*
X1339565Y1698627D03*
Y1694093D03*
Y1689556D03*
X1347439Y1716737D03*
Y1702564D03*
Y1707666D03*
Y1712203D03*
X1339565Y1712800D03*
Y1708266D03*
Y1703729D03*
X1347439Y1721840D03*
Y1726377D03*
Y1730911D03*
X1339565Y1726974D03*
Y1722440D03*
Y1717903D03*
X1351461Y876434D03*
X1353311Y879623D03*
X1364414D03*
X1360713Y873245D03*
X1362563Y876434D03*
X1358863D03*
X1355162D03*
X1364414Y892379D03*
X1360713D03*
X1353311Y886001D03*
X1362563Y882812D03*
X1358863D03*
X1364414Y886001D03*
X1360713D03*
X1355162Y882812D03*
X1357012Y892379D03*
X1355162Y895568D03*
X1362563Y889190D03*
X1358863D03*
X1351461D03*
X1353311Y892379D03*
X1351461Y895568D03*
Y882812D03*
X1357012Y886001D03*
X1362563Y895568D03*
X1358863D03*
X1355162Y889190D03*
X1364414Y905134D03*
Y898757D03*
Y911512D03*
X1360713Y905134D03*
Y898757D03*
Y911512D03*
X1357012Y898757D03*
X1362563Y901946D03*
X1358863D03*
X1357012Y905134D03*
Y911512D03*
X1355162Y908324D03*
X1353311Y911512D03*
X1351461Y901946D03*
X1353311Y905134D03*
X1351461Y908324D03*
X1353311Y898757D03*
X1362563Y908324D03*
X1358863D03*
X1355162Y901946D03*
X1364414Y917890D03*
Y924268D03*
X1360713Y917890D03*
Y924268D03*
X1358863Y914701D03*
X1362563D03*
X1357012Y917890D03*
X1355162Y921079D03*
X1357012Y924268D03*
X1351461Y921079D03*
X1353311Y924268D03*
X1351461Y914701D03*
X1353311Y917890D03*
X1358863Y921079D03*
X1362563D03*
X1355162Y914701D03*
X1364414Y930646D03*
X1360713D03*
X1362563Y933835D03*
X1358863D03*
X1355162D03*
X1362563Y927457D03*
X1358863D03*
X1357012Y930646D03*
X1355162Y940213D03*
X1351461Y927457D03*
X1353311Y930646D03*
X1351461Y940213D03*
Y933835D03*
X1353311Y937024D03*
X1362563Y940213D03*
X1358863D03*
X1357012Y937024D03*
X1355162Y927457D03*
X1364414Y937024D03*
X1360713D03*
Y956158D03*
Y943402D03*
Y949780D03*
X1364414Y956158D03*
Y943402D03*
Y949780D03*
X1357012Y943402D03*
X1358863Y946591D03*
X1362563D03*
X1357012Y949780D03*
Y956158D03*
X1355162Y952969D03*
X1353311Y943402D03*
X1351461Y946591D03*
X1353311Y949780D03*
X1351461Y952969D03*
X1353311Y956158D03*
X1362563Y952969D03*
X1358863D03*
X1355162Y946591D03*
X1360713Y962536D03*
Y968914D03*
X1364414Y962536D03*
Y968914D03*
X1358863Y959347D03*
X1362563D03*
X1357012Y962536D03*
X1355162Y965725D03*
X1357012Y968914D03*
X1351461Y965725D03*
X1353311Y968914D03*
X1351461Y959347D03*
X1353311Y962536D03*
X1362563Y965725D03*
X1358863D03*
X1355162Y959347D03*
X1360713Y975292D03*
X1364414D03*
X1358863Y972103D03*
X1362563D03*
X1357012Y975292D03*
X1360713Y981670D03*
X1355162Y978481D03*
X1362563Y984859D03*
X1355162D03*
X1351461D03*
Y978481D03*
X1353311Y981670D03*
X1351461Y972103D03*
X1353311Y975292D03*
X1357012Y981670D03*
X1364414D03*
X1358863Y984859D03*
X1362563Y978481D03*
X1358863D03*
X1355162Y972103D03*
Y991237D03*
Y997615D03*
X1362563Y991237D03*
Y997615D03*
X1360713Y994426D03*
Y988048D03*
Y1000804D03*
X1353311Y988048D03*
X1351461Y997615D03*
X1353311Y1000804D03*
Y994426D03*
X1357012Y988048D03*
X1358863Y997615D03*
X1357012Y994426D03*
X1358863Y991237D03*
X1364414Y988048D03*
Y994426D03*
X1357012Y1000804D03*
X1364414D03*
X1351461Y991237D03*
X1358863Y1010371D03*
X1360713Y1007182D03*
X1362563Y1003993D03*
X1355162D03*
X1351461D03*
X1353311Y1007182D03*
X1357012D03*
X1358863Y1003993D03*
X1364414Y1007182D03*
X1355162Y1010371D03*
X1362563D03*
X1351461D03*
X1356343Y1028055D03*
X1363745D03*
X1360044D03*
X1352642D03*
X1350792Y1031244D03*
Y1044000D03*
Y1037622D03*
X1356343Y1034433D03*
Y1040811D03*
X1363745Y1034433D03*
Y1040811D03*
X1361894Y1044000D03*
Y1037622D03*
Y1031244D03*
X1354493D03*
X1352642Y1034433D03*
X1354493Y1037622D03*
X1352642Y1040811D03*
X1358193Y1031244D03*
X1360044Y1040811D03*
Y1034433D03*
X1358193Y1037622D03*
Y1044000D03*
X1354493D03*
X1361894Y1063134D03*
X1365595D03*
X1354493Y1056756D03*
X1350792D03*
Y1050378D03*
X1352642Y1059945D03*
X1356343Y1047189D03*
X1363745D03*
X1356343Y1053567D03*
X1361894Y1050378D03*
X1356343Y1059945D03*
X1363745Y1053567D03*
X1354493Y1050378D03*
X1352642Y1047189D03*
X1363745Y1059945D03*
X1360044D03*
Y1047189D03*
X1358193Y1050378D03*
X1360044Y1053567D03*
X1361894Y1056756D03*
X1358193D03*
X1352642Y1053567D03*
X1361894Y1069512D03*
X1365595D03*
Y1075890D03*
X1361894D03*
X1350792Y1063134D03*
Y1069512D03*
X1358193Y1063134D03*
X1356343Y1072701D03*
X1363745Y1066323D03*
X1358193Y1069512D03*
X1360044Y1066323D03*
X1354493Y1063134D03*
X1352642Y1066323D03*
X1354493Y1069512D03*
X1352642Y1072701D03*
X1361894Y1069512D03*
Y1063134D03*
X1363745Y1072701D03*
X1360044D03*
X1356343Y1066323D03*
X1365595Y1088646D03*
Y1082268D03*
X1361894Y1088646D03*
Y1082268D03*
X1350792Y1075890D03*
Y1082268D03*
Y1088646D03*
X1358193Y1075890D03*
X1363745Y1079079D03*
X1360044D03*
X1356343Y1085457D03*
X1358193Y1088646D03*
Y1082268D03*
X1354493Y1075890D03*
X1352642Y1079079D03*
X1354493Y1082268D03*
X1352642Y1085457D03*
X1354493Y1088646D03*
X1361894Y1075890D03*
Y1088646D03*
Y1082268D03*
X1363745Y1085457D03*
X1360044D03*
X1356343Y1079079D03*
X1361894Y1095024D03*
X1365595D03*
X1350792D03*
Y1101402D03*
X1356343Y1104591D03*
X1363745Y1091835D03*
X1360044D03*
X1358193Y1095024D03*
X1356343Y1098213D03*
X1363745Y1104591D03*
X1360044D03*
X1352642D03*
X1354493Y1095024D03*
X1352642Y1098213D03*
X1354493Y1101402D03*
X1352642Y1091835D03*
X1361894Y1095024D03*
X1363745Y1098213D03*
X1360044D03*
X1356343Y1091835D03*
X1358193Y1101402D03*
X1361894D03*
X1350792Y1107780D03*
Y1114158D03*
X1358193Y1107780D03*
X1360044Y1110969D03*
X1363745D03*
X1356343Y1117347D03*
X1358193Y1114158D03*
X1354493D03*
X1352642Y1117347D03*
X1354493Y1107780D03*
X1352642Y1110969D03*
X1361894Y1114158D03*
Y1107780D03*
X1363745Y1117347D03*
X1360044D03*
X1356343Y1110969D03*
X1350792Y1120536D03*
Y1126914D03*
Y1133292D03*
X1358193Y1126914D03*
X1363745Y1123725D03*
X1360044D03*
X1358193Y1120536D03*
X1356343Y1130102D03*
X1358193Y1133292D03*
X1354493Y1120536D03*
X1352642Y1123725D03*
X1354493Y1133292D03*
Y1126914D03*
X1352642Y1130102D03*
X1361894Y1120536D03*
Y1126914D03*
Y1133292D03*
X1363745Y1130102D03*
X1360044D03*
X1356343Y1123725D03*
X1350792Y1139669D03*
Y1146047D03*
X1358193Y1139669D03*
X1363745Y1136480D03*
X1360044D03*
X1356343Y1142858D03*
X1363745Y1149236D03*
X1360044D03*
X1358193Y1146047D03*
X1352642Y1136480D03*
X1354493Y1139669D03*
X1352642Y1142858D03*
X1354493Y1146047D03*
X1352642Y1149236D03*
X1361894Y1139669D03*
Y1146047D03*
X1360044Y1142858D03*
X1363745D03*
X1356343Y1149236D03*
Y1136480D03*
X1354493Y1158803D03*
X1350792Y1152425D03*
Y1158803D03*
X1352642Y1161992D03*
X1356343Y1155614D03*
X1363745D03*
X1360044D03*
X1363745Y1161992D03*
X1354493Y1152425D03*
X1352642Y1155614D03*
X1358193Y1152425D03*
X1356343Y1161992D03*
X1360044D03*
X1361894Y1158803D03*
X1358193D03*
X1361894Y1152425D03*
X1351141Y1547243D03*
X1352536Y1540295D03*
X1355866Y1547243D03*
X1357260Y1540295D03*
X1360590Y1547243D03*
X1361984Y1540295D03*
X1352436Y1549970D03*
X1357161D03*
X1361885D03*
X1354011Y1552698D03*
X1358735D03*
X1363460D03*
X1360260Y1554453D03*
X1355536D03*
X1350811D03*
X1360811Y1561853D03*
X1356087D03*
X1351362D03*
X1352436Y1563608D03*
X1357161D03*
X1361885D03*
X1354011Y1566336D03*
X1358735D03*
X1363460D03*
X1360260Y1556953D03*
X1360811Y1559353D03*
X1350811Y1556953D03*
X1351362Y1559353D03*
X1356087D03*
X1355536Y1556953D03*
X1355586Y1569063D03*
X1361984Y1575641D03*
X1360310Y1569063D03*
X1352536Y1575641D03*
X1350861Y1569063D03*
X1357260Y1575641D03*
X1350619Y1625380D03*
X1358419D03*
X1362679D03*
X1352379Y1635380D03*
X1356659D03*
X1364439D03*
X1356659Y1647292D03*
X1352379D03*
X1364439D03*
X1358419Y1657292D03*
X1350619D03*
X1362679D03*
X1363187Y1679320D03*
Y1683857D03*
X1355313Y1684454D03*
Y1679920D03*
Y1675383D03*
Y1694093D03*
Y1689556D03*
X1363187Y1688391D03*
Y1693493D03*
Y1698030D03*
X1355313Y1698627D03*
X1363187Y1716737D03*
Y1702564D03*
Y1707666D03*
Y1712203D03*
X1355313Y1712800D03*
Y1708266D03*
Y1703729D03*
X1363187Y1726377D03*
Y1730911D03*
X1355313Y1726974D03*
Y1722440D03*
Y1717903D03*
X1363187Y1721840D03*
X1373666Y876434D03*
X1375516Y873245D03*
Y879623D03*
X1369965Y876434D03*
X1366264D03*
X1377367D03*
X1368115Y879623D03*
X1371815D03*
X1375516Y892379D03*
X1371815D03*
X1369965Y882812D03*
X1366264D03*
X1369965Y889190D03*
X1368115Y892379D03*
X1366264Y895568D03*
X1373666Y882812D03*
X1377367D03*
X1379217Y892379D03*
X1377367Y895568D03*
X1373666Y889190D03*
X1368115Y886001D03*
X1369965Y895568D03*
X1373666D03*
X1366264Y889190D03*
X1377366D03*
X1379216Y886001D03*
X1371815D03*
X1375516D03*
Y898757D03*
Y905134D03*
X1371815Y898757D03*
Y905134D03*
X1375516Y911512D03*
X1371815D03*
X1368115Y898757D03*
X1369965Y901946D03*
X1366264D03*
X1368115Y905134D03*
Y911512D03*
X1366264Y908324D03*
X1379217Y898757D03*
X1377367Y901946D03*
X1373666D03*
X1379217Y905134D03*
X1377367Y908324D03*
X1379217Y911512D03*
X1369965Y908324D03*
X1373666D03*
X1375516Y917890D03*
Y924268D03*
X1371815Y917890D03*
Y924268D03*
X1369965Y914701D03*
X1368115Y917890D03*
X1366264Y914701D03*
X1368115Y924268D03*
X1366264Y921079D03*
X1377367Y914701D03*
X1373666D03*
X1379217Y917890D03*
X1377367Y921079D03*
X1379217Y924268D03*
X1369965Y921079D03*
X1373666D03*
X1375516Y930646D03*
X1371815D03*
X1366264Y933835D03*
X1369965Y927457D03*
X1368115Y930646D03*
X1369965Y933835D03*
X1366264Y927457D03*
Y940213D03*
X1377367Y927457D03*
X1373666D03*
X1379217Y930646D03*
X1377367Y933835D03*
X1373666D03*
X1377367Y940213D03*
X1369965D03*
X1373666D03*
X1371815Y937024D03*
X1379217D03*
X1368115D03*
X1375516D03*
X1371815Y956158D03*
Y943402D03*
Y949780D03*
X1375516Y956158D03*
Y943402D03*
Y949780D03*
X1368115Y943402D03*
X1369965Y946591D03*
X1368115Y949780D03*
X1366264Y946591D03*
X1368115Y956158D03*
X1366264Y952969D03*
X1379217Y943402D03*
X1373666Y946591D03*
X1377367D03*
X1379217Y949780D03*
X1377367Y952969D03*
X1379217Y956158D03*
X1369965Y952969D03*
X1373666D03*
X1371815Y962536D03*
Y968914D03*
X1375516Y962536D03*
Y968914D03*
X1366264Y959347D03*
X1369965D03*
X1368115Y962536D03*
X1366264Y965725D03*
X1368115Y968914D03*
X1373666Y959347D03*
X1377367Y965725D03*
Y959347D03*
X1379217Y962536D03*
Y968914D03*
X1369965Y965725D03*
X1373666D03*
X1371815Y975292D03*
X1375516D03*
X1369965Y972103D03*
X1368115Y975292D03*
Y981670D03*
X1366264Y972103D03*
Y978481D03*
X1369965Y984859D03*
X1373666Y972103D03*
X1377367D03*
X1379217Y975292D03*
X1375516Y981670D03*
X1377367Y978481D03*
Y984859D03*
X1366264D03*
X1369965Y978481D03*
X1373666D03*
X1371815Y981670D03*
X1379217D03*
X1373666Y984859D03*
X1369965Y991237D03*
Y997615D03*
X1368115Y994426D03*
Y988048D03*
Y1000804D03*
X1375516Y994426D03*
X1377367Y991237D03*
Y997615D03*
X1375516Y988048D03*
Y1000804D03*
X1373666Y991237D03*
X1371815Y988048D03*
Y994426D03*
Y1000804D03*
X1366264Y997615D03*
Y991237D03*
X1379217Y988048D03*
Y994426D03*
X1373666Y997615D03*
X1379217Y1000804D03*
X1369965Y1003993D03*
X1368115Y1007182D03*
X1366264Y1010371D03*
X1373666D03*
X1375516Y1007182D03*
X1371815D03*
X1377367Y1003993D03*
X1366264D03*
X1379217Y1007182D03*
X1377367Y1010371D03*
X1373666Y1003993D03*
X1369965Y1010371D03*
X1371146Y1028055D03*
X1374847D03*
X1378548D03*
X1367445D03*
X1369296Y1044000D03*
Y1037622D03*
Y1031244D03*
X1371146Y1034433D03*
X1376697Y1037622D03*
X1378548Y1040811D03*
X1371146D03*
X1374847Y1034433D03*
X1376697Y1031244D03*
Y1044000D03*
X1374847Y1040811D03*
X1378548Y1034433D03*
X1372997Y1037622D03*
Y1044000D03*
X1367445Y1040811D03*
Y1034433D03*
X1365595Y1031244D03*
Y1037622D03*
Y1044000D03*
X1372997Y1031244D03*
Y1063134D03*
X1376697D03*
X1378548Y1053567D03*
X1376697Y1050378D03*
X1367445Y1059945D03*
X1369296Y1056756D03*
Y1050378D03*
X1371146Y1047189D03*
X1378548D03*
X1376697Y1056756D03*
X1371146Y1053567D03*
X1378548Y1059945D03*
X1374847Y1047189D03*
Y1053567D03*
X1371146Y1059945D03*
X1372997Y1056756D03*
Y1050378D03*
X1374847Y1059945D03*
X1365595Y1056756D03*
X1367445Y1047189D03*
Y1053567D03*
X1365595Y1050378D03*
X1372997Y1069512D03*
X1376697D03*
X1372997Y1075890D03*
X1376697D03*
X1369296Y1063134D03*
Y1069512D03*
X1367445Y1066323D03*
Y1072701D03*
X1371146Y1066323D03*
X1378548D03*
X1374847D03*
X1378548Y1072701D03*
X1372997Y1069512D03*
Y1063134D03*
X1365595Y1069512D03*
Y1063134D03*
X1376697Y1069512D03*
Y1063134D03*
X1371146Y1072701D03*
X1374847D03*
X1372997Y1088646D03*
Y1082268D03*
X1376697Y1088646D03*
Y1082268D03*
X1369296Y1075890D03*
X1367445Y1079079D03*
X1369296Y1088646D03*
X1367445Y1085457D03*
X1369296Y1082268D03*
X1371146Y1079079D03*
X1378548D03*
X1374847D03*
X1378548Y1085457D03*
X1372997Y1075890D03*
X1365595D03*
X1376697D03*
X1372997Y1088646D03*
Y1082268D03*
X1365595Y1088646D03*
Y1082268D03*
X1376697Y1088646D03*
Y1082268D03*
X1374847Y1085457D03*
X1371146D03*
X1372997Y1095024D03*
X1376697D03*
X1367445Y1091835D03*
X1369296Y1095024D03*
X1367445Y1104591D03*
Y1098213D03*
X1371146Y1091835D03*
X1378548D03*
X1374847D03*
X1371146Y1104591D03*
X1374847D03*
X1378548Y1098213D03*
Y1104591D03*
X1372997Y1095024D03*
X1365595D03*
X1376697D03*
X1374847Y1098213D03*
X1371146D03*
X1372997Y1101402D03*
X1376697D03*
X1369296D03*
X1365595D03*
X1369296Y1107780D03*
X1367445Y1110969D03*
X1369296Y1114158D03*
X1367445Y1117347D03*
X1371146Y1110969D03*
X1378548D03*
X1374847D03*
X1378548Y1117347D03*
X1365595Y1114158D03*
Y1107780D03*
X1376697Y1114158D03*
Y1107780D03*
X1372997Y1114158D03*
Y1107780D03*
X1374847Y1117347D03*
X1371146D03*
X1367445Y1130103D03*
X1369296Y1126914D03*
Y1120536D03*
X1367445Y1123725D03*
X1369296Y1133292D03*
X1374847Y1123725D03*
X1371146D03*
X1378548D03*
Y1130102D03*
X1365595Y1120536D03*
X1376697D03*
Y1126914D03*
X1372997Y1120536D03*
Y1126914D03*
X1365595D03*
Y1133292D03*
X1376697D03*
X1372997D03*
X1371146Y1130102D03*
X1374847D03*
X1369296Y1139669D03*
X1367445Y1136480D03*
Y1142858D03*
X1369296Y1146047D03*
X1374847Y1136480D03*
X1371146D03*
X1378548D03*
Y1142858D03*
X1371146Y1149236D03*
X1374847D03*
X1365595Y1139669D03*
Y1146047D03*
X1376697Y1139669D03*
Y1146047D03*
X1372997Y1139669D03*
Y1146047D03*
X1374847Y1142858D03*
X1371146D03*
X1378548Y1149236D03*
X1367445D03*
Y1155614D03*
X1365595Y1158803D03*
X1371146Y1155614D03*
X1378548D03*
X1374847D03*
X1376697Y1158803D03*
Y1165181D03*
X1374847Y1161992D03*
X1369296Y1152425D03*
X1371146Y1161992D03*
X1378548D03*
X1367445D03*
X1372997Y1158803D03*
X1369296D03*
X1365595Y1152425D03*
X1376697D03*
X1372997D03*
X1365315Y1547243D03*
X1366709Y1540295D03*
X1370039Y1547243D03*
X1371433Y1540295D03*
X1374763Y1547243D03*
X1376158Y1540295D03*
X1379488Y1547243D03*
X1371334Y1549970D03*
X1376058D03*
X1366609D03*
X1372909Y1552698D03*
X1377633D03*
X1368184D03*
X1379158Y1554453D03*
X1374433D03*
X1369709D03*
X1364984D03*
X1374984Y1561853D03*
X1370260D03*
X1365535D03*
X1371334Y1563608D03*
X1376058D03*
X1366609D03*
X1372909Y1566336D03*
X1377633D03*
X1368184D03*
X1369709Y1556953D03*
X1370260Y1559353D03*
X1379158Y1556953D03*
X1374984Y1559353D03*
X1374433Y1556953D03*
X1365535Y1559353D03*
X1364984Y1556953D03*
X1379208Y1569063D03*
X1369759D03*
X1365035D03*
X1371433Y1575641D03*
X1366709D03*
X1376158D03*
X1374483Y1569063D03*
X1370479Y1625380D03*
X1374740D03*
X1368719Y1635380D03*
X1376499Y1635286D03*
X1368719Y1647292D03*
X1376499D03*
X1370479Y1657292D03*
X1374739D03*
X1386619Y879623D03*
X1382918Y873245D03*
X1384768Y876434D03*
X1394020Y873245D03*
X1388469Y876434D03*
X1392170D03*
X1381067D03*
X1390320Y879623D03*
X1394021D03*
X1386619Y892379D03*
X1394020D03*
X1382918D03*
X1384768Y882812D03*
X1381067D03*
Y889190D03*
X1384768D03*
X1392170Y882812D03*
X1388469D03*
Y895568D03*
X1392170Y889190D03*
X1390319Y892379D03*
X1381067Y895568D03*
X1384768D03*
X1390319Y886001D03*
X1392170Y895568D03*
X1388469Y889190D03*
X1394021Y886001D03*
X1386619Y905134D03*
Y898757D03*
X1394020Y905134D03*
Y898757D03*
X1382918Y905134D03*
Y898757D03*
X1386619Y911512D03*
X1394020D03*
X1382918D03*
X1381067Y901946D03*
X1384768D03*
X1388469D03*
X1390319Y898757D03*
X1392170Y901946D03*
X1388469Y908324D03*
X1390319Y911512D03*
Y905134D03*
X1384768Y908324D03*
X1392170D03*
X1381067Y908323D03*
X1386619Y924268D03*
Y917890D03*
X1394020Y924268D03*
Y917890D03*
X1382918Y924268D03*
Y917890D03*
X1381067Y914701D03*
X1384768D03*
X1390319Y917890D03*
X1388469Y914701D03*
X1392170D03*
X1388469Y921079D03*
X1390319Y924268D03*
X1384768Y921079D03*
X1381067D03*
X1392170D03*
X1394020Y937024D03*
X1381067Y927457D03*
X1384768D03*
X1388469D03*
Y933835D03*
X1392170Y927457D03*
X1390319Y930646D03*
X1392170Y933835D03*
X1388469Y940213D03*
X1390319Y937024D03*
X1382918Y930646D03*
X1386619D03*
X1384768Y940213D03*
X1381067D03*
X1394020Y930646D03*
X1392170Y940213D03*
X1381067Y933835D03*
X1386619Y937024D03*
X1384768Y933835D03*
X1382918Y937024D03*
X1394020Y956158D03*
Y943402D03*
Y949780D03*
X1382918Y956158D03*
Y943402D03*
Y949780D03*
X1386619Y956158D03*
Y943402D03*
Y949780D03*
X1381067Y946591D03*
X1384768D03*
X1388469D03*
X1390319Y943402D03*
X1392170Y946591D03*
X1390319Y949780D03*
X1388469Y952969D03*
X1390319Y956158D03*
X1384768Y952969D03*
X1381067D03*
X1392170D03*
X1394020Y962536D03*
Y968914D03*
X1382918Y962536D03*
Y968914D03*
X1386619Y962536D03*
Y968914D03*
X1381067Y959347D03*
X1384768D03*
X1388469Y965725D03*
Y959347D03*
X1392170D03*
X1390319Y962536D03*
Y968914D03*
X1384768Y965725D03*
X1381067D03*
X1392170D03*
X1394020Y975292D03*
X1382918D03*
X1386619D03*
X1388469Y978481D03*
X1381067Y972103D03*
X1384768D03*
X1382918Y981670D03*
X1384768Y984859D03*
X1388469Y972103D03*
X1392170D03*
X1390319Y981670D03*
Y975292D03*
X1392170Y984859D03*
X1381067Y978481D03*
X1384768D03*
X1386619Y981670D03*
X1381067Y984859D03*
X1392170Y978481D03*
X1394020Y981670D03*
X1388469Y984859D03*
X1384768Y991237D03*
X1382918Y988048D03*
X1392170Y991237D03*
X1390319Y988048D03*
X1384756Y997607D03*
X1392157D03*
X1386619Y988048D03*
X1394020D03*
X1381067Y991237D03*
X1388457Y997607D03*
X1388469Y991237D03*
X1386606Y1007174D03*
X1381065Y1010365D03*
X1382905Y1007174D03*
X1385937Y1028063D03*
X1382236D03*
X1385937Y1034441D03*
X1393339Y1040819D03*
X1385937D03*
X1380398Y1044000D03*
X1382246Y1040819D03*
X1389638D03*
X1382236Y1034441D03*
X1380398Y1037622D03*
Y1031244D03*
X1384099Y1063134D03*
X1387800D03*
X1395201D03*
X1385949Y1047189D03*
Y1053567D03*
X1384099Y1056756D03*
Y1050378D03*
X1393351Y1047189D03*
Y1053567D03*
X1389650Y1059945D03*
X1391500Y1056756D03*
Y1050378D03*
X1382249Y1047189D03*
X1389650D03*
X1380398Y1050378D03*
X1382249Y1059945D03*
Y1053567D03*
X1385949Y1059945D03*
X1380398Y1056756D03*
X1387800D03*
X1393351Y1059945D03*
X1387800Y1050378D03*
X1389650Y1053567D03*
X1384099Y1069512D03*
X1387800D03*
X1395201D03*
Y1075890D03*
X1384099D03*
X1387800D03*
X1389650Y1066323D03*
X1391500Y1069512D03*
X1389650Y1072701D03*
X1380398Y1063134D03*
X1385949Y1066323D03*
X1382249D03*
X1380398Y1069512D03*
X1391500Y1063134D03*
X1393351Y1066323D03*
X1384099Y1069512D03*
Y1063134D03*
X1387800Y1069512D03*
Y1063134D03*
X1382249Y1072701D03*
X1385949D03*
X1393351D03*
X1395201Y1082268D03*
Y1088646D03*
X1384099D03*
Y1082268D03*
X1387800Y1088646D03*
Y1082268D03*
X1380398Y1075890D03*
X1385949Y1079079D03*
X1382249D03*
X1380398Y1088646D03*
Y1082268D03*
X1391500Y1075890D03*
X1393351Y1079079D03*
X1389650D03*
X1391500Y1088646D03*
X1389650Y1085457D03*
X1391500Y1082268D03*
X1384099Y1075890D03*
X1387800D03*
X1384099Y1088646D03*
Y1082268D03*
X1387800Y1088646D03*
Y1082268D03*
X1382249Y1085457D03*
X1385949D03*
X1393351D03*
X1384099Y1095024D03*
X1387800D03*
X1395201D03*
Y1101402D03*
X1385949Y1091835D03*
X1382249D03*
X1380398Y1095024D03*
X1393351Y1091835D03*
X1389650D03*
X1391500Y1095024D03*
Y1101402D03*
X1389650Y1098213D03*
X1393351Y1104591D03*
X1389650D03*
X1384099Y1095024D03*
X1387800D03*
X1382249Y1098213D03*
X1385949D03*
X1393351D03*
X1385949Y1104591D03*
X1384099Y1101402D03*
X1380398D03*
X1382249Y1104591D03*
X1387800Y1101402D03*
X1385949Y1110969D03*
X1382249D03*
X1380398Y1107780D03*
Y1114158D03*
X1393351Y1110969D03*
X1389650D03*
X1391500Y1107780D03*
X1389650Y1117347D03*
X1391500Y1114158D03*
X1387800D03*
X1384099D03*
Y1107780D03*
X1382249Y1117347D03*
X1385949D03*
X1387800Y1107780D03*
X1393351Y1117347D03*
X1385949Y1123725D03*
X1382249D03*
X1380398Y1120536D03*
Y1126914D03*
Y1133292D03*
X1393351Y1123725D03*
X1389650D03*
X1391500Y1120536D03*
Y1126914D03*
Y1133292D03*
X1389650Y1130102D03*
X1387800Y1120536D03*
Y1126914D03*
X1384099Y1120536D03*
Y1126914D03*
X1387800Y1133292D03*
X1384099D03*
X1385949Y1130102D03*
X1382249D03*
X1393351D03*
X1380398Y1139669D03*
X1385949Y1136480D03*
X1382249D03*
X1385949Y1149236D03*
X1382249D03*
X1380398Y1146047D03*
X1391500Y1139669D03*
X1393351Y1136480D03*
X1389650D03*
Y1142858D03*
X1393351Y1149236D03*
X1391500Y1146047D03*
X1387800Y1139669D03*
Y1146047D03*
X1384099Y1139669D03*
Y1146047D03*
X1382249Y1142858D03*
X1385949D03*
X1393351D03*
X1389650Y1149236D03*
X1385949Y1155614D03*
X1382249D03*
X1385949Y1161992D03*
X1387800Y1158803D03*
X1393351Y1155614D03*
X1389650D03*
X1380398Y1152425D03*
X1382249Y1161992D03*
X1391500Y1152425D03*
X1393351Y1161992D03*
X1389650D03*
X1384099Y1158803D03*
X1380398D03*
X1391500D03*
X1387800Y1152425D03*
X1384099D03*
X1388937Y1547243D03*
X1380882Y1540295D03*
X1384212Y1547243D03*
X1385606Y1540295D03*
X1390331D03*
X1393661Y1547243D03*
X1380783Y1549970D03*
X1385507D03*
X1390232D03*
X1382357Y1552698D03*
X1387082D03*
X1391806D03*
X1393331Y1554453D03*
X1388607D03*
X1383882D03*
X1393882Y1561853D03*
X1389158D03*
X1384433D03*
X1379709D03*
X1380783Y1563608D03*
X1385507D03*
X1390232D03*
X1382357Y1566336D03*
X1387082D03*
X1391806D03*
X1388607Y1556953D03*
X1384433Y1559353D03*
X1383882Y1556953D03*
X1379709Y1559353D03*
X1393882D03*
X1389158D03*
X1393331Y1556953D03*
X1388657Y1569063D03*
X1385606Y1575641D03*
X1383932Y1569063D03*
X1380882Y1575641D03*
X1390331D03*
X1393381Y1569063D03*
X1382539Y1625380D03*
X1388569Y1635380D03*
X1380779D03*
Y1647292D03*
X1388569D03*
X1382539Y1657292D03*
X1397721Y873245D03*
Y879623D03*
X1395871Y876434D03*
X1408823Y879623D03*
X1399571Y876434D03*
X1403272D03*
X1405123Y879623D03*
X1401423D03*
X1406973Y895568D03*
X1397721Y892379D03*
X1403272Y895568D03*
X1399571Y882812D03*
X1395871D03*
X1401422Y892379D03*
X1399571Y895568D03*
X1395871Y889190D03*
X1403272Y882812D03*
X1406973D03*
X1403272Y889190D03*
X1406973D03*
X1401422Y886001D03*
X1395871Y895568D03*
X1399571Y889190D03*
X1408823Y892379D03*
X1405123D03*
X1397722Y886001D03*
X1408824D03*
X1405123D03*
X1406973Y908324D03*
Y901946D03*
X1397721Y905134D03*
Y898757D03*
X1403272Y908324D03*
Y901946D03*
X1397721Y911512D03*
X1399571Y901946D03*
X1395871D03*
X1401422Y905134D03*
Y911512D03*
X1405123Y905134D03*
X1408823D03*
X1401422Y898757D03*
X1399571Y908323D03*
X1395871Y908324D03*
X1408823Y911512D03*
X1405123D03*
X1408823Y898757D03*
X1405123D03*
X1406973Y921079D03*
Y914701D03*
X1397721Y924268D03*
Y917890D03*
X1403272Y921079D03*
Y914701D03*
X1399571D03*
X1401422Y917890D03*
X1395871Y914701D03*
X1399571Y921079D03*
X1401422Y924268D03*
X1405123Y917890D03*
X1408823D03*
X1395871Y921079D03*
X1408823Y924268D03*
X1405123D03*
X1403272Y940213D03*
X1406973D03*
X1397721Y937024D03*
X1406973Y927457D03*
X1403272D03*
X1395871D03*
Y933835D03*
X1399571Y927457D03*
X1401422Y930646D03*
X1399571Y933835D03*
Y940213D03*
X1401422Y937024D03*
X1405123Y930646D03*
X1408823D03*
X1405123Y937024D03*
X1408823D03*
X1397721Y930646D03*
X1395871Y940213D03*
X1406973Y933835D03*
X1403272D03*
Y952969D03*
Y946591D03*
X1406973Y952969D03*
Y946591D03*
X1397721Y956158D03*
Y943402D03*
Y949780D03*
X1401422Y943402D03*
X1399571Y946591D03*
X1401422Y949780D03*
X1399571Y952969D03*
X1401422Y956158D03*
X1408823Y949780D03*
X1405123D03*
X1395871Y946591D03*
Y952969D03*
X1405123Y943402D03*
X1408823D03*
X1405123Y956158D03*
X1408823D03*
X1403272Y959347D03*
Y965725D03*
X1406973Y959347D03*
Y965725D03*
X1397721Y962536D03*
Y968914D03*
X1399571Y965725D03*
X1395871Y959347D03*
X1399571D03*
X1401422Y962536D03*
Y968914D03*
X1408823Y962536D03*
X1405123D03*
Y968914D03*
X1395871Y965725D03*
X1408823Y968914D03*
X1403272Y978481D03*
Y972103D03*
X1406973Y978481D03*
Y972103D03*
X1397721Y975292D03*
Y981670D03*
X1399571Y978481D03*
X1395871Y972103D03*
X1399571D03*
X1401422Y975292D03*
X1399571Y984859D03*
X1405123Y981670D03*
X1408823Y975292D03*
X1405123D03*
X1406973Y984859D03*
X1395871Y978481D03*
X1401422Y981670D03*
X1395871Y984859D03*
X1408823Y981670D03*
X1403272Y984859D03*
X1399571Y991237D03*
X1397721Y988048D03*
X1406973Y991237D03*
X1405123Y988048D03*
X1406961Y997607D03*
X1399559D03*
X1401422Y988048D03*
X1395858Y997607D03*
X1395871Y991237D03*
X1403260Y997607D03*
X1408823Y988048D03*
X1403272Y991237D03*
X1400740Y1040819D03*
X1397039D03*
X1404441D03*
X1408154Y1059945D03*
X1404453D03*
X1398902Y1063134D03*
X1400752Y1047189D03*
X1398902Y1056756D03*
X1400752Y1053567D03*
Y1059945D03*
X1398902Y1050378D03*
X1408154Y1047189D03*
Y1053567D03*
X1406304Y1056756D03*
Y1050378D03*
X1404453Y1059945D03*
X1408154D03*
X1397052Y1047189D03*
X1404453D03*
X1395201Y1050378D03*
X1402603Y1056756D03*
Y1050378D03*
X1395201Y1056756D03*
X1397052Y1059945D03*
Y1053567D03*
X1404453D03*
Y1072701D03*
Y1066323D03*
X1408154Y1072701D03*
Y1066323D03*
X1398902Y1069512D03*
Y1075890D03*
X1402603Y1063134D03*
Y1069512D03*
X1397052Y1066323D03*
X1400752D03*
Y1072701D03*
X1406304Y1063134D03*
X1395201D03*
X1404453Y1072701D03*
Y1066323D03*
X1395201Y1069512D03*
X1398902Y1063134D03*
X1408154Y1072701D03*
Y1066323D03*
X1398902Y1069512D03*
X1406304D03*
X1397052Y1072701D03*
X1408154Y1079079D03*
Y1085457D03*
X1404453Y1079079D03*
Y1085457D03*
X1398902Y1082268D03*
Y1088646D03*
X1404453Y1091835D03*
X1408154D03*
X1402603Y1075890D03*
X1400752Y1079079D03*
X1397052D03*
X1402603Y1088646D03*
Y1082268D03*
X1400752Y1085457D03*
X1406304Y1075890D03*
Y1088646D03*
X1395201Y1075890D03*
X1404453Y1079079D03*
X1398902Y1075890D03*
X1408154Y1079079D03*
X1395201Y1082268D03*
X1404453Y1085457D03*
X1395201Y1088646D03*
X1398902Y1082268D03*
X1408154Y1085457D03*
X1398902Y1088646D03*
X1397052Y1085457D03*
X1406304Y1082268D03*
X1404453Y1098213D03*
X1398902Y1095024D03*
Y1101402D03*
X1408154Y1098213D03*
X1402603Y1095024D03*
X1400752Y1091835D03*
X1397052D03*
X1402603Y1101402D03*
X1400752Y1104591D03*
X1397052D03*
X1400752Y1098213D03*
X1406304Y1101402D03*
X1395201Y1095024D03*
Y1101402D03*
X1404453Y1098213D03*
Y1091835D03*
X1398902Y1095024D03*
Y1101402D03*
X1408154Y1098213D03*
Y1091835D03*
X1397052Y1098213D03*
X1406304Y1095024D03*
X1408154Y1104591D03*
X1404453D03*
X1402603Y1107780D03*
X1397052Y1110969D03*
X1400752D03*
X1402603Y1114158D03*
X1400752Y1117347D03*
X1406304Y1107780D03*
X1398902Y1114158D03*
X1408154Y1117347D03*
Y1110969D03*
X1395201Y1114158D03*
X1404453Y1117347D03*
Y1110969D03*
X1398902Y1107780D03*
X1395201D03*
X1397052Y1117347D03*
X1406304Y1114158D03*
X1402603Y1120536D03*
Y1126914D03*
X1397052Y1123725D03*
X1400752D03*
X1402603Y1133292D03*
X1406304Y1120536D03*
Y1133292D03*
X1400752Y1130103D03*
X1398902Y1120536D03*
Y1126914D03*
X1408154Y1123725D03*
X1395201Y1120536D03*
Y1126914D03*
X1404453Y1123725D03*
X1398902Y1133292D03*
X1408154Y1130102D03*
X1395201Y1133292D03*
X1404453Y1130102D03*
X1397052D03*
X1406304Y1126914D03*
X1402603Y1139669D03*
X1397052Y1136480D03*
X1400752D03*
Y1142858D03*
X1402603Y1146047D03*
X1397052Y1149236D03*
X1408154D03*
X1404453D03*
X1398902Y1139669D03*
Y1146047D03*
X1408154Y1142858D03*
Y1136480D03*
X1395201Y1139669D03*
Y1146047D03*
X1404453Y1142858D03*
Y1136480D03*
X1397052Y1142858D03*
X1400752Y1149236D03*
X1406304Y1139669D03*
Y1146047D03*
X1398902Y1158803D03*
X1397052Y1155614D03*
X1400752D03*
X1397052Y1161992D03*
X1398902Y1165181D03*
X1406304Y1158803D03*
X1402603Y1152425D03*
X1400752Y1161992D03*
X1406304Y1152425D03*
X1404453Y1161992D03*
X1395201Y1158803D03*
X1398902Y1152425D03*
X1395201D03*
X1408154Y1155614D03*
X1395055Y1540295D03*
X1394956Y1549970D03*
X1396531Y1552698D03*
X1399256Y1540355D03*
X1401356D03*
X1402763Y1547073D03*
X1402707Y1549336D03*
X1398076Y1554453D03*
X1394956Y1563608D03*
X1396531Y1566336D03*
X1403058Y1567540D03*
X1403059Y1564618D03*
X1402970Y1561698D03*
X1395055Y1575641D03*
X1398712Y1569063D03*
X1402473Y1571658D03*
X1410674Y876434D03*
X1423602Y879623D03*
X1421751Y876434D03*
X1410674Y882812D03*
Y889190D03*
Y895568D03*
X1421751Y882812D03*
Y895568D03*
Y889190D03*
X1423602Y892379D03*
X1410674Y901946D03*
Y908324D03*
X1421751Y901946D03*
X1423602Y905134D03*
X1421751Y908324D03*
X1423602Y911512D03*
Y898757D03*
X1410674Y914701D03*
Y921079D03*
X1423602Y917890D03*
X1421751Y914701D03*
Y921079D03*
X1423602Y924268D03*
X1421751Y940213D03*
X1410674Y927457D03*
Y933835D03*
Y940213D03*
X1423602Y930646D03*
X1421751Y927457D03*
Y933835D03*
X1423602Y937024D03*
X1410674Y946591D03*
Y952969D03*
X1423602Y949780D03*
X1421751Y946591D03*
Y952969D03*
X1423602Y943402D03*
Y956158D03*
X1410674Y959347D03*
Y965725D03*
X1423602Y962536D03*
X1421751Y959347D03*
Y965725D03*
X1423602Y968914D03*
X1410674Y972103D03*
Y978481D03*
X1423602Y981670D03*
Y975292D03*
X1421751Y972103D03*
Y978481D03*
Y984859D03*
X1410674D03*
X1423602Y988048D03*
X1421751Y991237D03*
X1421764Y997607D03*
X1410661D03*
X1410674Y991237D03*
X1411855Y1059945D03*
X1422932Y1047189D03*
Y1059945D03*
Y1053567D03*
X1411855Y1047189D03*
X1410004Y1050378D03*
X1411855Y1053567D03*
X1410004Y1056756D03*
Y1063134D03*
X1411855Y1066323D03*
Y1072701D03*
X1422932D03*
Y1066323D03*
X1410004Y1069512D03*
Y1075890D03*
X1411855Y1079079D03*
Y1085457D03*
X1410004Y1088646D03*
X1422932Y1079079D03*
Y1085457D03*
X1410004Y1082268D03*
X1422932Y1091835D03*
Y1104591D03*
Y1098213D03*
X1411855Y1091835D03*
Y1104591D03*
Y1098213D03*
X1410004Y1101402D03*
Y1095024D03*
Y1107780D03*
X1411855Y1110969D03*
Y1117347D03*
X1422932Y1110969D03*
Y1117347D03*
X1410004Y1114158D03*
X1411855Y1123725D03*
X1410004Y1120536D03*
X1411855Y1130102D03*
X1410004Y1133292D03*
X1422932Y1123725D03*
Y1130102D03*
X1410004Y1126914D03*
X1411855Y1136480D03*
Y1142858D03*
Y1149236D03*
X1422932Y1136480D03*
Y1142858D03*
Y1149236D03*
X1410004Y1139669D03*
Y1146047D03*
X1411855Y1155614D03*
Y1161992D03*
X1422932Y1155614D03*
Y1161992D03*
X1410004Y1152425D03*
Y1158803D03*
X1436554Y876434D03*
X1438405Y879623D03*
X1431003Y873245D03*
X1434704Y879623D03*
Y873245D03*
X1438405D03*
X1429153Y876434D03*
X1432854D03*
X1434704Y892379D03*
X1425452Y895568D03*
X1438405Y892379D03*
X1429153Y895568D03*
Y882812D03*
X1425452Y889190D03*
X1429153D03*
X1431003Y892379D03*
X1432854Y895568D03*
X1436554Y889190D03*
Y882812D03*
X1431003Y886001D03*
X1427302D03*
Y892379D03*
X1432854Y889190D03*
X1436554Y895568D03*
X1438405Y886001D03*
X1434704Y898757D03*
Y905134D03*
X1425452Y901946D03*
Y908324D03*
X1438405Y898757D03*
Y905134D03*
X1429153Y901946D03*
Y908324D03*
X1432854Y901946D03*
X1431003Y898757D03*
Y911512D03*
Y905134D03*
X1427302D03*
X1436554Y901946D03*
X1432854Y908323D03*
X1434704Y911512D03*
X1438405D03*
X1427302D03*
X1436554Y908324D03*
X1427302Y898757D03*
X1432854Y914701D03*
X1431003Y917890D03*
X1427302D03*
X1432854Y921079D03*
X1431003Y924268D03*
X1436554Y914701D03*
X1434704Y917890D03*
Y924268D03*
X1425452Y914701D03*
Y921079D03*
X1438405Y917890D03*
Y924268D03*
X1429153Y914701D03*
Y921079D03*
X1427302Y924268D03*
X1436554Y921079D03*
X1438405Y937024D03*
X1429153Y940213D03*
X1434704Y937024D03*
X1425452Y940213D03*
X1432854Y927457D03*
X1431003Y930646D03*
X1427302D03*
X1432854Y933835D03*
Y940213D03*
X1431003Y937024D03*
X1427302D03*
X1436554Y927457D03*
Y933835D03*
X1425452Y927457D03*
X1429153D03*
Y933835D03*
X1425452D03*
X1434704Y930646D03*
X1438405D03*
X1436554Y940213D03*
X1438405Y943402D03*
Y956158D03*
X1429153Y946591D03*
Y952969D03*
X1438405Y949780D03*
X1434704Y943402D03*
Y956158D03*
X1425452Y946591D03*
Y952969D03*
X1434704Y949780D03*
X1431003Y943402D03*
Y949780D03*
X1427302D03*
X1432854Y946591D03*
Y952969D03*
X1431003Y956158D03*
X1436554Y946591D03*
X1427302Y943402D03*
Y956158D03*
X1436554Y952969D03*
X1432854Y959347D03*
X1427302Y962536D03*
X1431003D03*
X1432854Y965725D03*
X1431003Y968914D03*
X1436554Y959347D03*
X1438405Y962536D03*
X1429153Y965725D03*
Y959347D03*
X1438405Y968914D03*
X1434704Y962536D03*
X1425452Y965725D03*
Y959347D03*
X1434704Y968914D03*
X1427302D03*
X1436554Y965725D03*
X1432854Y978481D03*
X1431003Y981670D03*
X1432854Y972103D03*
X1431003Y975292D03*
X1427302D03*
X1429153Y984859D03*
X1438405Y981670D03*
X1436554Y972103D03*
Y984859D03*
X1438405Y975292D03*
X1429153Y972103D03*
Y978481D03*
X1434704Y975292D03*
X1425452Y972103D03*
Y978481D03*
X1427302Y981670D03*
X1434704D03*
X1425452Y984859D03*
X1432854D03*
X1436554Y978481D03*
X1431003Y988048D03*
X1429153Y991237D03*
X1436554D03*
X1438405Y988048D03*
X1436567Y997607D03*
X1429165D03*
X1434704Y988048D03*
X1425465Y997607D03*
X1432866D03*
X1427302Y988048D03*
X1425452Y991237D03*
X1432854D03*
X1430346Y1040819D03*
X1437748D03*
X1434047D03*
X1430334Y1059945D03*
X1426633D03*
X1435885Y1063134D03*
X1439586D03*
X1430334Y1047189D03*
X1424783Y1056756D03*
X1434035Y1059945D03*
X1432184Y1056756D03*
X1430334Y1053567D03*
X1424783Y1050378D03*
X1432184D03*
X1437735Y1047189D03*
Y1053567D03*
X1430334Y1059945D03*
X1426633D03*
X1434035Y1047189D03*
X1426633D03*
X1435885Y1050378D03*
X1428483D03*
X1437735Y1059945D03*
X1435885Y1056756D03*
X1428483D03*
X1426633Y1053567D03*
X1434035D03*
X1430334Y1066323D03*
Y1072701D03*
X1426633Y1066323D03*
Y1072701D03*
X1435885Y1069512D03*
X1439586D03*
Y1075890D03*
X1435885D03*
X1432184Y1063134D03*
X1428483D03*
X1424783D03*
X1432184Y1069512D03*
X1434035Y1072701D03*
Y1066323D03*
X1437735D03*
X1430334D03*
Y1072701D03*
X1426633Y1066323D03*
Y1072701D03*
X1435885Y1063134D03*
Y1069512D03*
X1428483D03*
X1424783D03*
X1437735Y1072701D03*
X1439586Y1088646D03*
Y1082268D03*
X1430334Y1079079D03*
X1426633D03*
X1435885Y1088646D03*
X1430334Y1085457D03*
X1426633D03*
X1435885Y1082268D03*
X1430334Y1091835D03*
X1426633D03*
X1437735Y1079079D03*
X1428483Y1075890D03*
X1432184D03*
X1424783D03*
X1434035Y1079079D03*
X1424783Y1088646D03*
X1432184Y1082268D03*
X1428483Y1088646D03*
X1432184D03*
X1434035Y1085457D03*
X1430334Y1079079D03*
X1426633D03*
X1435885Y1075890D03*
Y1088646D03*
X1428483Y1082268D03*
X1424783D03*
X1437735Y1085457D03*
X1430334D03*
X1426633D03*
X1435885Y1082268D03*
Y1101402D03*
Y1095024D03*
X1430334Y1098213D03*
X1426633D03*
X1439586Y1101402D03*
Y1095024D03*
X1432184D03*
X1434035Y1091835D03*
Y1104591D03*
X1428483Y1101402D03*
X1432184D03*
X1434035Y1098213D03*
X1424783Y1101402D03*
X1437735Y1091835D03*
Y1104591D03*
X1435885Y1101402D03*
Y1095024D03*
X1428483D03*
X1424783D03*
X1430334Y1104591D03*
X1426633D03*
X1437735Y1098213D03*
X1430334Y1091835D03*
Y1098213D03*
X1426633Y1091835D03*
Y1098213D03*
X1428483Y1107780D03*
X1432184D03*
X1424783D03*
X1434035Y1110969D03*
Y1117347D03*
X1432184Y1114158D03*
X1437735Y1110969D03*
X1426633D03*
Y1117347D03*
X1435885Y1114158D03*
X1430334Y1110969D03*
Y1117347D03*
X1428483Y1114158D03*
X1424783D03*
X1435885Y1107780D03*
X1437735Y1117347D03*
X1432184Y1126914D03*
Y1120536D03*
X1428483D03*
X1424783D03*
X1434035Y1123725D03*
X1424783Y1133292D03*
X1428483D03*
X1432184D03*
X1437735Y1123725D03*
X1434035Y1130103D03*
X1430334Y1130102D03*
X1426633D03*
Y1123725D03*
X1435885Y1126914D03*
Y1120536D03*
X1430334Y1123725D03*
X1424783Y1126914D03*
X1428483D03*
X1437735Y1130102D03*
X1435885Y1133292D03*
X1432184Y1139669D03*
X1434035Y1136480D03*
Y1142858D03*
X1430334Y1149236D03*
X1432184Y1146047D03*
X1426633Y1149236D03*
X1437735Y1136480D03*
Y1149236D03*
X1435885Y1146047D03*
Y1139669D03*
X1428483D03*
X1424783D03*
X1434035Y1149236D03*
X1428483Y1146047D03*
X1424783D03*
X1437735Y1142858D03*
X1426633Y1136480D03*
Y1142858D03*
X1430334Y1136480D03*
Y1142858D03*
X1426633Y1161992D03*
X1424783Y1152425D03*
X1426633Y1155614D03*
X1430333D03*
X1435885Y1158803D03*
Y1152425D03*
X1428483D03*
X1432184D03*
X1434035Y1161992D03*
X1430334D03*
X1424783Y1158803D03*
X1432184D03*
X1434035Y1155614D03*
X1428484Y1158803D03*
X1437735Y1155614D03*
X1447657Y876434D03*
X1445806Y879623D03*
X1443956Y876434D03*
X1440255D03*
X1451358D03*
X1449507Y873245D03*
X1453208D03*
X1445806Y892379D03*
X1449507D03*
X1443956Y882812D03*
X1447657D03*
X1440255Y889190D03*
X1447657D03*
X1442106Y892379D03*
X1443956Y895568D03*
X1451357Y882812D03*
X1451358Y889190D03*
X1453208Y892379D03*
X1440255Y882812D03*
X1442106Y886001D03*
X1443956Y889190D03*
X1447657Y895568D03*
X1440255D03*
X1453208Y886001D03*
X1451358Y895568D03*
X1445806Y898757D03*
Y905134D03*
X1449507Y898757D03*
Y905134D03*
X1442106Y898757D03*
X1440255Y901946D03*
X1447657D03*
X1443956D03*
X1442106Y905134D03*
X1443956Y908324D03*
X1442106Y911512D03*
X1451358Y901946D03*
X1453208Y898757D03*
Y905134D03*
Y911512D03*
X1445806D03*
X1449507D03*
X1447657Y908324D03*
X1440255D03*
X1451357D03*
X1440255Y914701D03*
X1443956D03*
X1447657D03*
X1442106Y917890D03*
X1443956Y921079D03*
X1442106Y924268D03*
X1451357Y914701D03*
X1453208Y917890D03*
Y924268D03*
X1445806Y917890D03*
Y924268D03*
X1449507Y917890D03*
Y924268D03*
X1447657Y921079D03*
X1440255D03*
X1451357D03*
X1440255Y927457D03*
X1443956D03*
X1447657D03*
X1440255Y933835D03*
X1443956D03*
X1442106Y937024D03*
X1443956Y940213D03*
X1453208Y930646D03*
X1451357Y927457D03*
X1445806Y930646D03*
X1449507D03*
X1447657Y940213D03*
X1440255D03*
X1451357D03*
X1442106Y930646D03*
X1453208Y937024D03*
X1445806D03*
X1451357Y933835D03*
X1447657D03*
X1449507Y937024D03*
Y949780D03*
Y943402D03*
Y956158D03*
X1445806Y949780D03*
Y943402D03*
Y956158D03*
X1447657Y946591D03*
X1442106Y943402D03*
X1440255Y946591D03*
X1442106Y949780D03*
X1443956Y946591D03*
Y952969D03*
X1442106Y956158D03*
X1451357Y946591D03*
X1453208Y943402D03*
Y949780D03*
Y956158D03*
X1447657Y952969D03*
X1440255D03*
X1451357D03*
X1440255Y959347D03*
X1443956D03*
X1447657D03*
X1443956Y965725D03*
X1442106Y962536D03*
Y968914D03*
X1451357Y959347D03*
X1453208Y962536D03*
Y968914D03*
X1449507D03*
Y962536D03*
X1445806Y968914D03*
Y962536D03*
X1440255Y965725D03*
X1447657D03*
X1451357D03*
X1445806Y981670D03*
X1443956Y978481D03*
Y972103D03*
X1447657D03*
X1442106Y975292D03*
X1440255Y972103D03*
X1443956Y984859D03*
X1453208Y981670D03*
X1451357Y972103D03*
X1453208Y975292D03*
X1451357Y984859D03*
X1449507Y975292D03*
X1445806D03*
X1440255Y978481D03*
X1447657D03*
X1442106Y981670D03*
X1449507D03*
X1447657Y984859D03*
X1440255D03*
X1451357Y978481D03*
X1445806Y988048D03*
X1443956Y991237D03*
X1453208Y988048D03*
Y994426D03*
X1451357Y991237D03*
X1453208Y1000804D03*
X1443968Y997607D03*
X1449507Y988048D03*
X1440268Y997607D03*
X1447669D03*
X1442106Y988048D03*
X1440255Y991237D03*
X1447657D03*
X1453208Y1007182D03*
X1452542Y1040819D03*
X1445149D03*
X1441449D03*
X1448850D03*
X1450688Y1063134D03*
X1446987D03*
X1445137Y1047189D03*
X1446987Y1056756D03*
X1445137Y1059945D03*
X1439586Y1056756D03*
X1445137Y1053567D03*
X1439586Y1050378D03*
X1446987D03*
X1452539Y1047189D03*
Y1053567D03*
X1441436Y1047189D03*
X1448838D03*
X1450688Y1050378D03*
Y1056756D03*
X1441436Y1059945D03*
Y1053567D03*
X1443287Y1056756D03*
X1448838Y1053567D03*
X1443287Y1050378D03*
X1448838Y1059945D03*
X1452539D03*
X1450688Y1069512D03*
X1446987D03*
X1450688Y1075890D03*
X1446987D03*
X1443287Y1063134D03*
X1445137Y1072701D03*
X1443287Y1069512D03*
X1448838Y1066323D03*
X1445137D03*
X1441436D03*
X1452539D03*
X1439586Y1063134D03*
Y1069512D03*
X1450688Y1063134D03*
Y1069512D03*
X1446987Y1063134D03*
Y1069512D03*
X1441436Y1072701D03*
X1448838D03*
X1452539D03*
X1450688Y1082268D03*
X1446987D03*
X1450688Y1088646D03*
X1446987D03*
X1445137Y1079079D03*
X1448838D03*
X1441436D03*
X1443287Y1075890D03*
Y1088646D03*
X1445137Y1085457D03*
X1443287Y1082268D03*
X1452539Y1079079D03*
X1439586Y1075890D03*
X1450688D03*
X1446987D03*
X1439586Y1088646D03*
X1450688Y1082268D03*
X1446987D03*
X1448838Y1085457D03*
X1441436D03*
X1452539D03*
X1439586Y1082268D03*
X1450688Y1088646D03*
X1446987D03*
X1450688Y1095024D03*
X1446987D03*
X1441436Y1091835D03*
X1448838D03*
X1445137D03*
X1443287Y1095024D03*
X1445137Y1104591D03*
X1443287Y1101402D03*
X1445137Y1098213D03*
X1441436Y1104591D03*
X1452539Y1091835D03*
X1439586Y1101402D03*
Y1095024D03*
X1448838Y1098213D03*
X1441436D03*
X1452539D03*
X1448838Y1104591D03*
X1452539D03*
X1446987Y1101402D03*
X1450688D03*
Y1095024D03*
X1446987D03*
X1441436Y1110969D03*
X1448838D03*
X1445137D03*
X1443287Y1107780D03*
X1445137Y1117347D03*
X1443287Y1114158D03*
X1452539Y1110969D03*
X1446987Y1114158D03*
X1439586D03*
X1450688D03*
Y1107780D03*
X1446987D03*
X1439586D03*
X1448838Y1117347D03*
X1441436D03*
X1452539D03*
X1445137Y1123725D03*
X1448838D03*
X1443287Y1120536D03*
X1441436Y1123725D03*
X1443287Y1126914D03*
Y1133292D03*
X1445137Y1130102D03*
X1452539Y1123725D03*
X1446987Y1126914D03*
Y1120536D03*
X1439586Y1126914D03*
Y1120536D03*
X1450688Y1126914D03*
Y1120536D03*
X1446987Y1133292D03*
X1450688D03*
X1448838Y1130102D03*
X1441436D03*
X1452539Y1130103D03*
X1439586Y1133292D03*
X1448838Y1149236D03*
X1443287Y1146047D03*
X1441436Y1149236D03*
X1452539Y1136480D03*
Y1149236D03*
X1445137Y1142858D03*
X1443287Y1139669D03*
X1445137Y1136480D03*
X1448838D03*
X1441436D03*
X1446987Y1139669D03*
X1450688D03*
X1446987Y1146047D03*
X1439586D03*
Y1139669D03*
X1450688Y1146047D03*
X1448838Y1142858D03*
X1441436D03*
X1445137Y1149236D03*
X1452539Y1142858D03*
X1446987Y1152425D03*
X1443287Y1165181D03*
X1439586Y1158803D03*
X1446987D03*
X1450688Y1152425D03*
X1441436Y1155614D03*
X1443287Y1152425D03*
X1452539Y1161992D03*
X1441436D03*
X1445137D03*
X1448838Y1155614D03*
X1439586Y1152425D03*
X1445137Y1155614D03*
X1443287Y1158803D03*
X1450627Y1540509D03*
X1452827D03*
X1450792Y1546218D03*
X1449133Y1551121D03*
X1449626Y1556810D03*
Y1561725D03*
X1449534Y1554612D03*
X1449580Y1568698D03*
Y1570898D03*
X1451027Y1573317D03*
X1456909Y873245D03*
Y879623D03*
X1458759Y876434D03*
X1468011Y879623D03*
X1462460Y876434D03*
X1455058D03*
X1466161D03*
X1464310Y873245D03*
X1460609D03*
Y879623D03*
X1464310D03*
X1468011Y892379D03*
X1456909D03*
X1460609D03*
X1455058Y882812D03*
X1462460D03*
X1466161D03*
X1458759D03*
Y889190D03*
X1455058Y895568D03*
X1464310Y892379D03*
X1466161Y895568D03*
X1462460Y889190D03*
X1464310Y886001D03*
X1458759Y895568D03*
X1462460D03*
X1466161Y889190D03*
X1455058D03*
X1460609Y886001D03*
X1456909D03*
X1468011D03*
Y911512D03*
Y898757D03*
Y905134D03*
X1456909Y898757D03*
Y905134D03*
X1460609Y898757D03*
Y905134D03*
X1464310Y898757D03*
X1455058Y901946D03*
X1458759D03*
X1466161D03*
X1462460D03*
X1464310Y905134D03*
X1455058Y908324D03*
X1464310Y911512D03*
X1466161Y908323D03*
X1456909Y911512D03*
X1460609D03*
X1458759Y908324D03*
X1462460D03*
X1458759Y914701D03*
X1464310Y917890D03*
Y924268D03*
X1455058Y921079D03*
X1466161D03*
X1455058Y914701D03*
X1462460D03*
X1466161D03*
X1468011Y924268D03*
Y917890D03*
X1456909Y924268D03*
Y917890D03*
X1460609Y924268D03*
Y917890D03*
X1458759Y921079D03*
X1462460D03*
X1455058Y927457D03*
X1458759D03*
X1466161D03*
X1462460D03*
X1455058Y933835D03*
X1464310Y930646D03*
X1462460Y933835D03*
X1466161D03*
X1458759D03*
X1455058Y940213D03*
X1466161D03*
X1468011Y930646D03*
X1456909D03*
X1460609D03*
X1462460Y940213D03*
X1458759D03*
X1456909Y937024D03*
X1464310D03*
X1460609D03*
X1468011D03*
X1460609Y949780D03*
Y943402D03*
Y956158D03*
X1468011Y949780D03*
Y943402D03*
Y956158D03*
X1456909Y949780D03*
Y943402D03*
Y956158D03*
X1462460Y946591D03*
X1466161D03*
X1458759D03*
X1466161Y952969D03*
X1464310Y956158D03*
X1455058Y952969D03*
X1464310Y943402D03*
X1455058Y946591D03*
X1464310Y949780D03*
X1458759Y952969D03*
X1462460D03*
X1455058Y965725D03*
X1466161D03*
X1455058Y959347D03*
X1462460D03*
X1466161D03*
X1458759D03*
X1464310Y962536D03*
Y968914D03*
X1460609D03*
Y962536D03*
X1468011Y968914D03*
Y962536D03*
X1456909Y968914D03*
Y962536D03*
X1462460Y965725D03*
X1458759D03*
X1460609Y981670D03*
X1455058Y978481D03*
X1466161D03*
X1455058Y972103D03*
X1462460D03*
X1466161D03*
X1458759D03*
X1464310Y975292D03*
X1458759Y984859D03*
X1466161D03*
X1468011Y981670D03*
X1460609Y975292D03*
X1468011D03*
X1456909D03*
X1462460Y978481D03*
X1458759D03*
X1464310Y981670D03*
X1456909D03*
X1462460Y984859D03*
X1455058D03*
X1458759Y997615D03*
X1466161D03*
X1460609Y988048D03*
Y994426D03*
X1458759Y991237D03*
X1466161D03*
X1460609Y1000804D03*
X1468011Y988048D03*
Y994426D03*
Y1000804D03*
X1464310Y988048D03*
Y994426D03*
X1456909Y988048D03*
Y994426D03*
X1462460Y997615D03*
Y991237D03*
X1455058Y997615D03*
Y991237D03*
X1456909Y1000804D03*
X1464310D03*
X1458759Y1003993D03*
X1466161D03*
Y1010371D03*
X1458759D03*
X1460609Y1007182D03*
X1468011D03*
X1464310D03*
X1456909D03*
X1462460Y1010371D03*
Y1003993D03*
X1455058Y1010371D03*
Y1003993D03*
X1463641Y1028055D03*
X1456239D03*
X1459940D03*
X1467342D03*
X1459940Y1040811D03*
X1458090Y1031244D03*
X1463641Y1034433D03*
X1456239D03*
X1465491Y1031244D03*
X1454389Y1037622D03*
X1467342Y1040811D03*
X1454389Y1044000D03*
X1461791Y1037622D03*
Y1044000D03*
X1458090Y1037622D03*
Y1044000D03*
X1465491Y1037622D03*
Y1044000D03*
X1463641Y1040811D03*
X1456239D03*
X1459940Y1034433D03*
X1461791Y1031244D03*
X1454389D03*
X1467342Y1034433D03*
X1461791Y1063134D03*
X1458090D03*
X1469192D03*
X1459940Y1047189D03*
X1456239Y1059945D03*
X1459940Y1053567D03*
X1454389Y1056756D03*
X1461791D03*
X1454389Y1050378D03*
X1461791D03*
X1467342Y1047189D03*
Y1059945D03*
Y1053567D03*
X1463641Y1047189D03*
X1456239D03*
X1465491Y1050378D03*
X1456239Y1053567D03*
X1463641D03*
X1458090Y1056756D03*
X1463641Y1059945D03*
X1465491Y1056756D03*
X1458090Y1050378D03*
X1459940Y1059945D03*
X1461791Y1069512D03*
X1458090D03*
X1469192D03*
Y1075890D03*
X1461791D03*
X1458090D03*
X1465491Y1063134D03*
X1454389D03*
X1456239Y1072701D03*
X1459940Y1066323D03*
X1463641D03*
X1465491Y1069512D03*
X1454389D03*
X1456239Y1066323D03*
X1467342Y1072701D03*
Y1066323D03*
X1461791Y1063134D03*
Y1069512D03*
X1458090Y1063134D03*
Y1069512D03*
X1463641Y1072701D03*
X1459940D03*
X1469192Y1082268D03*
Y1088646D03*
X1461791Y1082268D03*
Y1088646D03*
X1458090Y1082268D03*
Y1088646D03*
X1459940Y1079079D03*
X1463641D03*
X1456239D03*
X1465491Y1075890D03*
X1454389D03*
X1465491Y1088646D03*
X1454389D03*
X1456239Y1085457D03*
X1465491Y1082268D03*
X1454389D03*
X1467342Y1079079D03*
Y1085457D03*
X1461791Y1075890D03*
X1458090D03*
X1463641Y1085457D03*
X1459940D03*
X1461791Y1082268D03*
Y1088646D03*
X1458090Y1082268D03*
Y1088646D03*
X1461791Y1095024D03*
X1458090D03*
X1469192D03*
X1456239Y1098213D03*
X1467342Y1091835D03*
Y1104591D03*
Y1098213D03*
X1463641Y1091835D03*
X1459940D03*
X1456239D03*
X1465491Y1095024D03*
X1454389D03*
X1459940Y1104591D03*
X1463641D03*
X1456239D03*
X1463641Y1098213D03*
X1459940D03*
X1454389Y1101402D03*
X1461791D03*
X1458090D03*
X1465491D03*
X1461791Y1095024D03*
X1458090D03*
X1465491Y1107780D03*
X1454389D03*
X1463641Y1110969D03*
X1459940D03*
X1456239D03*
Y1117347D03*
X1454389Y1114158D03*
X1465491D03*
X1467342Y1110969D03*
Y1117347D03*
X1458090Y1114158D03*
Y1107780D03*
X1461791Y1114158D03*
Y1107780D03*
X1459940Y1117347D03*
X1463641D03*
X1454389Y1120536D03*
X1465491Y1126914D03*
X1454389D03*
X1459940Y1123725D03*
X1463641D03*
X1465491Y1120536D03*
X1456239Y1123725D03*
X1454389Y1133292D03*
X1456239Y1130102D03*
X1465491Y1133292D03*
X1467342Y1123725D03*
Y1130102D03*
X1458090Y1133292D03*
X1461791D03*
X1458090Y1126914D03*
Y1120536D03*
X1461791Y1126914D03*
Y1120536D03*
X1459940Y1130102D03*
X1463641D03*
X1456239Y1142858D03*
X1465491Y1139669D03*
X1459940Y1136480D03*
X1463641D03*
X1454389Y1139669D03*
X1456239Y1136480D03*
X1465491Y1146047D03*
X1459940Y1149236D03*
X1463641D03*
X1454389Y1146047D03*
X1467342Y1136480D03*
Y1142858D03*
X1458090Y1146047D03*
Y1139669D03*
X1461791Y1146047D03*
Y1139669D03*
X1463641Y1142858D03*
X1459940D03*
X1456239Y1149236D03*
X1467342D03*
X1454389Y1158803D03*
X1467342Y1155614D03*
X1465491Y1158803D03*
X1463641Y1155614D03*
X1461791Y1152425D03*
X1458090Y1158803D03*
X1459940Y1155614D03*
X1465491Y1152425D03*
X1454389D03*
X1467342Y1161992D03*
X1463641D03*
X1456239D03*
X1461791Y1165181D03*
X1458090Y1152425D03*
X1461791Y1158803D03*
X1456239Y1155614D03*
X1454994Y1540512D03*
X1458907Y1547243D03*
X1460301Y1540295D03*
X1463631Y1547243D03*
X1465026Y1540295D03*
X1468356Y1547243D03*
X1457735Y1552195D03*
X1461777Y1552698D03*
X1460202Y1549970D03*
X1464926D03*
X1466501Y1552698D03*
X1468026Y1554453D03*
X1463301D03*
X1458577D03*
X1468577Y1561853D03*
X1463852D03*
X1459128D03*
X1460202Y1563608D03*
X1464926D03*
X1461777Y1566336D03*
X1466501D03*
X1458577Y1556953D03*
X1468577Y1559353D03*
X1463852D03*
X1459128D03*
X1463301Y1556953D03*
X1468026D03*
X1455098Y1575425D03*
X1468076Y1569063D03*
X1463351D03*
X1460301Y1575641D03*
X1458626Y1569063D03*
X1465026Y1575641D03*
X1455098Y1577625D03*
X1458013Y1625380D03*
X1465813D03*
X1464053Y1635380D03*
Y1647292D03*
X1465813Y1657292D03*
X1458013D03*
X1475413Y879623D03*
X1479113Y873245D03*
X1469861Y876434D03*
X1479113Y879623D03*
X1482814D03*
X1473562Y876434D03*
X1477263D03*
X1471712Y873245D03*
X1475413D03*
X1480964Y876434D03*
X1471712Y892379D03*
X1482814Y886001D03*
X1480964Y882812D03*
X1469861D03*
X1479113Y886001D03*
X1482814Y892379D03*
X1469861Y889190D03*
X1473562D03*
X1475413Y892379D03*
X1477263Y895568D03*
X1480964Y889190D03*
X1479113Y892379D03*
X1480964Y895568D03*
X1475413Y886001D03*
X1477263Y889190D03*
X1473562Y895568D03*
X1469861D03*
X1471712Y886001D03*
Y911512D03*
Y898757D03*
Y905134D03*
X1482814Y898757D03*
X1469861Y901946D03*
X1475413Y898757D03*
X1473562Y901946D03*
X1482814Y905134D03*
Y911512D03*
X1477263Y908324D03*
X1475413Y911512D03*
Y905134D03*
X1479113Y911512D03*
X1480964Y901946D03*
X1479113Y905134D03*
X1480964Y908324D03*
X1479113Y898757D03*
X1469861Y908324D03*
X1473562D03*
X1477263Y901946D03*
X1482814Y917890D03*
X1469861Y914701D03*
X1473562D03*
X1475413Y917890D03*
Y924268D03*
X1482814D03*
X1477263Y921079D03*
X1480964D03*
X1479113Y924268D03*
X1480964Y914701D03*
X1479113Y917890D03*
X1471712Y924268D03*
Y917890D03*
X1473562Y921079D03*
X1469861D03*
X1477263Y914701D03*
X1469861Y933835D03*
X1473562D03*
X1482814Y930646D03*
X1475413D03*
X1477263Y933835D03*
X1473562Y927457D03*
X1469861D03*
X1482814Y937024D03*
X1477263Y940213D03*
X1480964Y927457D03*
X1479113Y930646D03*
X1480964Y940213D03*
Y933835D03*
X1479113Y937024D03*
X1471712Y930646D03*
X1469861Y940213D03*
X1473562D03*
X1477263Y927457D03*
X1475413Y937024D03*
X1471712D03*
Y949780D03*
Y943402D03*
Y956158D03*
X1482814Y943402D03*
Y949780D03*
X1475413Y943402D03*
X1469861Y946591D03*
X1473562D03*
X1475413Y949780D03*
X1482814Y956158D03*
X1477263Y952969D03*
X1475413Y956158D03*
X1479113Y943402D03*
X1480964Y946591D03*
X1479113Y949780D03*
X1480964Y952969D03*
X1479113Y956158D03*
X1473562Y952969D03*
X1469861D03*
X1477263Y946591D03*
X1482814Y962536D03*
X1469861Y959347D03*
X1473562D03*
X1475413Y962536D03*
X1477263Y965725D03*
X1482814Y968914D03*
X1475413D03*
X1480964Y965725D03*
X1479113Y968914D03*
X1480964Y959347D03*
X1479113Y962536D03*
X1471712Y968914D03*
Y962536D03*
X1473562Y965725D03*
X1469861D03*
X1477263Y959347D03*
X1482814Y975292D03*
Y981670D03*
X1469861Y972103D03*
X1473562D03*
X1475413Y975292D03*
X1477263Y978481D03*
X1475413Y981670D03*
X1473562Y984859D03*
X1480964D03*
Y978481D03*
X1479113Y981670D03*
X1480964Y972103D03*
X1479113Y975292D03*
X1471712D03*
Y981670D03*
X1473562Y978481D03*
X1469861D03*
Y984859D03*
X1477263Y972103D03*
Y984859D03*
X1475413Y1000804D03*
X1482814Y988048D03*
Y994426D03*
X1473562Y991237D03*
Y997615D03*
X1475413Y988048D03*
Y994426D03*
X1482814Y1000804D03*
X1479113Y988048D03*
X1480964Y997615D03*
X1479113Y1000804D03*
X1480964Y991237D03*
X1477263D03*
X1469861Y997615D03*
Y991237D03*
X1471712Y988048D03*
Y994426D03*
X1477263Y997615D03*
X1471712Y1000804D03*
X1479113Y994426D03*
X1482814Y1007182D03*
X1473562Y1003993D03*
Y1010371D03*
X1475413Y1007182D03*
X1480964Y1003993D03*
X1479113Y1007182D03*
X1471712D03*
X1477263Y1010371D03*
Y1003993D03*
X1469861Y1010371D03*
Y1003993D03*
X1480964Y1010371D03*
X1478444Y1028055D03*
X1471043D03*
X1474743D03*
X1482145D03*
X1472893Y1031244D03*
X1469192Y1037622D03*
Y1044000D03*
X1478444Y1034433D03*
X1476594Y1037622D03*
X1474743Y1040811D03*
X1476594Y1044000D03*
X1471043Y1034433D03*
X1480295Y1031244D03*
X1482145Y1034433D03*
X1480295Y1037622D03*
X1482145Y1040811D03*
X1480295Y1044000D03*
X1478444Y1040811D03*
X1471043D03*
X1472893Y1037622D03*
Y1044000D03*
X1474743Y1034433D03*
X1476594Y1031244D03*
X1469192D03*
X1472893Y1063134D03*
X1474743Y1047189D03*
X1480295Y1056756D03*
X1482145Y1059945D03*
X1469192Y1050378D03*
X1476594D03*
Y1056756D03*
X1474743Y1053567D03*
X1478444Y1059945D03*
X1469192Y1056756D03*
X1480295Y1050378D03*
X1482145Y1047189D03*
X1472893Y1050378D03*
X1478444Y1047189D03*
X1471043D03*
X1478444Y1053567D03*
X1472893Y1056756D03*
X1471043Y1053567D03*
X1474743Y1059945D03*
X1471043D03*
X1482145Y1053567D03*
X1472893Y1069512D03*
Y1075890D03*
X1476594Y1063134D03*
X1478444Y1072701D03*
X1476594Y1069512D03*
X1474743Y1066323D03*
X1471043D03*
X1480295Y1063134D03*
X1482145Y1066323D03*
X1480295Y1069512D03*
X1482145Y1072701D03*
X1472893Y1063134D03*
Y1069512D03*
X1469192Y1063134D03*
Y1069512D03*
X1478444Y1066323D03*
X1471043Y1072701D03*
X1474743D03*
X1472893Y1082268D03*
Y1088646D03*
X1476594Y1075890D03*
X1474743Y1079079D03*
X1471043D03*
X1478444Y1085457D03*
X1476594Y1088646D03*
Y1082268D03*
X1480295Y1075890D03*
X1482145Y1079079D03*
X1480295Y1082268D03*
X1482145Y1085457D03*
X1480295Y1088646D03*
X1472893Y1075890D03*
X1469192D03*
X1478444Y1079079D03*
X1474743Y1085457D03*
X1471043D03*
X1472893Y1082268D03*
Y1088646D03*
X1469192Y1082268D03*
Y1088646D03*
X1472893Y1095024D03*
X1474743Y1091835D03*
X1471043D03*
X1476594Y1095024D03*
X1478444Y1098213D03*
Y1104591D03*
X1474743D03*
X1471043D03*
X1472893Y1101402D03*
X1482145Y1104591D03*
X1480295Y1095024D03*
X1482145Y1098213D03*
X1480295Y1101402D03*
X1482145Y1091835D03*
X1478444D03*
X1476594Y1101402D03*
X1474743Y1098213D03*
X1471043D03*
X1469192Y1101402D03*
X1472893Y1095024D03*
X1469192D03*
X1476594Y1107780D03*
X1474743Y1110969D03*
X1471043D03*
X1476594Y1114158D03*
X1478444Y1117347D03*
X1480295Y1114158D03*
X1482145Y1117347D03*
X1480295Y1107780D03*
X1482145Y1110969D03*
X1469192Y1107780D03*
Y1114158D03*
X1472893Y1107780D03*
Y1114158D03*
X1478444Y1110969D03*
X1474743Y1117347D03*
X1471043D03*
X1476594Y1126914D03*
Y1120536D03*
X1474743Y1123725D03*
X1471043D03*
X1478444Y1130102D03*
X1476594Y1133292D03*
X1480295Y1120536D03*
X1482145Y1123725D03*
X1480295Y1133292D03*
Y1126914D03*
X1482145Y1130102D03*
X1469192Y1120536D03*
X1472893D03*
X1478444Y1123725D03*
X1474743Y1130102D03*
X1471043D03*
X1469192Y1133292D03*
Y1126914D03*
X1472893Y1133292D03*
Y1126914D03*
X1476594Y1139669D03*
X1474743Y1136480D03*
X1471043D03*
X1478444Y1142858D03*
X1476594Y1146047D03*
X1474743Y1149236D03*
X1471043D03*
X1482145Y1136480D03*
X1480295Y1139669D03*
X1482145Y1142858D03*
X1480295Y1146047D03*
X1482145Y1149236D03*
X1478444Y1136480D03*
X1474743Y1142858D03*
X1471043D03*
X1478444Y1149236D03*
X1469192Y1146047D03*
Y1139669D03*
X1472893Y1146047D03*
Y1139669D03*
Y1158803D03*
X1471043Y1155614D03*
Y1161992D03*
X1469192Y1152425D03*
X1474743Y1155614D03*
X1478444D03*
X1472893Y1152425D03*
X1480295Y1158803D03*
X1469192D03*
X1480295Y1152425D03*
X1482145Y1155614D03*
X1476594Y1152425D03*
X1478444Y1161992D03*
X1474743D03*
X1476594Y1158803D03*
X1476778Y1165778D03*
X1469750Y1540295D03*
X1473080Y1547243D03*
X1474474Y1540295D03*
X1477805Y1547243D03*
X1479199Y1540295D03*
X1482529Y1547243D03*
X1483923Y1540295D03*
X1479099Y1549970D03*
X1483824D03*
X1480674Y1552698D03*
X1469651Y1549970D03*
X1474375D03*
X1471225Y1552698D03*
X1475950D03*
X1482199Y1554453D03*
X1477474D03*
X1472750D03*
X1482750Y1561853D03*
X1478025D03*
X1473301D03*
X1469651Y1563608D03*
X1474375D03*
X1479099D03*
X1483824D03*
X1471225Y1566336D03*
X1475950D03*
X1480674D03*
X1482199Y1556953D03*
X1482750Y1559353D03*
X1472750Y1556953D03*
X1473301Y1559353D03*
X1477474Y1556953D03*
X1478025Y1559353D03*
X1482249Y1569063D03*
X1477525D03*
X1469750Y1575641D03*
X1483923D03*
X1474474D03*
X1472800Y1569063D03*
X1479199Y1575641D03*
X1470073Y1625380D03*
X1482133D03*
X1477873D03*
X1471833Y1635380D03*
X1483893D03*
X1476113D03*
X1471833Y1647292D03*
X1483893D03*
X1476113D03*
X1470073Y1657292D03*
X1477873D03*
X1482133D03*
X1486515Y879623D03*
X1492066Y876434D03*
X1490216Y879623D03*
X1484665Y876434D03*
X1488365D03*
X1490216Y886001D03*
X1484665Y882812D03*
X1488365D03*
X1495767D03*
X1493917Y886001D03*
X1488365Y889190D03*
X1495767D03*
X1490216Y892379D03*
X1495767Y895568D03*
X1486515Y886001D03*
X1484665Y889190D03*
Y895568D03*
X1486515Y892379D03*
X1497617Y886001D03*
X1492066Y889190D03*
X1493917Y892379D03*
X1492066Y895568D03*
X1497617Y892379D03*
X1488365Y895568D03*
X1492066Y882812D03*
X1490216Y898757D03*
X1488365Y901946D03*
X1495767D03*
X1488365Y908324D03*
X1490216Y911512D03*
X1495767Y908324D03*
X1484665D03*
X1486515Y898757D03*
X1484665Y901946D03*
X1486515Y905134D03*
Y911512D03*
X1493917D03*
X1497617Y898757D03*
X1492066Y901946D03*
X1493917Y905134D03*
X1497617D03*
X1492066Y908324D03*
X1497617Y911512D03*
X1493917Y898757D03*
X1490216Y905134D03*
X1495767Y914701D03*
X1490216Y917890D03*
X1488365Y921079D03*
X1495767D03*
X1486515Y917890D03*
X1484665Y921079D03*
X1486515Y924268D03*
X1484665Y914701D03*
X1497617Y917890D03*
X1492066Y921079D03*
X1493917Y924268D03*
X1497617D03*
X1492066Y914701D03*
X1493917Y917890D03*
X1488365Y914701D03*
X1490216Y924268D03*
Y930646D03*
X1495767Y933835D03*
X1488365Y927457D03*
X1495767D03*
X1488365Y940213D03*
X1495767D03*
X1490216Y937024D03*
X1484665Y927457D03*
X1486515Y937024D03*
X1484665Y940213D03*
Y933835D03*
X1486515Y930646D03*
X1492066Y927457D03*
X1493917Y930646D03*
X1497617Y937024D03*
X1492066Y940213D03*
Y933835D03*
X1497617Y930646D03*
X1493917Y937024D03*
X1488365Y933835D03*
Y946591D03*
X1490216Y949780D03*
X1495767Y946591D03*
Y952969D03*
X1490216Y956158D03*
X1486515Y943402D03*
X1484665Y946591D03*
X1486515Y956158D03*
X1484665Y952969D03*
X1486515Y949780D03*
X1493917Y943402D03*
X1497617D03*
X1492066Y946591D03*
X1493917Y949780D03*
X1497617Y956158D03*
X1492066Y952969D03*
X1497617Y949780D03*
X1493917Y956158D03*
X1490216Y943402D03*
X1488365Y952969D03*
Y965725D03*
X1495767Y959347D03*
Y965725D03*
X1488365Y959347D03*
X1490216Y968914D03*
X1486515Y962536D03*
X1484665Y965725D03*
Y959347D03*
X1486515Y968914D03*
X1497617Y962536D03*
X1492066Y965725D03*
X1493917Y968914D03*
X1492066Y959347D03*
X1493917Y962536D03*
X1497617Y968914D03*
X1490216Y962536D03*
X1495767Y972103D03*
X1490216Y975292D03*
X1486515Y981670D03*
X1488365Y978481D03*
X1495767D03*
X1497617Y981670D03*
X1484665Y984859D03*
X1488365D03*
X1495767D03*
X1486515Y975292D03*
X1484665Y978481D03*
Y972103D03*
X1492066Y984859D03*
X1497617Y975292D03*
X1492066Y978481D03*
X1493917Y981670D03*
X1492066Y972103D03*
X1493917Y975292D03*
X1490216Y981670D03*
X1488365Y972103D03*
X1490216Y988048D03*
X1488365Y997615D03*
X1490216Y994426D03*
X1495767Y991237D03*
Y997615D03*
X1486515Y994426D03*
X1484665Y997615D03*
X1486515Y1000804D03*
Y988048D03*
X1493917D03*
X1497617Y994426D03*
X1492066Y997615D03*
X1493917Y1000804D03*
X1497617D03*
Y988048D03*
X1492066Y991237D03*
X1488365D03*
X1490216Y1000804D03*
X1493917Y994426D03*
X1484665Y991237D03*
X1488365Y1003993D03*
X1490216Y1007182D03*
X1495767Y1003993D03*
Y1010371D03*
X1484665D03*
X1486515Y1007182D03*
X1484665Y1003993D03*
X1497617Y1007182D03*
X1492066Y1003993D03*
X1493917Y1007182D03*
X1488365Y1010371D03*
X1492066D03*
X1489547Y1028055D03*
X1496948D03*
X1493247D03*
X1485846D03*
X1483995Y1031244D03*
Y1037622D03*
Y1044000D03*
X1491397Y1031244D03*
X1489547Y1040811D03*
Y1034433D03*
X1491397Y1044000D03*
X1496948Y1034433D03*
Y1040811D03*
X1485846Y1034433D03*
X1487696Y1037622D03*
X1485846Y1040811D03*
X1495098Y1031244D03*
X1493247Y1034433D03*
X1498799Y1037622D03*
X1495098D03*
X1493247Y1040811D03*
X1495098Y1044000D03*
X1491397Y1037622D03*
X1498798Y1044000D03*
Y1031244D03*
X1487696Y1044000D03*
Y1031244D03*
X1496948Y1047189D03*
X1483995Y1050378D03*
Y1056756D03*
X1489547Y1053567D03*
X1495098Y1056756D03*
X1491397Y1050378D03*
X1489547Y1059945D03*
X1493247D03*
X1496948Y1053567D03*
Y1059945D03*
X1485846D03*
X1487696Y1050378D03*
X1485846Y1053567D03*
X1495098Y1050378D03*
X1493247Y1047189D03*
X1498799Y1050378D03*
X1489547Y1047189D03*
X1491397Y1056756D03*
X1498798D03*
X1493247Y1053567D03*
X1487696Y1056756D03*
X1485846Y1047189D03*
X1483995Y1063134D03*
X1491397D03*
X1483995Y1069512D03*
X1489547Y1072701D03*
X1491397Y1069512D03*
X1496948Y1072701D03*
Y1066323D03*
X1485846Y1072701D03*
X1487696Y1063134D03*
Y1069512D03*
X1485846Y1066323D03*
X1495098Y1063134D03*
X1498799D03*
X1493247Y1066323D03*
X1495098Y1069512D03*
X1498799D03*
X1493247Y1072701D03*
X1489547Y1066323D03*
X1483995Y1075890D03*
X1489547Y1079079D03*
X1496948D03*
X1483995Y1088646D03*
X1491397D03*
X1496948Y1085457D03*
X1483995Y1082268D03*
X1491397D03*
X1487696Y1075890D03*
X1485846Y1079079D03*
X1487696Y1082268D03*
Y1088646D03*
X1485846Y1085457D03*
X1495098Y1075890D03*
X1498799D03*
X1493247Y1079079D03*
X1495098Y1082268D03*
X1498799D03*
X1493247Y1085457D03*
X1498799Y1088646D03*
X1495098D03*
X1491397Y1075890D03*
X1489547Y1085457D03*
Y1091835D03*
X1496948D03*
X1483995Y1095024D03*
Y1101402D03*
X1489547Y1098213D03*
X1491397Y1101402D03*
X1496948Y1098213D03*
Y1104591D03*
X1487696Y1101402D03*
X1485846Y1091835D03*
X1487696Y1095024D03*
X1485846Y1098213D03*
Y1104591D03*
X1498799Y1101402D03*
X1493247Y1104591D03*
X1495098Y1095024D03*
X1498799D03*
X1493247Y1098213D03*
X1495098Y1101402D03*
X1493247Y1091835D03*
X1491397Y1095024D03*
X1489547Y1104591D03*
Y1110969D03*
X1496948D03*
X1483995Y1107780D03*
X1491397D03*
X1483995Y1114158D03*
X1489547Y1117347D03*
X1496948D03*
X1485846Y1110969D03*
X1487696Y1114158D03*
X1485846Y1117347D03*
X1487696Y1107780D03*
X1495098Y1114158D03*
X1498799D03*
X1493247Y1117347D03*
X1498799Y1107780D03*
X1495098D03*
X1493247Y1110969D03*
X1491397Y1114158D03*
X1483995Y1120536D03*
X1491397D03*
X1496948Y1123725D03*
X1483995Y1126914D03*
X1491397D03*
X1483995Y1133292D03*
X1496948Y1130102D03*
X1489547Y1130103D03*
X1487696Y1120536D03*
X1485846Y1130102D03*
X1487696Y1133292D03*
Y1126914D03*
X1485846Y1123725D03*
X1495098Y1120536D03*
X1498799D03*
X1493247Y1123725D03*
X1495098Y1133292D03*
X1498799D03*
Y1126914D03*
X1495098D03*
X1493247Y1130102D03*
X1491397Y1133292D03*
X1489547Y1123725D03*
X1483995Y1139669D03*
X1489547Y1136480D03*
X1491397Y1139669D03*
X1496948Y1136480D03*
Y1142858D03*
X1483995Y1146047D03*
X1489547Y1149236D03*
X1491397Y1146047D03*
X1496948Y1149236D03*
X1485846Y1136480D03*
X1487696Y1139669D03*
X1485846Y1149236D03*
X1487696Y1146047D03*
X1485846Y1142858D03*
X1493247Y1136480D03*
X1495098Y1139669D03*
X1498799D03*
X1493247Y1142858D03*
X1498799Y1146047D03*
X1495098D03*
X1493247Y1149236D03*
X1489547Y1142858D03*
X1487696Y1165181D03*
X1498799Y1158803D03*
X1483995Y1152425D03*
X1485846Y1155614D03*
X1489547D03*
X1493247D03*
X1496948D03*
X1483995Y1158803D03*
X1491397D03*
X1493247Y1161992D03*
X1487696Y1152425D03*
X1495098D03*
X1498799D03*
X1491397D03*
X1489547Y1161992D03*
X1485846D03*
X1487696Y1158803D03*
X1495111Y1165289D03*
X1491410D03*
X1498812D03*
X1488648Y1540295D03*
X1487253Y1547243D03*
X1491978D03*
X1493372Y1540295D03*
X1496702Y1547243D03*
X1498096Y1540295D03*
X1497997Y1549970D03*
X1488548D03*
X1493273D03*
X1485399Y1552698D03*
X1490123D03*
X1494847D03*
X1496372Y1554453D03*
X1491648D03*
X1486923D03*
X1496923Y1561853D03*
X1492199D03*
X1487474D03*
X1488548Y1563608D03*
X1493273D03*
X1497997D03*
X1485399Y1566336D03*
X1490123D03*
X1494847D03*
X1496372Y1556953D03*
X1491648D03*
X1496923Y1559353D03*
X1492199D03*
X1486923Y1556953D03*
X1487474Y1559353D03*
X1491698Y1569063D03*
X1488648Y1575641D03*
X1493372D03*
X1498096D03*
X1496422Y1569063D03*
X1486973D03*
X1489933Y1625380D03*
X1494193D03*
X1495953Y1635380D03*
X1488173D03*
X1495953Y1647292D03*
X1488173D03*
X1494193Y1657292D03*
X1489933D03*
X1501318Y873245D03*
Y879623D03*
X1510570Y876434D03*
X1508720Y879623D03*
X1506869Y876434D03*
X1512421Y879623D03*
X1505019D03*
X1501318Y886001D03*
X1510570Y882812D03*
X1508720Y886001D03*
X1503169Y889190D03*
Y895568D03*
X1501318Y892379D03*
X1508720D03*
X1499468Y882812D03*
X1505019Y886001D03*
X1512421D03*
X1506869Y889190D03*
X1510570D03*
X1505019Y892379D03*
X1510570Y895568D03*
X1506869D03*
X1512421Y892379D03*
X1499468Y889190D03*
Y895568D03*
X1506869Y882812D03*
X1501318Y898757D03*
X1508720D03*
X1503169Y901946D03*
X1501318Y905134D03*
X1508720D03*
X1501318Y911512D03*
X1508720D03*
X1503169Y908323D03*
X1510570Y908324D03*
X1505019Y911512D03*
X1512421Y898757D03*
X1506869Y901946D03*
X1510570D03*
X1505019Y905134D03*
X1512421D03*
X1506869Y908324D03*
X1512421Y911512D03*
X1505019Y898757D03*
X1499468Y908324D03*
Y901946D03*
X1503169Y914701D03*
X1501318Y917890D03*
X1508720D03*
X1503169Y921079D03*
X1501318Y924268D03*
X1508720D03*
X1512421Y917890D03*
X1506869Y921079D03*
X1510570D03*
X1505019Y924268D03*
X1512421D03*
X1510570Y914701D03*
X1506869D03*
X1505019Y917890D03*
X1499468Y921079D03*
Y914701D03*
X1503169Y927457D03*
X1501318Y930646D03*
X1503169Y933835D03*
X1508720Y930646D03*
Y937024D03*
X1503169Y940213D03*
X1501318Y937024D03*
X1506869Y927457D03*
X1510570D03*
X1505019Y930646D03*
X1512421Y937024D03*
X1506869Y940213D03*
X1510570D03*
Y933835D03*
X1506869D03*
X1512421Y930646D03*
X1505019Y937024D03*
X1499468Y927457D03*
Y940213D03*
Y933835D03*
X1501318Y943402D03*
X1508720D03*
X1503169Y946591D03*
X1501318Y949780D03*
X1508720D03*
X1503169Y952969D03*
X1501318Y956158D03*
X1508720D03*
X1505019Y943402D03*
X1512421D03*
X1506869Y946591D03*
X1510570D03*
X1505019Y949780D03*
X1512421Y956158D03*
X1510570Y952969D03*
X1506869D03*
X1512421Y949780D03*
X1505019Y956158D03*
X1499468Y946591D03*
Y952969D03*
X1503169Y959347D03*
Y965725D03*
X1501318Y962536D03*
X1508720D03*
X1501318Y968914D03*
X1508720D03*
X1512421Y962536D03*
X1506869Y965725D03*
X1510570D03*
X1505019Y968914D03*
X1506869Y959347D03*
X1510570D03*
X1505019Y962536D03*
X1512421Y968914D03*
X1499468Y965725D03*
Y959347D03*
X1510570Y984859D03*
X1512421Y981670D03*
X1503169Y972103D03*
X1501318Y975292D03*
X1503169Y978481D03*
X1501318Y981670D03*
X1508720Y975292D03*
Y981670D03*
X1499468Y984859D03*
X1503169D03*
X1506869D03*
X1512421Y975292D03*
X1506869Y978481D03*
X1510570D03*
X1505019Y981670D03*
X1510570Y972103D03*
X1506869D03*
X1505019Y975292D03*
X1499468Y978481D03*
Y972103D03*
X1503169Y991237D03*
X1501318Y988048D03*
X1503169Y997615D03*
X1501318Y994426D03*
X1508720Y988048D03*
Y994426D03*
X1501318Y1000804D03*
X1508720D03*
X1505019Y988048D03*
X1512421Y994426D03*
X1510570Y997615D03*
X1506869D03*
X1505019Y1000804D03*
X1512421D03*
Y988048D03*
X1506869Y991237D03*
X1499468Y997615D03*
Y991237D03*
X1505019Y994426D03*
X1510570Y991237D03*
X1501318Y1007182D03*
X1503169Y1010371D03*
X1508720Y1007182D03*
X1503169Y1003993D03*
X1510570Y1010371D03*
X1512421Y1007182D03*
X1510570Y1003993D03*
X1506869D03*
X1505019Y1007182D03*
X1499468Y1010371D03*
Y1003993D03*
X1506869Y1010371D03*
X1504350Y1028055D03*
X1508050D03*
X1500649D03*
X1511751D03*
X1502499Y1031244D03*
X1509901D03*
X1504350Y1040811D03*
X1502499Y1037622D03*
X1504350Y1034433D03*
X1502499Y1044000D03*
X1509901Y1037622D03*
Y1044000D03*
X1506200Y1031244D03*
X1508050Y1034433D03*
X1511751D03*
X1513602Y1037622D03*
X1506200D03*
X1508050Y1040811D03*
X1511751D03*
X1506200Y1044000D03*
X1500649Y1034433D03*
Y1040811D03*
X1513602Y1044000D03*
Y1031244D03*
X1504350Y1047189D03*
Y1053567D03*
X1502499Y1050378D03*
X1509901Y1056756D03*
Y1050378D03*
X1504350Y1059945D03*
X1508050D03*
X1506200Y1056756D03*
X1502499D03*
X1506200Y1050378D03*
X1511751Y1059945D03*
X1508050Y1047189D03*
X1513602Y1050378D03*
X1511751Y1053567D03*
X1500649Y1059945D03*
Y1053567D03*
Y1047189D03*
X1513602Y1056756D03*
X1511751Y1047189D03*
X1508050Y1053567D03*
X1502499Y1063134D03*
X1509901D03*
X1502499Y1069512D03*
X1504350Y1072701D03*
Y1066323D03*
X1509901Y1069512D03*
X1511751Y1072701D03*
X1506200Y1063134D03*
X1513602D03*
X1508050Y1066323D03*
X1506200Y1069512D03*
X1513602D03*
X1508050Y1072701D03*
X1511751Y1066323D03*
X1500649Y1072701D03*
Y1066323D03*
X1502499Y1075890D03*
X1509901D03*
X1504350Y1079079D03*
Y1085457D03*
X1502499Y1088646D03*
X1509901D03*
X1502499Y1082268D03*
X1509901D03*
X1506200Y1075890D03*
X1513602D03*
X1508050Y1079079D03*
X1511751D03*
X1506200Y1082268D03*
X1513602D03*
X1508050Y1085457D03*
X1513602Y1088646D03*
X1506200D03*
X1511751Y1085457D03*
X1500649Y1079079D03*
Y1085457D03*
X1504350Y1091835D03*
X1502499Y1095024D03*
X1509901D03*
X1504350Y1098213D03*
X1502499Y1101402D03*
X1509901D03*
X1504350Y1104591D03*
X1513602Y1101402D03*
X1508050Y1104591D03*
X1511751Y1091835D03*
X1506200Y1095024D03*
X1513602D03*
X1508050Y1098213D03*
X1511751D03*
X1506200Y1101402D03*
X1511751Y1104591D03*
X1508050Y1091835D03*
X1500649D03*
Y1098213D03*
Y1104591D03*
X1502499Y1107780D03*
X1509901D03*
X1504350Y1110969D03*
X1509901Y1114158D03*
X1504350Y1117347D03*
X1502499Y1114158D03*
X1511751Y1110969D03*
X1506200Y1114158D03*
X1513602D03*
X1508050Y1117347D03*
X1511751D03*
X1513602Y1107780D03*
X1506200D03*
X1508050Y1110969D03*
X1500649D03*
Y1117347D03*
X1502499Y1120536D03*
X1504350Y1123725D03*
X1509901Y1120536D03*
X1502499Y1126914D03*
X1509901D03*
Y1133292D03*
X1502499D03*
X1504350Y1130103D03*
X1506200Y1120536D03*
X1513602D03*
X1508050Y1123725D03*
X1511751Y1130102D03*
X1506200Y1133292D03*
X1513602D03*
Y1126914D03*
X1506200D03*
X1511751Y1123725D03*
X1508050Y1130102D03*
X1500649D03*
Y1123725D03*
X1502499Y1139669D03*
X1504350Y1136480D03*
X1509901Y1139669D03*
X1504350Y1142858D03*
Y1149236D03*
X1502499Y1146047D03*
X1509901D03*
X1508050Y1136480D03*
X1511751D03*
X1506200Y1139669D03*
X1513602D03*
X1508050Y1142858D03*
X1511751Y1149236D03*
X1513602Y1146047D03*
X1506200D03*
X1511751Y1142858D03*
X1508050Y1149236D03*
X1500649Y1136480D03*
Y1149236D03*
Y1142858D03*
X1504350Y1155614D03*
X1502499Y1152425D03*
X1509901D03*
X1511751Y1155614D03*
X1502499Y1158803D03*
X1506200D03*
X1509901D03*
X1506200Y1152425D03*
X1513602D03*
X1508050Y1155614D03*
X1500649D03*
X1513602Y1158803D03*
X1500649Y1161992D03*
X1504350D03*
X1509914Y1165289D03*
X1506213D03*
X1502512D03*
X1502821Y1540295D03*
X1501427Y1547243D03*
X1506151D03*
X1507545Y1540295D03*
X1510875Y1547243D03*
X1512270Y1540295D03*
X1507446Y1549970D03*
X1512170D03*
X1502721D03*
X1509021Y1552698D03*
X1513745D03*
X1499572D03*
X1504296D03*
X1510545Y1554453D03*
X1505821D03*
X1501096D03*
X1511096Y1561853D03*
X1506372D03*
X1501647D03*
X1507446Y1563608D03*
X1512170D03*
X1502721D03*
X1509021Y1566336D03*
X1513745D03*
X1499572D03*
X1504296D03*
X1505821Y1556953D03*
X1506372Y1559353D03*
X1511096D03*
X1510545Y1556953D03*
X1501096D03*
X1501647Y1559353D03*
X1505871Y1569063D03*
X1501147D03*
X1507545Y1575641D03*
X1512270D03*
X1510595Y1569063D03*
X1502821Y1575641D03*
X1501993Y1625380D03*
X1506253D03*
X1508013Y1635380D03*
X1500233D03*
X1512293D03*
X1508013Y1647292D03*
X1500233D03*
X1512293D03*
X1501993Y1657292D03*
X1506253D03*
X1513187Y1679320D03*
Y1683857D03*
X1505313Y1684454D03*
Y1679920D03*
Y1675383D03*
X1513187Y1688391D03*
Y1693493D03*
Y1698030D03*
X1505313Y1698627D03*
Y1694093D03*
Y1689556D03*
X1513187Y1716737D03*
Y1702564D03*
Y1707666D03*
Y1712203D03*
X1505313Y1712800D03*
Y1708266D03*
Y1703729D03*
X1513187Y1721840D03*
Y1726377D03*
Y1730911D03*
X1505313Y1726974D03*
Y1722440D03*
Y1717903D03*
X1521673Y876434D03*
X1517972D03*
X1519822Y879623D03*
X1527224D03*
X1516121D03*
X1523523Y873245D03*
X1527224D03*
X1516121D03*
X1519822D03*
X1514271Y876434D03*
X1523523Y879623D03*
X1525373Y876434D03*
X1514271Y882812D03*
Y889190D03*
X1521673Y882812D03*
X1519822Y886001D03*
X1525373Y882812D03*
X1527224Y886001D03*
X1521673Y889190D03*
Y895568D03*
X1527224Y892379D03*
X1516121D03*
X1523523Y886001D03*
X1517972Y889190D03*
X1525373D03*
X1519822Y892379D03*
X1525373Y895568D03*
X1517972D03*
X1523523Y892379D03*
X1516121Y886001D03*
X1514271Y895568D03*
Y901946D03*
Y908324D03*
X1521673Y901946D03*
X1527224Y898757D03*
X1516121D03*
X1527224Y911512D03*
Y905134D03*
X1516121Y911512D03*
X1521673Y908323D03*
X1525373Y908324D03*
X1519822Y911512D03*
X1523523Y898757D03*
X1517972Y901946D03*
X1525373D03*
X1519822Y905134D03*
X1523523D03*
X1517972Y908324D03*
X1523523Y911512D03*
X1519822Y898757D03*
X1516121Y905134D03*
X1514271Y921079D03*
X1521673Y914701D03*
X1527224Y917890D03*
X1516121D03*
X1521673Y921079D03*
X1527224Y924268D03*
X1523523Y917890D03*
X1517972Y921079D03*
X1525373D03*
X1519822Y924268D03*
X1523523D03*
X1525373Y914701D03*
X1517972D03*
X1519822Y917890D03*
X1516121Y924268D03*
X1514271Y914701D03*
Y927457D03*
Y940213D03*
X1516121Y930646D03*
X1521673Y927457D03*
Y933835D03*
X1527224Y930646D03*
X1516121Y937024D03*
X1527224D03*
X1521673Y940213D03*
X1517972Y927457D03*
X1525373D03*
X1519822Y930646D03*
X1523523Y937024D03*
X1517972Y940213D03*
X1525373D03*
Y933835D03*
X1517972D03*
X1523523Y930646D03*
X1519822Y937024D03*
X1514271Y933835D03*
Y946591D03*
X1516121Y949780D03*
X1521673Y946591D03*
X1527224Y943402D03*
Y949780D03*
X1521673Y952969D03*
X1527224Y956158D03*
X1516121D03*
X1519822Y943402D03*
X1523523D03*
X1517972Y946591D03*
X1525373D03*
X1519822Y949780D03*
X1523523Y956158D03*
X1525373Y952969D03*
X1517972D03*
X1523523Y949780D03*
X1519822Y956158D03*
X1516121Y943402D03*
X1514271Y952969D03*
Y959347D03*
Y965725D03*
X1521673Y959347D03*
Y965725D03*
X1527224Y962536D03*
Y968914D03*
X1516121D03*
X1523523Y962536D03*
X1517972Y965725D03*
X1525373D03*
X1519822Y968914D03*
X1517972Y959347D03*
X1525373D03*
X1519822Y962536D03*
X1523523Y968914D03*
X1516121Y962536D03*
X1514271Y978481D03*
Y984859D03*
X1521673Y972103D03*
X1523523Y981670D03*
X1521673Y978481D03*
X1527224Y975292D03*
Y981670D03*
X1516121Y975292D03*
X1521673Y984859D03*
X1525373D03*
X1517972D03*
X1523523Y975292D03*
X1517972Y978481D03*
X1525373D03*
X1519822Y981670D03*
X1525373Y972103D03*
X1517972D03*
X1519822Y975292D03*
X1516121Y981670D03*
X1514271Y972103D03*
Y997615D03*
X1521673Y991237D03*
Y997615D03*
X1527224Y988048D03*
Y994426D03*
X1516121Y988048D03*
Y994426D03*
X1527224Y1000804D03*
X1519822Y988048D03*
X1523523Y994426D03*
X1525373Y997615D03*
X1517972D03*
X1519822Y1000804D03*
X1523523D03*
Y988048D03*
X1517972Y991237D03*
X1516121Y1000804D03*
X1514271Y991237D03*
X1519822Y994426D03*
X1525373Y991237D03*
X1514271Y1003993D03*
X1516121Y1007182D03*
X1521673Y1003993D03*
Y1010371D03*
X1527224Y1007182D03*
X1525373Y1010371D03*
X1523523Y1007182D03*
X1525373Y1003993D03*
X1517972D03*
X1519822Y1007182D03*
X1514271Y1010371D03*
X1517972D03*
X1522854Y1028055D03*
X1515452D03*
X1519153D03*
X1526554D03*
X1522854Y1034433D03*
Y1040811D03*
X1517302Y1044000D03*
X1528405Y1037622D03*
Y1044000D03*
X1515452Y1040811D03*
Y1034433D03*
X1517302Y1031244D03*
X1528405D03*
X1521003D03*
X1519153Y1034433D03*
X1526554D03*
X1524704Y1037622D03*
X1521003D03*
X1519153Y1040811D03*
X1526554D03*
X1521003Y1044000D03*
X1517302Y1037622D03*
X1524704Y1044000D03*
Y1031244D03*
X1515452Y1053567D03*
Y1059945D03*
X1522854Y1047189D03*
Y1053567D03*
X1521003Y1056756D03*
X1517302Y1050378D03*
X1522854Y1059945D03*
X1519153D03*
X1528405Y1050378D03*
Y1056756D03*
X1521003Y1050378D03*
X1526554Y1059945D03*
X1519153Y1047189D03*
X1524704Y1050378D03*
X1526554Y1053567D03*
X1517302Y1056756D03*
X1515452Y1047189D03*
X1524704Y1056756D03*
X1526554Y1047189D03*
X1519153Y1053567D03*
X1517302Y1063134D03*
X1528405D03*
X1515452Y1072701D03*
X1522854Y1066323D03*
Y1072701D03*
X1517302Y1069512D03*
X1528405D03*
X1526554Y1072701D03*
X1521003Y1063134D03*
X1524704D03*
X1519153Y1066323D03*
X1521003Y1069512D03*
X1524704D03*
X1519153Y1072701D03*
X1526554Y1066323D03*
X1515452D03*
X1528405Y1075890D03*
X1515452Y1079079D03*
X1522854D03*
X1517302Y1082268D03*
X1528405D03*
X1522854Y1085457D03*
X1517302Y1088646D03*
X1528405D03*
X1521003Y1075890D03*
X1524704D03*
X1519153Y1079079D03*
X1526554D03*
X1521003Y1082268D03*
X1524704D03*
X1519153Y1085457D03*
X1524704Y1088646D03*
X1521003D03*
X1526554Y1085457D03*
X1515452D03*
X1517302Y1075890D03*
X1515452Y1091835D03*
X1522854D03*
X1528405Y1095024D03*
X1522854Y1104591D03*
X1528405Y1101402D03*
X1515452Y1098213D03*
X1522854D03*
X1517302Y1101402D03*
X1524704D03*
X1519153Y1104591D03*
X1526554Y1091835D03*
X1521003Y1095024D03*
X1524704D03*
X1519153Y1098213D03*
X1526554D03*
X1521003Y1101402D03*
X1526554Y1104591D03*
X1519153Y1091835D03*
X1515452Y1104591D03*
X1517302Y1095024D03*
Y1107780D03*
X1528405D03*
X1522854Y1110969D03*
X1515452D03*
X1522854Y1117347D03*
X1528405Y1114158D03*
X1515452Y1117347D03*
X1526554Y1110969D03*
X1521003Y1114158D03*
X1524704D03*
X1519153Y1117347D03*
X1526554D03*
X1524704Y1107780D03*
X1521003D03*
X1519153Y1110969D03*
X1517302Y1114158D03*
X1522854Y1123725D03*
X1517302Y1120536D03*
X1528405D03*
X1517302Y1126914D03*
X1528405D03*
Y1133292D03*
X1515452Y1130102D03*
X1522854Y1130103D03*
X1521003Y1120536D03*
X1524704D03*
X1519153Y1123725D03*
X1526554Y1130102D03*
X1521003Y1133292D03*
X1524704D03*
Y1126914D03*
X1521003D03*
X1526554Y1123725D03*
X1519153Y1130102D03*
X1517302Y1133292D03*
X1515452Y1123725D03*
X1522854Y1142858D03*
Y1136480D03*
X1517302Y1139669D03*
X1528405D03*
X1515452Y1136480D03*
X1528405Y1146047D03*
X1515452Y1149236D03*
X1522854D03*
X1517302Y1146047D03*
X1519153Y1136480D03*
X1526554D03*
X1521003Y1139669D03*
X1524704D03*
X1519153Y1142858D03*
X1526554Y1149236D03*
X1524704Y1146047D03*
X1521003D03*
X1526554Y1142858D03*
X1519153Y1149236D03*
X1515452Y1142858D03*
X1528405Y1152425D03*
X1524704Y1158803D03*
X1528405D03*
X1515452Y1155614D03*
X1519153D03*
X1522854D03*
X1519153Y1161992D03*
X1521003Y1152425D03*
X1524704D03*
X1526554Y1155614D03*
X1517302Y1152425D03*
X1521003Y1158803D03*
X1515452Y1161992D03*
X1525049Y1547243D03*
X1521718Y1540295D03*
X1515600Y1547243D03*
X1516994Y1540295D03*
X1520324Y1547243D03*
X1526443Y1540295D03*
X1516895Y1549970D03*
X1521619D03*
X1526344D03*
X1518469Y1552698D03*
X1523194D03*
X1527918D03*
X1524719Y1554453D03*
X1519994D03*
X1515270D03*
X1525270Y1561853D03*
X1520545D03*
X1515821D03*
X1516895Y1563608D03*
X1521619D03*
X1526344D03*
X1518469Y1566336D03*
X1523194D03*
X1527918D03*
X1515821Y1559353D03*
X1515270Y1556953D03*
X1519994D03*
X1520545Y1559353D03*
X1525270D03*
X1524719Y1556953D03*
X1524769Y1569063D03*
X1515320D03*
X1516994Y1575641D03*
X1526443D03*
X1521718D03*
X1520044Y1569063D03*
X1514053Y1625380D03*
X1518313D03*
X1526113D03*
X1520073Y1635380D03*
X1524353D03*
X1520073Y1647292D03*
X1524353D03*
X1518313Y1657292D03*
X1514053D03*
X1526113D03*
X1521061Y1684454D03*
Y1679920D03*
Y1675383D03*
Y1698627D03*
Y1694093D03*
Y1689556D03*
Y1712800D03*
Y1708266D03*
Y1703729D03*
Y1726974D03*
Y1722440D03*
Y1717903D03*
X1529074Y876434D03*
X1538326Y879623D03*
X1542027D03*
X1540176Y876434D03*
X1530924Y873245D03*
X1534625Y879623D03*
X1536476Y876434D03*
X1530925Y886001D03*
X1529074Y889190D03*
Y895568D03*
X1540176Y882812D03*
X1536476D03*
X1534625Y886001D03*
X1540176Y889190D03*
X1542027Y892379D03*
X1534625D03*
X1538326Y886001D03*
X1532775Y889190D03*
X1536476D03*
X1530925Y892379D03*
X1536476Y895568D03*
X1532775D03*
X1538326Y892379D03*
X1540176Y895568D03*
X1542027Y886001D03*
X1532775Y882812D03*
X1529074Y901946D03*
Y908324D03*
X1542027Y898757D03*
X1540176Y901946D03*
X1534625Y898757D03*
X1540176Y908324D03*
X1542027Y911512D03*
X1534625Y905134D03*
Y911512D03*
X1536476Y908324D03*
X1530925Y911512D03*
X1538326Y898757D03*
X1532775Y901946D03*
X1536476D03*
X1530925Y905134D03*
X1538326D03*
X1532775Y908324D03*
X1538326Y911512D03*
X1530925Y898757D03*
X1542027Y905134D03*
X1529074Y914701D03*
Y921079D03*
X1542027Y917890D03*
X1534625D03*
X1540176Y921079D03*
X1534625Y924268D03*
X1538326Y917890D03*
X1532775Y921079D03*
X1536476D03*
X1530925Y924268D03*
X1538326D03*
X1536476Y914701D03*
X1532775D03*
X1530925Y917890D03*
X1542027Y924268D03*
X1540176Y914701D03*
X1529074Y927457D03*
Y933835D03*
Y940213D03*
X1540176Y927457D03*
X1542027Y930646D03*
X1534625D03*
X1542027Y937024D03*
X1540176Y940213D03*
X1534625Y937024D03*
X1532775Y927457D03*
X1536476D03*
X1530925Y930646D03*
X1538326Y937024D03*
X1532775Y940213D03*
X1536476D03*
Y933835D03*
X1532775D03*
X1538326Y930646D03*
X1530925Y937024D03*
X1540176Y933835D03*
X1529074Y946591D03*
Y952969D03*
X1540176Y946591D03*
X1542027Y949780D03*
X1534625Y943402D03*
Y949780D03*
Y956158D03*
X1542027D03*
X1530925Y943402D03*
X1538326D03*
X1532775Y946591D03*
X1536476D03*
X1530925Y949780D03*
X1538326Y956158D03*
X1536476Y952969D03*
X1532775D03*
X1538326Y949780D03*
X1530925Y956158D03*
X1540176Y952969D03*
X1542027Y943402D03*
X1529074Y959347D03*
Y965725D03*
X1540176Y959347D03*
Y965725D03*
X1534625Y962536D03*
X1542027Y968914D03*
X1534625D03*
X1538326Y962536D03*
X1532775Y965725D03*
X1536476D03*
X1530925Y968914D03*
X1532775Y959347D03*
X1536476D03*
X1530925Y962536D03*
X1538326Y968914D03*
X1542027Y962536D03*
X1538326Y981670D03*
X1542027Y975292D03*
X1540176Y978481D03*
X1534625Y975292D03*
Y981670D03*
X1536476Y984859D03*
X1540176D03*
X1529074Y972103D03*
Y978481D03*
Y984859D03*
X1532775D03*
X1538326Y975292D03*
X1532775Y978481D03*
X1536476D03*
X1530925Y981670D03*
X1536476Y972103D03*
X1532775D03*
X1530925Y975292D03*
X1542027Y981670D03*
X1540176Y972103D03*
X1529074Y991237D03*
Y997615D03*
X1542027Y988048D03*
X1540176Y997615D03*
X1542027Y994426D03*
X1534625Y988048D03*
Y994426D03*
Y1000804D03*
X1530925Y988048D03*
X1538326Y994426D03*
X1536476Y997615D03*
X1532775D03*
X1530925Y1000804D03*
X1538326D03*
Y988048D03*
X1532775Y991237D03*
X1542027Y1000804D03*
X1540176Y991237D03*
X1530924Y994426D03*
X1536476Y991237D03*
X1542027Y1007182D03*
X1534625D03*
X1529074Y1003993D03*
Y1010371D03*
X1540176Y1003993D03*
X1536476Y1010371D03*
X1538326Y1007182D03*
X1536476Y1003993D03*
X1532775D03*
X1530925Y1007182D03*
X1540176Y1010371D03*
X1532775D03*
X1530255Y1028055D03*
X1541358D03*
X1533956D03*
X1537657D03*
X1530255Y1034433D03*
Y1040811D03*
X1541357D03*
Y1034433D03*
X1543208Y1031244D03*
Y1044000D03*
X1535806Y1031244D03*
Y1037622D03*
Y1044000D03*
X1532106Y1031244D03*
X1533956Y1034433D03*
X1537657D03*
X1539507Y1037622D03*
X1532106D03*
X1533956Y1040811D03*
X1537657D03*
X1532106Y1044000D03*
X1543208Y1037622D03*
X1539507Y1044000D03*
Y1031244D03*
X1530255Y1047189D03*
Y1053567D03*
Y1059945D03*
X1541357Y1053567D03*
Y1059945D03*
X1543208Y1050378D03*
X1532106Y1056756D03*
X1535806D03*
Y1050378D03*
X1533956Y1059945D03*
X1532106Y1050378D03*
X1537657Y1059945D03*
X1533956Y1047189D03*
X1539507Y1050378D03*
X1537657Y1053567D03*
X1543208Y1056756D03*
X1541357Y1047189D03*
X1539507Y1056756D03*
X1537657Y1047189D03*
X1533956Y1053567D03*
X1530255Y1066323D03*
Y1072701D03*
X1543208Y1063134D03*
X1535806D03*
X1543208Y1069512D03*
X1541357Y1072701D03*
X1535806Y1069512D03*
X1537657Y1072701D03*
X1532106Y1063134D03*
X1539507D03*
X1533956Y1066323D03*
X1532106Y1069512D03*
X1539507D03*
X1533956Y1072701D03*
X1537657Y1066323D03*
X1541357D03*
X1530255Y1079079D03*
Y1085457D03*
X1535806Y1075890D03*
X1541357Y1079079D03*
X1543208Y1082268D03*
Y1088646D03*
X1535806D03*
Y1082268D03*
X1532106Y1075890D03*
X1539507D03*
X1533956Y1079079D03*
X1537657D03*
X1532106Y1082268D03*
X1539507D03*
X1533956Y1085457D03*
X1539507Y1088646D03*
X1532106D03*
X1537657Y1085457D03*
X1541357D03*
X1543208Y1075890D03*
X1530255Y1098213D03*
Y1104591D03*
X1541357Y1091835D03*
X1535806Y1095024D03*
X1543208Y1101402D03*
X1541357Y1098213D03*
X1535806Y1101402D03*
X1530255Y1091835D03*
X1539507Y1101402D03*
X1533956Y1104591D03*
X1537657Y1091835D03*
X1532106Y1095024D03*
X1539507D03*
X1533956Y1098213D03*
X1537657D03*
X1532106Y1101402D03*
X1537657Y1104591D03*
X1533956Y1091835D03*
X1541357Y1104591D03*
X1543208Y1095024D03*
X1530255Y1110969D03*
Y1117347D03*
X1543208Y1107780D03*
X1535806D03*
X1541357Y1110969D03*
Y1117347D03*
X1535806Y1114158D03*
X1537657Y1110969D03*
X1532106Y1114158D03*
X1539507D03*
X1533956Y1117347D03*
X1537657D03*
X1539507Y1107780D03*
X1532106D03*
X1533956Y1110969D03*
X1543208Y1114158D03*
X1530255Y1123725D03*
Y1130102D03*
X1543208Y1120536D03*
X1535806D03*
X1543208Y1126914D03*
X1535806D03*
X1541357Y1130102D03*
X1535806Y1133292D03*
X1532106Y1120536D03*
X1539507D03*
X1533956Y1123725D03*
X1537657Y1130102D03*
X1532106Y1133292D03*
X1539507D03*
Y1126914D03*
X1532106D03*
X1537657Y1123725D03*
X1533956Y1130102D03*
X1543208Y1133292D03*
X1541357Y1123725D03*
X1530255Y1142858D03*
Y1136480D03*
Y1149236D03*
X1541357Y1136480D03*
X1543208Y1139669D03*
X1535806D03*
X1543208Y1146047D03*
X1541357Y1149236D03*
X1535806Y1146047D03*
X1533956Y1136480D03*
X1537657D03*
X1532106Y1139669D03*
X1539507D03*
X1533956Y1142858D03*
X1537657Y1149236D03*
X1539507Y1146047D03*
X1532106D03*
X1537657Y1142858D03*
X1533956Y1149236D03*
X1541357Y1142858D03*
X1533956Y1161992D03*
X1543208Y1158803D03*
X1530255Y1155614D03*
X1537657D03*
X1541357D03*
X1535806Y1152425D03*
X1532106Y1158803D03*
X1535806D03*
X1541357Y1161992D03*
X1532106Y1165181D03*
Y1152425D03*
X1539507D03*
X1533956Y1155614D03*
X1539507Y1158803D03*
X1543208Y1152425D03*
X1537657Y1161992D03*
X1530255D03*
X1531167Y1540295D03*
X1529773Y1547243D03*
X1531068Y1549970D03*
X1532643Y1552698D03*
X1535368Y1540355D03*
X1537468D03*
X1538875Y1547073D03*
X1538819Y1549336D03*
X1534188Y1554453D03*
X1529443D03*
X1529994Y1561853D03*
X1531068Y1563608D03*
X1532643Y1566336D03*
X1529443Y1556953D03*
X1529994Y1559353D03*
X1539170Y1567540D03*
X1539171Y1564618D03*
X1539082Y1561698D03*
X1534824Y1569063D03*
X1531167Y1575641D03*
X1529493Y1569063D03*
X1538585Y1571658D03*
X1539170Y1569640D03*
X1530373Y1625380D03*
X1542433D03*
X1538173D03*
X1532133Y1635380D03*
X1536413D03*
X1532133Y1647292D03*
X1536413D03*
X1530373Y1657292D03*
X1542433D03*
X1538173D03*
X1528935Y1679320D03*
Y1683857D03*
X1536809Y1684454D03*
Y1679920D03*
Y1675383D03*
X1528935Y1688391D03*
Y1693493D03*
Y1698030D03*
X1536809Y1698627D03*
Y1694093D03*
Y1689556D03*
X1528935Y1712203D03*
X1536809Y1712800D03*
Y1708266D03*
Y1703729D03*
X1528935Y1716737D03*
Y1702564D03*
Y1707666D03*
Y1721840D03*
Y1726377D03*
Y1730911D03*
X1536809Y1726974D03*
Y1722440D03*
Y1717903D03*
X1545728Y873245D03*
X1553129Y879623D03*
X1549428D03*
X1545728D03*
Y886001D03*
X1547578Y882812D03*
X1553129Y886001D03*
X1551279Y882812D03*
X1547578Y889190D03*
Y895568D03*
X1553129Y892379D03*
X1547578Y901946D03*
X1553129Y898757D03*
X1547578Y908324D03*
X1553870Y906181D03*
Y912559D03*
X1547578Y914701D03*
X1553870Y918937D03*
X1547578Y921079D03*
X1553870Y925315D03*
X1547578Y927457D03*
Y933835D03*
X1553870Y931693D03*
X1547578Y940213D03*
X1553870Y938071D03*
X1547578Y946591D03*
X1553870Y944449D03*
Y950827D03*
X1547578Y952969D03*
Y959347D03*
Y965725D03*
X1553870Y957205D03*
Y963583D03*
Y969961D03*
X1543877Y984859D03*
X1547578Y972103D03*
Y978481D03*
X1553870Y976339D03*
Y982717D03*
X1547578Y984859D03*
X1545728Y988048D03*
X1547578Y991237D03*
Y997615D03*
X1553870Y989095D03*
Y995473D03*
X1547578Y1003993D03*
Y1010371D03*
X1553870Y1008229D03*
Y1001851D03*
X1543877Y1010371D03*
X1548759Y1028055D03*
X1555051Y1030197D03*
X1545058Y1028055D03*
X1548759Y1040811D03*
Y1034433D03*
X1555051Y1042953D03*
Y1036575D03*
X1546909Y1056756D03*
X1545058Y1059945D03*
X1548759Y1047189D03*
X1555051Y1049331D03*
X1548759Y1053567D03*
Y1059945D03*
X1555051Y1055709D03*
Y1062087D03*
X1548759Y1072701D03*
Y1066323D03*
X1555051Y1068465D03*
Y1074843D03*
X1548759Y1079079D03*
X1555051Y1081221D03*
X1548759Y1085457D03*
X1555051Y1087599D03*
X1548759Y1091835D03*
X1555051Y1093977D03*
X1548759Y1098213D03*
Y1104591D03*
X1555051Y1100355D03*
Y1106733D03*
X1548759Y1110969D03*
X1555051Y1113111D03*
X1548759Y1117347D03*
X1555051Y1119489D03*
Y1132245D03*
X1548759Y1123725D03*
X1555051Y1125867D03*
X1548759Y1130102D03*
Y1136480D03*
X1555051Y1138622D03*
X1548759Y1142858D03*
X1555051Y1145000D03*
X1548759Y1149236D03*
X1545058Y1155614D03*
X1548759D03*
X1555051Y1151378D03*
X1550609Y1158803D03*
X1554310D03*
X1548759Y1161992D03*
X1546909Y1165181D03*
X1550233Y1625380D03*
X1554493D03*
X1544193Y1635380D03*
X1556253D03*
X1548473D03*
X1544193Y1647292D03*
X1556253D03*
X1548473D03*
X1554493Y1657292D03*
X1550233D03*
X1544683Y1679320D03*
Y1683857D03*
X1552557Y1684454D03*
Y1679920D03*
Y1675383D03*
X1544683Y1688391D03*
Y1693493D03*
Y1698030D03*
X1552557Y1698627D03*
Y1694093D03*
Y1689556D03*
X1544683Y1716737D03*
Y1702564D03*
Y1707666D03*
Y1712203D03*
X1552557Y1712800D03*
Y1708266D03*
Y1703729D03*
X1544683Y1721840D03*
Y1726377D03*
Y1730911D03*
X1552557Y1726974D03*
Y1722440D03*
Y1717903D03*
X1562293Y1625380D03*
X1566553D03*
X1568313Y1635380D03*
X1560533D03*
X1572593D03*
X1568313Y1647292D03*
X1560533D03*
X1572593D03*
X1562293Y1657292D03*
X1566553D03*
X1572243Y1684454D03*
Y1679920D03*
Y1675383D03*
X1560431Y1679320D03*
Y1683857D03*
X1572243Y1698627D03*
Y1694093D03*
Y1689556D03*
X1560431Y1688391D03*
Y1693493D03*
Y1698030D03*
X1572243Y1712800D03*
Y1708266D03*
Y1703729D03*
X1560431Y1716737D03*
Y1702564D03*
Y1707666D03*
Y1712203D03*
X1572243Y1726974D03*
Y1722440D03*
Y1717903D03*
X1560431Y1721840D03*
Y1726377D03*
Y1730911D03*
X1583056Y1540514D03*
X1586969Y1547243D03*
X1585797Y1552195D03*
X1588264Y1549970D03*
X1580940Y1540460D03*
X1578689Y1540509D03*
X1578854Y1546218D03*
X1577195Y1551121D03*
X1586639Y1554453D03*
X1587190Y1561853D03*
X1577688Y1556810D03*
Y1561725D03*
X1588264Y1563608D03*
X1586639Y1556953D03*
X1587190Y1559353D03*
X1577596Y1554612D03*
X1586688Y1569063D03*
X1583160Y1575425D03*
X1577642Y1568698D03*
Y1570898D03*
X1583160Y1577625D03*
X1579089Y1573317D03*
X1574353Y1625380D03*
X1578613D03*
X1586413D03*
X1580373Y1635380D03*
X1584653D03*
X1580373Y1647292D03*
X1584653D03*
X1574353Y1657292D03*
X1578613D03*
X1586413D03*
X1580117Y1679320D03*
Y1683857D03*
X1587991Y1684454D03*
Y1679920D03*
Y1675383D03*
X1580117Y1688391D03*
Y1693493D03*
Y1698030D03*
X1587991Y1698627D03*
Y1694093D03*
Y1689556D03*
X1580117Y1716737D03*
Y1702564D03*
Y1707666D03*
Y1712203D03*
X1587991Y1712800D03*
Y1708266D03*
Y1703729D03*
X1580117Y1721840D03*
Y1726377D03*
Y1730911D03*
X1587991Y1726974D03*
Y1722440D03*
Y1717903D03*
X1588363Y1540295D03*
X1591693Y1547243D03*
X1593088Y1540295D03*
X1596418Y1547243D03*
X1597812Y1540295D03*
X1601142Y1547243D03*
X1602536Y1540295D03*
X1592988Y1549970D03*
X1597713D03*
X1602437D03*
X1589839Y1552698D03*
X1594563D03*
X1599287D03*
X1600812Y1554453D03*
X1596088D03*
X1591363D03*
X1601363Y1561853D03*
X1596639D03*
X1591914D03*
X1592988Y1563608D03*
X1597713D03*
X1602437D03*
X1589839Y1566336D03*
X1594563D03*
X1599287D03*
X1600812Y1556953D03*
X1596639Y1559353D03*
X1596088Y1556953D03*
X1601363Y1559353D03*
X1591363Y1556953D03*
X1591914Y1559353D03*
X1602536Y1575641D03*
X1600862Y1569063D03*
X1597812Y1575641D03*
X1596138Y1569063D03*
X1593088Y1575641D03*
X1591413Y1569063D03*
X1588363Y1575641D03*
X1590673Y1625380D03*
X1602733D03*
X1598473D03*
X1592433Y1635380D03*
X1596713D03*
X1592433Y1647292D03*
X1596713D03*
X1590673Y1657292D03*
X1598473D03*
X1602733D03*
X1595865Y1679320D03*
Y1683857D03*
Y1688391D03*
Y1693493D03*
Y1698030D03*
Y1716737D03*
Y1702564D03*
Y1707666D03*
Y1712203D03*
Y1721840D03*
Y1726377D03*
Y1730911D03*
X1605867Y1547243D03*
X1607261Y1540295D03*
X1610591Y1547243D03*
X1611985Y1540295D03*
X1615315Y1547243D03*
X1616710Y1540295D03*
X1607161Y1549970D03*
X1611886D03*
X1616610D03*
X1604012Y1552698D03*
X1608736D03*
X1613461D03*
X1614985Y1554453D03*
X1610261D03*
X1605536D03*
X1615536Y1561853D03*
X1610812D03*
X1606087D03*
X1607161Y1563608D03*
X1611886D03*
X1616610D03*
X1604012Y1566336D03*
X1608736D03*
X1613461D03*
X1610261Y1556953D03*
X1610812Y1559353D03*
X1606087D03*
X1605536Y1556953D03*
X1614985D03*
X1615536Y1559353D03*
X1610311Y1569063D03*
X1605587D03*
X1616710Y1575641D03*
X1615035Y1569063D03*
X1611985Y1575641D03*
X1607261D03*
X1610533Y1625380D03*
X1614793D03*
X1604493Y1635380D03*
X1616553D03*
X1608773D03*
X1604493Y1647292D03*
X1616553D03*
X1608773D03*
X1614793Y1657292D03*
X1610533D03*
X1611613Y1679320D03*
Y1683857D03*
X1603739Y1684454D03*
Y1679920D03*
Y1675383D03*
X1611613Y1688391D03*
Y1693493D03*
Y1698030D03*
X1603739Y1698627D03*
Y1694093D03*
Y1689556D03*
X1611613Y1702564D03*
Y1707666D03*
Y1712203D03*
X1603739Y1712800D03*
Y1708266D03*
Y1703729D03*
X1611613Y1716737D03*
Y1721840D03*
Y1726377D03*
Y1730911D03*
X1603739Y1726974D03*
Y1722440D03*
Y1717903D03*
X1620040Y1547243D03*
X1621434Y1540295D03*
X1624764Y1547243D03*
X1626158Y1540295D03*
X1629489Y1547243D03*
X1630883Y1540295D03*
X1621335Y1549970D03*
X1626059D03*
X1630783D03*
X1618185Y1552698D03*
X1622909D03*
X1627634D03*
X1632358D03*
X1629158Y1554453D03*
X1624434D03*
X1619710D03*
X1629709Y1561853D03*
X1624985D03*
X1620261D03*
X1621335Y1563608D03*
X1626059D03*
X1630783D03*
X1618185Y1566336D03*
X1622909D03*
X1627634D03*
X1632358D03*
X1624434Y1556953D03*
X1624985Y1559353D03*
X1620261D03*
X1619710Y1556953D03*
X1629709Y1559353D03*
X1629158Y1556953D03*
X1629209Y1569063D03*
X1619760D03*
X1630883Y1575641D03*
X1626158D03*
X1624484Y1569063D03*
X1621434Y1575641D03*
X1622593Y1625380D03*
X1626853D03*
X1628613Y1635380D03*
X1620833D03*
X1632893D03*
X1628613Y1647292D03*
X1620833D03*
X1632893D03*
X1622593Y1657292D03*
X1626853D03*
X1627361Y1679320D03*
Y1683857D03*
X1619487Y1684454D03*
Y1679920D03*
Y1675383D03*
X1627361Y1688391D03*
Y1693493D03*
Y1698030D03*
X1619487Y1698627D03*
Y1694093D03*
Y1689556D03*
Y1708266D03*
Y1703729D03*
X1627361Y1716737D03*
Y1702564D03*
Y1707666D03*
Y1712203D03*
X1619487Y1712800D03*
X1627361Y1721840D03*
Y1726377D03*
Y1730911D03*
X1619487Y1726974D03*
Y1722440D03*
Y1717903D03*
X1634213Y1547243D03*
X1635607Y1540295D03*
X1638937Y1547243D03*
X1640332Y1540295D03*
X1643662Y1547243D03*
X1645056Y1540295D03*
X1635508Y1549970D03*
X1640232D03*
X1644957D03*
X1637083Y1552698D03*
X1641807D03*
X1646531D03*
X1643332Y1554453D03*
X1638607D03*
X1633883D03*
X1643883Y1561853D03*
X1639158D03*
X1634434D03*
X1635508Y1563608D03*
X1640232D03*
X1644957D03*
X1637083Y1566336D03*
X1641807D03*
X1646531D03*
X1633883Y1556953D03*
X1634434Y1559353D03*
X1643332Y1556953D03*
X1643883Y1559353D03*
X1639158D03*
X1638607Y1556953D03*
X1643382Y1569063D03*
X1633933D03*
X1645056Y1575641D03*
X1640332D03*
X1638657Y1569063D03*
X1635607Y1575641D03*
X1634653Y1625380D03*
X1638923D03*
X1646713D03*
X1640673Y1635286D03*
X1644953Y1635380D03*
X1640673Y1647292D03*
X1644953D03*
X1634653Y1657292D03*
X1638913D03*
X1646713D03*
X1653111Y1547243D03*
X1648386D03*
X1649780Y1540295D03*
X1654505D03*
X1657835Y1547243D03*
X1659229Y1540295D03*
X1649681Y1549970D03*
X1654406D03*
X1659130D03*
X1651256Y1552698D03*
X1655980D03*
X1660705D03*
X1662250Y1554453D03*
X1657505D03*
X1652781D03*
X1648056D03*
X1658056Y1561853D03*
X1653332D03*
X1648607D03*
X1649681Y1563608D03*
X1654406D03*
X1659130D03*
X1651256Y1566336D03*
X1655980D03*
X1660705D03*
X1652781Y1556953D03*
X1648607Y1559353D03*
X1648056Y1556953D03*
X1658056Y1559353D03*
X1653332D03*
X1657505Y1556953D03*
X1652831Y1569063D03*
X1649780Y1575641D03*
X1648106Y1569063D03*
X1654505Y1575641D03*
X1657555Y1569063D03*
X1659229Y1575641D03*
X1652743Y1635380D03*
Y1647292D03*
X1663430Y1540355D03*
X1665530D03*
X1666937Y1547073D03*
X1666881Y1549336D03*
X1667231Y1567540D03*
X1667232Y1564618D03*
X1667143Y1561698D03*
X1670227Y1567413D03*
X1668750Y1563158D03*
X1662886Y1569063D03*
X1666647Y1571658D03*
X1667231Y1569640D03*
X2392820Y1513806D03*
X5121120Y970856D03*
X5120120Y1284856D03*
Y1600356D03*
G54D12*
X27559Y87795D03*
X40708Y631889D03*
Y1368908D03*
X51180Y1714961D03*
X373622Y87795D03*
X395671Y1714960D03*
X661024Y631890D03*
X707677Y1714960D03*
X800787Y87795D03*
X931693Y757874D03*
X931692Y1072835D03*
X931693Y1387795D03*
X1045866Y87795D03*
X1155709Y1714961D03*
X1271260Y631890D03*
X1461806Y1714961D03*
X1499606Y87795D03*
X1806298Y1714961D03*
X1829921Y87795D03*
X1816772Y631889D03*
Y1368897D03*
X2392820Y390906D03*
G54D22*
X188155Y1516970D03*
Y1530608D03*
X192879Y1516970D03*
X197604D03*
X189730Y1519698D03*
X194454D03*
X199178D03*
X202328Y1516970D03*
X203903Y1519698D03*
X202328Y1530608D03*
X203903Y1533336D03*
X192879Y1530608D03*
X197604D03*
X189730Y1533336D03*
X194454D03*
X199178D03*
X207052Y1516970D03*
X211777D03*
X216501D03*
X208627Y1519698D03*
X213352D03*
X218076D03*
X216501Y1530608D03*
X218076Y1533336D03*
X207052Y1530608D03*
X211777D03*
X208627Y1533336D03*
X213352D03*
X221226Y1516970D03*
X225950D03*
X230674D03*
X222800Y1519698D03*
X227525D03*
X232249D03*
X230674Y1530608D03*
X232249Y1533336D03*
X221226Y1530608D03*
X225950D03*
X222800Y1533336D03*
X227525D03*
X235399Y1516970D03*
X240123D03*
X244848D03*
X236974Y1519698D03*
X241698D03*
X246422D03*
X244848Y1530608D03*
X246422Y1533336D03*
X235399Y1530608D03*
X240123D03*
X236974Y1533336D03*
X241698D03*
X249572Y1516970D03*
X254297D03*
X259021D03*
X251147Y1519698D03*
X255871D03*
X260596D03*
Y1533336D03*
X249572Y1530608D03*
X254297D03*
X259021D03*
X251147Y1533336D03*
X255871D03*
X317957Y886002D03*
X319807Y889191D03*
Y895569D03*
X317957Y892380D03*
Y898758D03*
X319807Y908325D03*
Y901947D03*
X317957Y905135D03*
Y911513D03*
Y917891D03*
X319807Y921080D03*
X317957Y924269D03*
X319807Y914702D03*
Y927458D03*
Y940214D03*
Y933836D03*
X317957Y937025D03*
Y930647D03*
Y943403D03*
X319807Y946592D03*
X317957Y956159D03*
X319807Y952970D03*
X317957Y949781D03*
X319807Y965726D03*
Y959348D03*
X317957Y962537D03*
Y968915D03*
X319807Y972104D03*
X317957Y975293D03*
X319807Y978482D03*
Y997616D03*
Y991238D03*
X317957Y994427D03*
Y1000805D03*
X319807Y1010372D03*
X317957Y1007183D03*
X319807Y1003994D03*
X320988Y1034434D03*
X319138Y1037623D03*
X320988Y1040812D03*
X319138Y1044001D03*
X320988Y1059946D03*
X319138Y1050379D03*
X320988Y1053568D03*
X319138Y1063135D03*
X320988Y1072702D03*
X319138Y1069513D03*
X320988Y1066324D03*
X319138Y1075891D03*
X320988Y1079080D03*
X319138Y1082269D03*
Y1088647D03*
X320988Y1085458D03*
Y1091836D03*
X319138Y1101403D03*
Y1095025D03*
X320988Y1098214D03*
Y1104592D03*
X319138Y1107781D03*
X320988Y1110970D03*
X319138Y1114159D03*
X320988Y1117348D03*
X319138Y1120537D03*
X320988Y1130103D03*
X319138Y1133293D03*
Y1126915D03*
X320988Y1123726D03*
Y1136481D03*
X319138Y1139670D03*
X320988Y1149237D03*
X319138Y1146048D03*
X320988Y1142859D03*
X319138Y1152426D03*
X316217Y1516970D03*
X320941D03*
X317792Y1519698D03*
X322516D03*
X320941Y1530608D03*
X322516Y1533336D03*
X316217Y1530608D03*
X317792Y1533336D03*
X323508Y889191D03*
X325358Y892380D03*
X323508Y895569D03*
X332760Y886002D03*
X330910Y889191D03*
Y895569D03*
X332760Y892380D03*
X338311Y889191D03*
X336461Y892380D03*
X338311Y895569D03*
X336461Y898758D03*
X325358D03*
X332760D03*
X336461Y911513D03*
X338311Y901947D03*
X336461Y905135D03*
X338311Y908325D03*
X325358Y911513D03*
X323508Y901947D03*
X325358Y905135D03*
X323508Y908325D03*
X330910D03*
Y901947D03*
X332760Y905135D03*
Y911513D03*
X323508Y921080D03*
X325358Y924269D03*
X323508Y914702D03*
X325358Y917891D03*
X332760D03*
X330910Y921080D03*
X332760Y924269D03*
X330910Y914702D03*
X338311Y921080D03*
X336461Y924269D03*
X338311Y914702D03*
X336461Y917891D03*
X338311Y927458D03*
X323508D03*
X330910D03*
X336461Y930647D03*
X338311Y940214D03*
Y933836D03*
X336461Y937025D03*
X325358Y930647D03*
X323508Y940214D03*
Y933836D03*
X325358Y937025D03*
X332760D03*
X330910Y940214D03*
Y933836D03*
X332760Y930647D03*
X325358Y943403D03*
X332760D03*
X336461D03*
X323508Y946592D03*
X325358Y949781D03*
X323508Y952970D03*
X325358Y956159D03*
X330910Y946592D03*
X332760Y956159D03*
X330910Y952970D03*
X332760Y949781D03*
X338311Y946592D03*
X336461Y949781D03*
X338311Y952970D03*
X336461Y956159D03*
X338311Y965726D03*
X336461Y968915D03*
X338311Y959348D03*
X336461Y962537D03*
X323508Y965726D03*
X325358Y968915D03*
X323508Y959348D03*
X325358Y962537D03*
X332760D03*
X330910Y965726D03*
Y959348D03*
X332760Y968915D03*
X323508Y972104D03*
X330910D03*
X338311D03*
X323508Y984860D03*
Y978482D03*
X325358Y981671D03*
Y975293D03*
X332760D03*
X330910Y978482D03*
X338311Y984860D03*
Y978482D03*
X336461Y981671D03*
Y975293D03*
Y988049D03*
X325358D03*
X338311Y997616D03*
X336461Y1000805D03*
Y994427D03*
X323508Y997616D03*
X325358Y1000805D03*
Y994427D03*
X332760D03*
X330910Y997616D03*
X332760Y1000805D03*
X330910Y991238D03*
X323508Y1003994D03*
X325358Y1007183D03*
X330910Y1010372D03*
X332760Y1007183D03*
X330910Y1003994D03*
X338311D03*
X336461Y1007183D03*
X326539Y1031245D03*
X337642D03*
X324689Y1034434D03*
X326539Y1037623D03*
X324689Y1040812D03*
X332091Y1034434D03*
X333941Y1037623D03*
X332091Y1040812D03*
X333941Y1044001D03*
X337642Y1037623D03*
X324689Y1047190D03*
X337642Y1050379D03*
X333941D03*
X326539D03*
X332091Y1059946D03*
Y1053568D03*
X326539Y1063135D03*
X333941D03*
X337642D03*
X324689Y1066324D03*
X326539Y1069513D03*
X324689Y1072702D03*
X332091D03*
X333941Y1069513D03*
X332091Y1066324D03*
X337642Y1069513D03*
Y1075891D03*
X333941D03*
X326539D03*
X337642Y1082269D03*
X333941D03*
Y1088647D03*
X337642D03*
X324689Y1079080D03*
X326539Y1082269D03*
X324689Y1085458D03*
X326539Y1088647D03*
X332091Y1079080D03*
Y1085458D03*
X324689Y1091836D03*
X332091D03*
X324689Y1104592D03*
X326539Y1095025D03*
X324689Y1098214D03*
X326539Y1101403D03*
X333941D03*
Y1095025D03*
X332091Y1098214D03*
Y1104592D03*
X337642Y1095025D03*
Y1101403D03*
X333941Y1107781D03*
X337642D03*
X326539D03*
X337642Y1114159D03*
X333941D03*
X326539D03*
X324689Y1117348D03*
Y1110970D03*
X332091D03*
Y1117348D03*
X326539Y1120537D03*
X333941D03*
X337642D03*
X324689Y1123726D03*
X326539Y1133293D03*
Y1126915D03*
X324689Y1130103D03*
X332091D03*
X333941Y1133293D03*
Y1126915D03*
X332091Y1123726D03*
X337642Y1133293D03*
Y1126915D03*
X324689Y1136481D03*
X332091D03*
X337642Y1139670D03*
X333941D03*
Y1146048D03*
X337642D03*
X326539Y1139670D03*
X324689Y1142859D03*
X326539Y1146048D03*
X324689Y1149237D03*
X332091D03*
Y1142859D03*
X326539Y1152426D03*
X333941D03*
X337642D03*
X324689Y1155615D03*
X332091D03*
X325666Y1516970D03*
X330390D03*
X335114D03*
X327240Y1519698D03*
X331965D03*
X336689D03*
X335114Y1530608D03*
X336689Y1533336D03*
X325666Y1530608D03*
X330390D03*
X327240Y1533336D03*
X331965D03*
X343862Y886002D03*
X349414Y889191D03*
X345713D03*
Y895569D03*
X349414D03*
X343862Y892380D03*
X351264D03*
Y898758D03*
X343862D03*
X351264Y911513D03*
X349414Y901947D03*
X351264Y905135D03*
X349414Y908325D03*
X345713D03*
Y901947D03*
X343862Y905135D03*
Y911513D03*
Y917891D03*
X349414Y921080D03*
X345713D03*
X343862Y924269D03*
X345713Y914702D03*
X349414D03*
X351264Y924269D03*
Y917891D03*
X349414Y927458D03*
X345713D03*
X351264Y930647D03*
X349414Y940214D03*
Y933836D03*
X351264Y937025D03*
X343862D03*
X345713Y940214D03*
Y933836D03*
X343862Y930647D03*
Y943403D03*
X351264D03*
X349414Y946592D03*
X345713D03*
X343862Y956159D03*
X345713Y952970D03*
X349414D03*
X343862Y949781D03*
X351264D03*
Y956159D03*
X349414Y965726D03*
X351264Y968915D03*
X349414Y959348D03*
X351264Y962537D03*
X343862D03*
X345713Y965726D03*
Y959348D03*
X343862Y968915D03*
X345713Y972104D03*
X349414D03*
Y984860D03*
X343862Y975293D03*
X349414Y978482D03*
X345713D03*
X351264Y981671D03*
Y975293D03*
Y988049D03*
X349414Y997616D03*
X351264Y1000805D03*
Y994427D03*
X343862D03*
X345713Y997616D03*
X343862Y1000805D03*
X345713Y991238D03*
Y1010372D03*
X343862Y1007183D03*
X345713Y1003994D03*
X349414D03*
X351264Y1007183D03*
X352445Y1031245D03*
X350595Y1034434D03*
X346894D03*
X345043Y1037623D03*
X350595Y1040812D03*
X346894D03*
X345043Y1044001D03*
X339492Y1034434D03*
Y1040812D03*
X352445Y1037623D03*
X350595Y1047190D03*
X339492D03*
X352445Y1050379D03*
X346894Y1059946D03*
X345043Y1050379D03*
X346894Y1053568D03*
X345043Y1063135D03*
X352445D03*
X346894Y1072702D03*
X350595Y1066324D03*
X345043Y1069513D03*
X350595Y1072702D03*
X346894Y1066324D03*
X339492D03*
Y1072702D03*
X352445Y1069513D03*
Y1075891D03*
X345043D03*
X350595Y1079080D03*
X352445Y1082269D03*
X350595Y1085458D03*
X352445Y1088647D03*
X346894Y1079080D03*
X345043Y1082269D03*
Y1088647D03*
X346894Y1085458D03*
X339492Y1079080D03*
Y1085458D03*
X346894Y1091836D03*
X350595D03*
X339492D03*
X345043Y1101403D03*
X350595Y1104592D03*
X345043Y1095025D03*
X350595Y1098214D03*
X346894D03*
Y1104592D03*
X339492D03*
Y1098214D03*
X352445Y1095025D03*
Y1101403D03*
Y1107781D03*
X345043D03*
X352445Y1114159D03*
X350595Y1117348D03*
Y1110970D03*
X346894D03*
X345043Y1114159D03*
X346894Y1117348D03*
X339492D03*
Y1110970D03*
X345043Y1120537D03*
X352445D03*
X350595Y1123726D03*
X346894Y1130103D03*
X345043Y1133293D03*
Y1126915D03*
X346894Y1123726D03*
X350595Y1130103D03*
X339492Y1123726D03*
Y1130103D03*
X352445Y1133293D03*
Y1126915D03*
X350595Y1136481D03*
X346894D03*
X339492D03*
X352445Y1139670D03*
X350595Y1142859D03*
X352445Y1146048D03*
X350595Y1149237D03*
X345043Y1139670D03*
X346894Y1149237D03*
X345043Y1146048D03*
X346894Y1142859D03*
X339492D03*
Y1149237D03*
X345043Y1152426D03*
X352445D03*
X350595Y1155615D03*
X339839Y1516970D03*
X344563D03*
X349288D03*
X341414Y1519698D03*
X346138D03*
X350862D03*
X349288Y1530608D03*
X350862Y1533336D03*
X339839Y1530608D03*
X344563D03*
X341414Y1533336D03*
X346138D03*
X358665Y886002D03*
X364217Y889191D03*
X356815D03*
X362366Y892380D03*
X356815Y895569D03*
X364217D03*
X358665Y892380D03*
Y898758D03*
X362366D03*
X364217Y901947D03*
Y908325D03*
X356815D03*
X362366Y911513D03*
X356815Y901947D03*
X362366Y905135D03*
X358665D03*
Y911513D03*
Y917891D03*
X364217Y921080D03*
X356815D03*
X362366Y924269D03*
X358665D03*
X356815Y914702D03*
X364217D03*
X362366Y917891D03*
X364217Y927458D03*
X356815D03*
X364217Y940214D03*
Y933836D03*
X362366Y930647D03*
X358665Y937025D03*
X356815Y940214D03*
Y933836D03*
X358665Y930647D03*
X362366Y937025D03*
Y943403D03*
X358665D03*
X364217Y946592D03*
X356815D03*
X362366Y949781D03*
X358665Y956159D03*
X356815Y952970D03*
X364217D03*
X358665Y949781D03*
X362366Y956159D03*
X364217Y965726D03*
Y959348D03*
X358665Y962537D03*
X356815Y965726D03*
X362366Y968915D03*
X356815Y959348D03*
X362366Y962537D03*
X358665Y968915D03*
X356815Y972104D03*
X364217D03*
Y984860D03*
X358665Y975293D03*
X364217Y978482D03*
X356815D03*
X362366Y981671D03*
Y975293D03*
Y988049D03*
X364217Y997616D03*
X358665Y994427D03*
X356815Y997616D03*
X362366Y1000805D03*
X358665D03*
X356815Y991238D03*
X362366Y994427D03*
X356815Y1010372D03*
X358665Y1007183D03*
X356815Y1003994D03*
X364217D03*
X362366Y1007183D03*
X363547Y1031245D03*
X365398Y1034434D03*
X357996D03*
X359847Y1037623D03*
X363547D03*
X365398Y1040812D03*
X357996D03*
X359847Y1044001D03*
X365398Y1047190D03*
X363547Y1050379D03*
X357996Y1059946D03*
X359847Y1050379D03*
X357996Y1053568D03*
X363547Y1063135D03*
X359847D03*
X357996Y1072702D03*
X365398Y1066324D03*
X363547Y1069513D03*
X359847D03*
X365398Y1072702D03*
X357996Y1066324D03*
X363547Y1075891D03*
X359847D03*
X365398Y1079080D03*
X363547Y1082269D03*
X365398Y1085458D03*
X363547Y1088647D03*
X357996Y1079080D03*
X359847Y1082269D03*
Y1088647D03*
X357996Y1085458D03*
Y1091836D03*
X365398D03*
X359847Y1101403D03*
X365398Y1104592D03*
X363547Y1095025D03*
X359847D03*
X365398Y1098214D03*
X357996D03*
X363547Y1101403D03*
X357996Y1104592D03*
X363547Y1107781D03*
X359847D03*
X363547Y1114159D03*
X365398Y1117348D03*
Y1110970D03*
X357996D03*
X359847Y1114159D03*
X357996Y1117348D03*
X363547Y1120537D03*
X359847D03*
X365398Y1123726D03*
X357996Y1130103D03*
X363547Y1133293D03*
X359847D03*
Y1126915D03*
X363547D03*
X357996Y1123726D03*
X365398Y1130103D03*
Y1136481D03*
X357996D03*
X363547Y1139670D03*
X365398Y1142859D03*
X363547Y1146048D03*
X365398Y1149237D03*
X359847Y1139670D03*
X357996Y1149237D03*
X359847Y1146048D03*
X357996Y1142859D03*
X363547Y1152426D03*
X359847D03*
X357996Y1155615D03*
X363461Y1516970D03*
X354012D03*
X358736D03*
X365036Y1519698D03*
X355587D03*
X360311D03*
X365036Y1533336D03*
X363461Y1530608D03*
X354012D03*
X358736D03*
X355587Y1533336D03*
X360311D03*
X369768Y886002D03*
X375319Y889191D03*
X371618D03*
X377169Y892380D03*
X371618Y895569D03*
X375319D03*
X369768Y892380D03*
Y898758D03*
X377169D03*
X371618Y908325D03*
X377169Y911513D03*
X375319Y901947D03*
X371618D03*
X377169Y905135D03*
X369768D03*
X375319Y908325D03*
X369768Y911513D03*
Y917891D03*
X375319Y921080D03*
X371618D03*
X377169Y924269D03*
X369768D03*
X371618Y914702D03*
X375319D03*
X377169Y917891D03*
X375319Y927458D03*
X371618D03*
X377169Y930647D03*
X369768Y937025D03*
X375319Y940214D03*
X371618D03*
Y933836D03*
X375319D03*
X369768Y930647D03*
X377169Y937025D03*
Y943403D03*
X369768D03*
X375319Y946592D03*
X371618D03*
X377169Y949781D03*
X369768Y956159D03*
X371618Y952970D03*
X375319D03*
X369768Y949781D03*
X377169Y956159D03*
X369768Y962537D03*
X375319Y965726D03*
X371618D03*
X377169Y968915D03*
X375319Y959348D03*
X371618D03*
X377169Y962537D03*
X369768Y968915D03*
X371618Y972104D03*
X375319D03*
Y984860D03*
X369768Y975293D03*
X375319Y978482D03*
X371618D03*
X377169Y981671D03*
Y975293D03*
Y988049D03*
X369768Y994427D03*
X371618Y997616D03*
X375319D03*
X377169Y1000805D03*
X369768D03*
X371618Y991238D03*
X377169Y994427D03*
X371618Y1010372D03*
X369768Y1007183D03*
X371618Y1003994D03*
X375319D03*
X377169Y1007183D03*
X378351Y1031245D03*
X376500Y1034434D03*
X372799D03*
X370949Y1037623D03*
X378351D03*
X376500Y1040812D03*
X372799D03*
X370949Y1044001D03*
X376500Y1047190D03*
X378351Y1050379D03*
X372799Y1059946D03*
X370949Y1050379D03*
X372799Y1053568D03*
X378351Y1063135D03*
X370949D03*
X372799Y1072702D03*
X376500Y1066324D03*
X378351Y1069513D03*
X370949D03*
X376500Y1072702D03*
X372799Y1066324D03*
X378351Y1075891D03*
X370949D03*
X376500Y1079080D03*
X372799D03*
X378351Y1082269D03*
X370949D03*
X376500Y1085458D03*
X370949Y1088647D03*
X378351D03*
X372799Y1085458D03*
Y1091836D03*
X376500D03*
X370949Y1101403D03*
X376500Y1104592D03*
X378351Y1095025D03*
X370949D03*
X376500Y1098214D03*
X372799D03*
X378351Y1101403D03*
X372799Y1104592D03*
X370949Y1107781D03*
X378351D03*
X372799Y1110970D03*
X378351Y1114159D03*
X370949D03*
X376500Y1117348D03*
X372799D03*
X376500Y1110970D03*
X378351Y1120537D03*
X370949D03*
X376500Y1123726D03*
X372799Y1130103D03*
X378351Y1133293D03*
X370949D03*
Y1126915D03*
X378351D03*
X372799Y1123726D03*
X376500Y1130103D03*
Y1136481D03*
X372799D03*
X378351Y1139670D03*
X370949D03*
X376500Y1142859D03*
X372799Y1149237D03*
X370949Y1146048D03*
X378351D03*
X372799Y1142859D03*
X376500Y1149237D03*
X378351Y1152426D03*
X370949D03*
X376500Y1155615D03*
X382051Y1158804D03*
X368185Y1516970D03*
X372910D03*
X377634D03*
X369760Y1519698D03*
X374484D03*
X379209D03*
X382359Y1516970D03*
Y1530608D03*
X379209Y1533336D03*
X368185Y1530608D03*
X372910D03*
X377634D03*
X369760Y1533336D03*
X374484D03*
X388272Y892380D03*
X384571D03*
X395673D03*
Y898758D03*
X388272D03*
X384571D03*
X395673Y905135D03*
Y911513D03*
X388272D03*
Y905135D03*
X384571Y911513D03*
Y905135D03*
X388272Y924269D03*
Y917891D03*
X384571Y924269D03*
Y917891D03*
X395673Y924269D03*
Y917891D03*
Y930647D03*
X388272D03*
X384571D03*
Y943403D03*
X395673D03*
X388272D03*
X384571Y949781D03*
Y956159D03*
X395673Y949781D03*
Y956159D03*
X388272Y949781D03*
Y956159D03*
X395673Y962537D03*
Y968915D03*
X384571Y962537D03*
Y968915D03*
X388272Y962537D03*
Y968915D03*
X395673Y975293D03*
X384571D03*
X388272D03*
X396855Y1107781D03*
X389453D03*
X385752D03*
X396855Y1114159D03*
X389453D03*
X385752D03*
X389453Y1120537D03*
X385752D03*
X396855D03*
X389453Y1126915D03*
Y1133293D03*
X385752Y1126915D03*
Y1133293D03*
X396855Y1126915D03*
Y1133293D03*
Y1139670D03*
Y1146048D03*
X389453Y1139670D03*
Y1146048D03*
X385752Y1139670D03*
Y1146048D03*
X389453Y1152426D03*
X385752D03*
X396855D03*
X385752Y1158804D03*
X393154D03*
X396855D03*
X387083Y1516970D03*
X383933Y1519698D03*
X388658D03*
X387083Y1530608D03*
X383933Y1533336D03*
X388658D03*
X399374Y892380D03*
X410477D03*
X406776D03*
X410477Y898758D03*
X399374D03*
X406776D03*
X410477Y905135D03*
Y911513D03*
X399374Y905135D03*
X406776D03*
X399374Y911513D03*
X406776D03*
X399374Y924269D03*
Y917891D03*
X410477D03*
Y924269D03*
X406776Y917891D03*
Y924269D03*
X399374Y930647D03*
X406776Y943403D03*
X399374D03*
X410477D03*
X406776Y949781D03*
Y956159D03*
X399374Y949781D03*
Y956159D03*
X410477Y949781D03*
Y956159D03*
Y962537D03*
Y968915D03*
X406776Y962537D03*
Y968915D03*
X399374Y962537D03*
Y968915D03*
X406776Y975293D03*
X399374D03*
X410477D03*
X400555Y1107781D03*
X411658Y1114159D03*
X400555D03*
X407957D03*
X400555Y1120537D03*
X407957D03*
X411658D03*
X400555Y1126915D03*
X407957D03*
X400555Y1133293D03*
X407957D03*
X411658Y1126915D03*
Y1133293D03*
Y1139670D03*
Y1146048D03*
X400555Y1139670D03*
Y1146048D03*
X407957Y1139670D03*
Y1146048D03*
X400555Y1152426D03*
X407957D03*
X411658D03*
X407957Y1158804D03*
X404256D03*
X421579Y892380D03*
X417878D03*
X427130Y895569D03*
X421579Y898758D03*
X417878D03*
X427130Y901947D03*
Y908325D03*
X421579Y905135D03*
X417878D03*
X421579Y911513D03*
X417878D03*
X421579Y917891D03*
Y924269D03*
X417878Y917891D03*
Y924269D03*
X427130Y914702D03*
Y921080D03*
Y927458D03*
Y940214D03*
X417878Y937025D03*
X421579D03*
X417878Y943403D03*
X421579D03*
X417878Y956159D03*
Y949781D03*
X421579Y956159D03*
Y949781D03*
X427130Y946592D03*
Y952970D03*
Y959348D03*
Y965726D03*
X417878Y962537D03*
Y968915D03*
X421579Y962537D03*
Y968915D03*
X427130Y972104D03*
X417878Y975293D03*
X421579D03*
X427130Y978482D03*
X422760Y1114159D03*
X419059D03*
X422760Y1120537D03*
X419059D03*
X422760Y1126915D03*
X419059D03*
X422760Y1133293D03*
X419059D03*
X422760Y1139670D03*
Y1146048D03*
X419059Y1139670D03*
Y1146048D03*
X422760Y1152426D03*
X419059D03*
Y1158804D03*
X415358D03*
X430831Y895569D03*
Y901947D03*
Y908325D03*
Y914702D03*
Y921080D03*
Y927458D03*
Y940214D03*
Y946592D03*
Y952970D03*
Y959348D03*
Y965726D03*
Y972104D03*
Y978482D03*
X432012Y1117348D03*
Y1110970D03*
X428311Y1117348D03*
Y1110970D03*
X432012Y1123726D03*
X428311D03*
X432012Y1130103D03*
X428311D03*
X432012Y1136481D03*
X428311D03*
X432012Y1142859D03*
X428311D03*
X449310Y895569D03*
X453011D03*
Y908325D03*
Y901947D03*
X449310Y908325D03*
Y901947D03*
Y921080D03*
Y914702D03*
X453011Y921080D03*
Y914702D03*
Y927458D03*
X449310D03*
X453011Y940214D03*
X449310D03*
X453011Y952970D03*
Y946592D03*
X449310Y952970D03*
Y946592D03*
X453011Y959348D03*
Y965726D03*
X449310Y959348D03*
Y965726D03*
X453011Y972104D03*
X449310D03*
X453011Y978482D03*
X449310D03*
X454192Y1110970D03*
Y1117348D03*
X450491Y1110970D03*
Y1117348D03*
Y1123726D03*
X454192D03*
X450491Y1130103D03*
X454192D03*
Y1136481D03*
X450491D03*
X454192Y1142859D03*
X450491D03*
X452328Y1516970D03*
X453903Y1519698D03*
X457052Y1516970D03*
Y1530608D03*
X453903Y1533336D03*
X452328Y1530608D03*
X458562Y892380D03*
X469664D03*
X462263D03*
X469664Y898758D03*
X458562D03*
X462263D03*
X469664Y905135D03*
Y911513D03*
X458562Y905135D03*
X462263D03*
X458562Y911513D03*
X462263D03*
X458562Y924269D03*
Y917891D03*
X469664Y924269D03*
Y917891D03*
X462263Y924269D03*
Y917891D03*
Y937025D03*
X458562D03*
X462263Y943403D03*
X458562D03*
X469664D03*
X462263Y956159D03*
Y949781D03*
X458562Y956159D03*
Y949781D03*
X469664Y956159D03*
Y949781D03*
Y962537D03*
Y968915D03*
X462263Y962537D03*
Y968915D03*
X458562Y962537D03*
Y968915D03*
X462263Y975293D03*
X458562D03*
X469664D03*
X470845Y1114159D03*
X459743D03*
X463444D03*
X459743Y1120537D03*
X463444D03*
X470845D03*
X459743Y1126915D03*
X463444D03*
X459743Y1133293D03*
X463444D03*
X470845Y1126915D03*
Y1133293D03*
Y1146048D03*
Y1139670D03*
X459743Y1146048D03*
Y1139670D03*
X463444Y1146048D03*
Y1139670D03*
X461777Y1516970D03*
X466501D03*
X458627Y1519698D03*
X463351D03*
X468076D03*
X471225Y1516970D03*
Y1530608D03*
X468076Y1533336D03*
X461777Y1530608D03*
X466501D03*
X458627Y1533336D03*
X463351D03*
X480767Y892380D03*
X484467D03*
X473365D03*
X484467Y898758D03*
X480767D03*
X473365D03*
X484467Y905135D03*
Y911513D03*
X480767Y905135D03*
X473365D03*
X480767Y911513D03*
X473365D03*
X480767Y917891D03*
Y924269D03*
X484467Y917891D03*
Y924269D03*
X473365D03*
Y917891D03*
X484467Y930647D03*
X480767D03*
X484467Y943403D03*
X473365D03*
X480767D03*
X484467Y956159D03*
Y949781D03*
X473365Y956159D03*
Y949781D03*
X480767Y956159D03*
Y949781D03*
X484467Y962537D03*
Y968915D03*
X473365Y962537D03*
Y968915D03*
X480767Y962537D03*
Y968915D03*
X484467Y975293D03*
X473365D03*
X480767D03*
X485649Y1107781D03*
X481948D03*
X485649Y1114159D03*
X481948D03*
X474546D03*
X481948Y1120537D03*
X474546D03*
X485649D03*
X481948Y1126915D03*
X474546D03*
X481948Y1133293D03*
X474546D03*
X485649Y1126915D03*
Y1133293D03*
Y1146048D03*
Y1139670D03*
X481948Y1146048D03*
Y1139670D03*
X474546Y1146048D03*
Y1139670D03*
X475950Y1516970D03*
X480674D03*
X472800Y1519698D03*
X477525D03*
X482249D03*
X485399Y1516970D03*
X486973Y1519698D03*
X485399Y1530608D03*
X486973Y1533336D03*
X475950Y1530608D03*
X480674D03*
X472800Y1533336D03*
X477525D03*
X482249D03*
X491869Y892380D03*
X495570D03*
X491869Y898758D03*
X495570D03*
X491869Y905135D03*
Y911513D03*
X495570Y905135D03*
Y911513D03*
X491869Y917891D03*
Y924269D03*
X495570Y917891D03*
Y924269D03*
X491869Y930647D03*
X495570D03*
Y943403D03*
X491869D03*
X495570Y956159D03*
Y949781D03*
X491869Y956159D03*
Y949781D03*
X495570Y962537D03*
Y968915D03*
X491869Y962537D03*
Y968915D03*
X495570Y975293D03*
X491869D03*
X493050Y1107781D03*
X496751D03*
X493050Y1114159D03*
X496751D03*
X493050Y1120537D03*
X496751D03*
X493050Y1133293D03*
Y1126915D03*
X496751Y1133293D03*
Y1126915D03*
X493050Y1146048D03*
Y1139670D03*
X496751Y1146048D03*
Y1139670D03*
X499572Y1516970D03*
X490123D03*
X494847D03*
X491698Y1519698D03*
X496422D03*
X501147D03*
X499572Y1530608D03*
X501147Y1533336D03*
X490123Y1530608D03*
X494847D03*
X491698Y1533336D03*
X496422D03*
X510373Y886002D03*
X504822Y889191D03*
X508523D03*
X502971Y892380D03*
X508523Y895569D03*
X504822D03*
X510373Y892380D03*
X515924Y889191D03*
Y895569D03*
X510373Y898758D03*
X502971D03*
X515924Y901947D03*
Y908325D03*
X508523D03*
X502971Y911513D03*
X504822Y901947D03*
X508523D03*
X502971Y905135D03*
X510373D03*
X504822Y908325D03*
X510373Y911513D03*
Y917891D03*
X504822Y921080D03*
X508523D03*
X502971Y924269D03*
X510373D03*
X508523Y914702D03*
X504822D03*
X502971Y917891D03*
X515924Y921080D03*
Y914702D03*
Y927458D03*
X504822D03*
X508523D03*
X515924Y940214D03*
Y933836D03*
X502971Y930647D03*
X510373Y937025D03*
X504822Y940214D03*
X508523D03*
Y933836D03*
X504822D03*
X510373Y930647D03*
X502971Y937025D03*
Y943403D03*
X510373D03*
X504822Y946592D03*
X508523D03*
X502971Y949781D03*
X510373Y956159D03*
X508523Y952970D03*
X504822D03*
X510373Y949781D03*
X502971Y956159D03*
X515924Y946592D03*
Y952970D03*
Y965726D03*
Y959348D03*
X510373Y962537D03*
X504822Y965726D03*
X508523D03*
X502971Y968915D03*
X504822Y959348D03*
X508523D03*
X502971Y962537D03*
X510373Y968915D03*
X508523Y972104D03*
X504822D03*
X515924D03*
X504822Y984860D03*
X510373Y975293D03*
X504822Y978482D03*
X508523D03*
X502971Y981671D03*
Y975293D03*
X515924Y984860D03*
Y978482D03*
X502971Y988049D03*
X510373D03*
X515924Y997616D03*
Y991238D03*
X510373Y994427D03*
X508523Y997616D03*
X504822D03*
X502971Y1000805D03*
X510373D03*
X504822Y991238D03*
X508523Y1010372D03*
X510373Y1007183D03*
X508523Y1003994D03*
X504822D03*
X502971Y1007183D03*
X515924Y1003994D03*
X504153Y1031245D03*
X506003Y1034434D03*
X509704D03*
X511554Y1037623D03*
X504153D03*
X506003Y1040812D03*
X509704D03*
X504153Y1044001D03*
X517105Y1034434D03*
Y1040812D03*
Y1047190D03*
X506003D03*
X504153Y1050379D03*
X509704Y1059946D03*
X511554Y1050379D03*
X509704Y1053568D03*
X504153Y1063135D03*
X511554D03*
X509704Y1072702D03*
X506003Y1066324D03*
X504153Y1069513D03*
X511554D03*
X506003Y1072702D03*
X509704Y1066324D03*
X517105D03*
Y1072702D03*
X504153Y1075891D03*
X511554D03*
X517105Y1079080D03*
Y1085458D03*
X506003Y1079080D03*
X509704D03*
X504153Y1082269D03*
X511554D03*
X506003Y1085458D03*
X511554Y1088647D03*
X504153D03*
X509704Y1085458D03*
Y1091836D03*
X506003D03*
X517105D03*
X511554Y1101403D03*
X506003Y1104592D03*
X504153Y1095025D03*
X511554D03*
X506003Y1098214D03*
X509704D03*
X504153Y1101403D03*
X509704Y1104592D03*
X517105D03*
Y1098214D03*
X511554Y1107781D03*
X504153D03*
X517105Y1117348D03*
Y1110970D03*
X509704D03*
X504153Y1114159D03*
X511554D03*
X506003Y1117348D03*
X509704D03*
X506003Y1110970D03*
X504153Y1120537D03*
X511554D03*
X506003Y1123726D03*
X509704Y1130103D03*
X504153Y1133293D03*
X511554D03*
Y1126915D03*
X504153D03*
X509704Y1123726D03*
X506003Y1130103D03*
X517105Y1123726D03*
Y1130103D03*
Y1136481D03*
X506003D03*
X509704D03*
X517105Y1142859D03*
Y1149237D03*
X504153Y1139670D03*
X511554D03*
X506003Y1142859D03*
X509704Y1149237D03*
X511554Y1146048D03*
X504153D03*
X509704Y1142859D03*
X506003Y1149237D03*
X504153Y1152426D03*
X511554D03*
X506003Y1155615D03*
X504296Y1516970D03*
X509021D03*
X513745D03*
X505871Y1519698D03*
X510595D03*
X515320D03*
X513745Y1530608D03*
X515320Y1533336D03*
X504296Y1530608D03*
X509021D03*
X505871Y1533336D03*
X510595D03*
X528877Y892380D03*
X521475Y886002D03*
X523326Y889191D03*
X517775Y892380D03*
X523326Y895569D03*
X521475Y892380D03*
X530727Y889191D03*
Y895569D03*
X528877Y898758D03*
X521475D03*
X517775D03*
X528877Y911513D03*
X530727Y901947D03*
X528877Y905135D03*
X530727Y908325D03*
X523326D03*
X517775Y911513D03*
X523326Y901947D03*
X517775Y905135D03*
X521475D03*
Y911513D03*
X528877Y924269D03*
Y917891D03*
X521475D03*
X523326Y921080D03*
X517775Y924269D03*
X521475D03*
X523326Y914702D03*
X517775Y917891D03*
X530727Y921080D03*
Y914702D03*
Y927458D03*
X523326D03*
X528877Y930647D03*
X530727Y940214D03*
Y933836D03*
X528877Y937025D03*
X517775Y930647D03*
X521475Y937025D03*
X523326Y940214D03*
Y933836D03*
X521475Y930647D03*
X517775Y937025D03*
X528877Y943403D03*
X517775D03*
X521475D03*
X528877Y949781D03*
Y956159D03*
X523326Y946592D03*
X517775Y949781D03*
X521475Y956159D03*
X523326Y952970D03*
X521475Y949781D03*
X517775Y956159D03*
X530727Y946592D03*
Y952970D03*
Y965726D03*
X528877Y968915D03*
X530727Y959348D03*
X528877Y962537D03*
X521475D03*
X523326Y965726D03*
X517775Y968915D03*
X523326Y959348D03*
X517775Y962537D03*
X521475Y968915D03*
X523326Y972104D03*
X530727D03*
X528877Y981671D03*
Y975293D03*
X521475D03*
X523326Y978482D03*
X517775Y981671D03*
Y975293D03*
X530727Y984860D03*
Y978482D03*
X528877Y988049D03*
X517775D03*
X521475D03*
X530727Y997616D03*
X528877Y1000805D03*
X530727Y991238D03*
X521475Y994427D03*
X523326Y997616D03*
X517775Y1000805D03*
X521475D03*
X528877Y1007183D03*
X523326Y1010372D03*
X521475Y1007183D03*
X523326Y1003994D03*
X517775Y1007183D03*
X530727Y1003994D03*
X518956Y1031245D03*
X530058D03*
X524507Y1034434D03*
X522657Y1037623D03*
X518956D03*
X524507Y1040812D03*
X518956Y1044001D03*
X531908Y1034434D03*
X530058Y1037623D03*
X531908Y1040812D03*
X530058Y1044001D03*
X531908Y1047190D03*
X530058Y1050379D03*
X518956D03*
X524507Y1059946D03*
X522657Y1050379D03*
X524507Y1053568D03*
X518956Y1063135D03*
X522657D03*
X530058D03*
X524507Y1072702D03*
X518956Y1069513D03*
X522657D03*
X524507Y1066324D03*
X531908D03*
X530058Y1069513D03*
X531908Y1072702D03*
X530058Y1075891D03*
X518956D03*
X522657D03*
X531908Y1079080D03*
X530058Y1082269D03*
X531908Y1085458D03*
X530058Y1088647D03*
X524507Y1079080D03*
X518956Y1082269D03*
X522657D03*
Y1088647D03*
X518956D03*
X524507Y1085458D03*
Y1091836D03*
X531908D03*
X522657Y1101403D03*
X518956Y1095025D03*
X522657D03*
X524507Y1098214D03*
X518956Y1101403D03*
X524507Y1104592D03*
X531908D03*
X530058Y1095025D03*
X531908Y1098214D03*
X530058Y1101403D03*
Y1107781D03*
X522657D03*
X518956D03*
X530058Y1114159D03*
X531908Y1117348D03*
Y1110970D03*
X524507D03*
X518956Y1114159D03*
X522657D03*
X524507Y1117348D03*
X518956Y1120537D03*
X522657D03*
X530058D03*
X524507Y1130103D03*
X518956Y1133293D03*
X522657D03*
Y1126915D03*
X518956D03*
X524507Y1123726D03*
X531908D03*
X530058Y1133293D03*
Y1126915D03*
X531908Y1130103D03*
Y1136481D03*
X524507D03*
X530058Y1139670D03*
X531908Y1142859D03*
X530058Y1146048D03*
X531908Y1149237D03*
X518956Y1139670D03*
X522657D03*
X524507Y1149237D03*
X522657Y1146048D03*
X518956D03*
X524507Y1142859D03*
X518956Y1152426D03*
X522657D03*
X530058D03*
X524507Y1155615D03*
X531908D03*
X518470Y1516970D03*
X523194D03*
X520044Y1519698D03*
X524769D03*
X518470Y1530608D03*
X523194D03*
X520044Y1533336D03*
X524769D03*
X536279Y886002D03*
X534428Y889191D03*
Y895569D03*
X536279Y892380D03*
X541830Y889191D03*
X543680Y892380D03*
X541830Y895569D03*
X543680Y898758D03*
X536279D03*
X543680Y911513D03*
Y905135D03*
X534428Y908325D03*
Y901947D03*
X536279Y905135D03*
Y911513D03*
X541830Y901947D03*
Y908325D03*
X536279Y917891D03*
X534428Y921080D03*
X536279Y924269D03*
X534428Y914702D03*
X541830Y921080D03*
X543680Y924269D03*
X541830Y914702D03*
X543680Y917891D03*
X534428Y927458D03*
X541830D03*
X543680Y930647D03*
Y937025D03*
X536279D03*
X534428Y940214D03*
Y933836D03*
X536279Y930647D03*
X541830Y940214D03*
Y933836D03*
X536279Y943403D03*
X543680D03*
X534428Y946592D03*
X536279Y956159D03*
X534428Y952970D03*
X536279Y949781D03*
X541830Y946592D03*
X543680Y949781D03*
X541830Y952970D03*
X543680Y956159D03*
Y968915D03*
Y962537D03*
X536279D03*
X534428Y965726D03*
Y959348D03*
X536279Y968915D03*
X541830Y965726D03*
Y959348D03*
X534428Y972104D03*
X541830D03*
X536279Y975293D03*
X534428Y978482D03*
X541830Y984860D03*
Y978482D03*
X543680Y981671D03*
Y975293D03*
Y988049D03*
X536279D03*
X543680Y1000805D03*
X536279Y994427D03*
X534428Y997616D03*
X536279Y1000805D03*
X541830Y997616D03*
Y991238D03*
X534428Y1010372D03*
X536279Y1007183D03*
X534428Y1003994D03*
X541830D03*
X543680Y1007183D03*
X544861Y1031245D03*
X535609Y1034434D03*
X537460Y1037623D03*
X535609Y1040812D03*
X543011Y1034434D03*
Y1040812D03*
X544861Y1037623D03*
Y1044001D03*
X543011Y1047190D03*
X544861Y1050379D03*
X535609Y1059946D03*
X537460Y1050379D03*
X535609Y1053568D03*
X537460Y1063135D03*
X544861D03*
X535609Y1072702D03*
X537460Y1069513D03*
X535609Y1066324D03*
X543011D03*
Y1072702D03*
X544861Y1069513D03*
Y1075891D03*
X537460D03*
X543011Y1079080D03*
X544861Y1082269D03*
X543011Y1085458D03*
X544861Y1088647D03*
X535609Y1079080D03*
X537460Y1082269D03*
Y1088647D03*
X535609Y1085458D03*
Y1091836D03*
X543011D03*
X537460Y1101403D03*
Y1095025D03*
X535609Y1098214D03*
Y1104592D03*
X543011D03*
Y1098214D03*
X544861Y1095025D03*
Y1101403D03*
Y1107781D03*
X537460D03*
X544861Y1114159D03*
X543011Y1117348D03*
Y1110970D03*
X535609D03*
X537460Y1114159D03*
X535609Y1117348D03*
X537460Y1120537D03*
X544861D03*
X535609Y1130103D03*
X537460Y1133293D03*
Y1126915D03*
X535609Y1123726D03*
X543011D03*
Y1130103D03*
X544861Y1133293D03*
Y1126915D03*
X543011Y1136481D03*
X535609D03*
X544861Y1139670D03*
X543011Y1142859D03*
X544861Y1146048D03*
X543011Y1149237D03*
X537460Y1139670D03*
X535609Y1149237D03*
X537460Y1146048D03*
X535609Y1142859D03*
X537460Y1152426D03*
X544861D03*
X556633Y889191D03*
X554783Y892380D03*
X556633Y895569D03*
X547381Y886002D03*
X549231Y889191D03*
Y895569D03*
X547381Y892380D03*
X560334Y889191D03*
Y895569D03*
X554783Y898758D03*
X547381D03*
X560334Y908325D03*
Y901947D03*
X554783Y911513D03*
X556633Y901947D03*
X554783Y905135D03*
X556633Y908325D03*
X549231D03*
Y901947D03*
X547381Y905135D03*
Y911513D03*
X556633Y921080D03*
X554783Y924269D03*
X556633Y914702D03*
X554783Y917891D03*
X547381D03*
X549231Y921080D03*
X547381Y924269D03*
X549231Y914702D03*
X560334Y921080D03*
Y914702D03*
Y927458D03*
X556633D03*
X549231D03*
X560334Y940214D03*
Y933836D03*
X554783Y930647D03*
X556633Y940214D03*
Y933836D03*
X554783Y937025D03*
X547381D03*
X549231Y940214D03*
Y933836D03*
X547381Y930647D03*
X554783Y943403D03*
X547381D03*
X556633Y946592D03*
X554783Y949781D03*
X556633Y952970D03*
X554783Y956159D03*
X549231Y946592D03*
X547381Y956159D03*
X549231Y952970D03*
X547381Y949781D03*
X560334Y946592D03*
Y952970D03*
Y965726D03*
Y959348D03*
X556633Y965726D03*
X554783Y968915D03*
X556633Y959348D03*
X554783Y962537D03*
X547381D03*
X549231Y965726D03*
Y959348D03*
X547381Y968915D03*
X556633Y972104D03*
X549231D03*
X560334D03*
X556633Y984860D03*
Y978482D03*
X554783Y981671D03*
Y975293D03*
X547381D03*
X549231Y978482D03*
X560334D03*
X554783Y988049D03*
X547381D03*
X560334Y997616D03*
X556633D03*
X554783Y1000805D03*
X556633Y991238D03*
X547381Y994427D03*
X549231Y997616D03*
X547381Y1000805D03*
X556633Y1003994D03*
X554783Y1007183D03*
X549231Y1010372D03*
X547381Y1007183D03*
X549231Y1003994D03*
X560334Y1010372D03*
Y1003994D03*
X555964Y1031245D03*
X557814Y1034434D03*
X555964Y1037623D03*
X557814Y1040812D03*
X555964Y1044001D03*
X550412Y1034434D03*
X548562Y1037623D03*
X550412Y1040812D03*
X561515Y1034434D03*
Y1040812D03*
X557814Y1047190D03*
X561515Y1059946D03*
Y1053568D03*
X555964Y1050379D03*
X550412Y1059946D03*
X548562Y1050379D03*
X550412Y1053568D03*
X555964Y1063135D03*
X548562D03*
X557814Y1066324D03*
X555964Y1069513D03*
X557814Y1072702D03*
X550412D03*
X548562Y1069513D03*
X550412Y1066324D03*
X561515Y1072702D03*
Y1066324D03*
X555964Y1075891D03*
X548562D03*
X557814Y1079080D03*
X561515D03*
X557814Y1085458D03*
X561515D03*
X555964Y1082269D03*
Y1088647D03*
X550412Y1079080D03*
X548562Y1082269D03*
Y1088647D03*
X550412Y1085458D03*
X557814Y1091836D03*
X550412D03*
X561515D03*
X557814Y1104592D03*
X555964Y1095025D03*
X557814Y1098214D03*
X555964Y1101403D03*
X548562D03*
Y1095025D03*
X550412Y1098214D03*
Y1104592D03*
X561515Y1098214D03*
Y1104592D03*
X555964Y1107781D03*
X548562D03*
X561515Y1110970D03*
X557814Y1117348D03*
X561515D03*
X557814Y1110970D03*
X555964Y1114159D03*
X550412Y1110970D03*
X548562Y1114159D03*
X550412Y1117348D03*
X555964Y1120537D03*
X548562D03*
X557814Y1123726D03*
X555964Y1133293D03*
Y1126915D03*
X557814Y1130103D03*
X550412D03*
X548562Y1133293D03*
Y1126915D03*
X550412Y1123726D03*
X561515Y1130103D03*
Y1123726D03*
X557814Y1136481D03*
X561515D03*
X550412D03*
X557814Y1142859D03*
X561515Y1149237D03*
Y1142859D03*
X557814Y1149237D03*
X555964Y1139670D03*
Y1146048D03*
X548562Y1139670D03*
X550412Y1149237D03*
X548562Y1146048D03*
X550412Y1142859D03*
X555964Y1152426D03*
X548562D03*
X557814Y1155615D03*
X550412D03*
X562184Y886002D03*
Y892380D03*
Y898758D03*
Y905135D03*
Y911513D03*
Y917891D03*
Y924269D03*
Y937025D03*
Y930647D03*
Y943403D03*
Y956159D03*
Y949781D03*
Y962537D03*
Y968915D03*
Y975293D03*
Y988049D03*
Y994427D03*
Y1000805D03*
Y1007183D03*
X563365Y1037623D03*
Y1050379D03*
Y1063135D03*
Y1069513D03*
Y1075891D03*
Y1082269D03*
Y1088647D03*
Y1101403D03*
Y1095025D03*
Y1107781D03*
Y1114159D03*
Y1120537D03*
Y1133293D03*
Y1126915D03*
Y1139670D03*
Y1146048D03*
Y1152426D03*
X580390Y1516970D03*
X585114D03*
X581965Y1519698D03*
X586689D03*
X589839Y1516970D03*
X591413Y1519698D03*
X589839Y1530608D03*
X591413Y1533336D03*
X580390Y1530608D03*
X585114D03*
X581965Y1533336D03*
X586689D03*
X594563Y1516970D03*
X599287D03*
X604012D03*
X596138Y1519698D03*
X600862D03*
X605587D03*
X604012Y1530608D03*
X605587Y1533336D03*
X594563Y1530608D03*
X599287D03*
X596138Y1533336D03*
X600862D03*
X608736Y1516970D03*
X613461D03*
X618185D03*
X610311Y1519698D03*
X615035D03*
X619760D03*
X618185Y1530608D03*
X619760Y1533336D03*
X608736Y1530608D03*
X613461D03*
X610311Y1533336D03*
X615035D03*
X627634Y1516970D03*
X632358D03*
X622909D03*
X629209Y1519698D03*
X633933D03*
X624484D03*
X632358Y1530608D03*
X633933Y1533336D03*
X627634Y1530608D03*
X622909D03*
X629209Y1533336D03*
X624484D03*
X637083Y1516970D03*
X641807D03*
X646532D03*
X638657Y1519698D03*
X643382D03*
X648106D03*
X651256Y1516970D03*
Y1530608D03*
X648106Y1533336D03*
X637083Y1530608D03*
X641807D03*
X646532D03*
X638657Y1533336D03*
X643382D03*
X652831Y1519698D03*
Y1533336D03*
X1196028Y1549970D03*
X1197603Y1552698D03*
X1200752Y1549970D03*
X1202327Y1552698D03*
X1200752Y1563608D03*
X1202327Y1566336D03*
X1196028Y1563608D03*
X1197603Y1566336D03*
X1205477Y1549970D03*
X1210201D03*
X1214925D03*
X1207051Y1552698D03*
X1211776D03*
X1216500D03*
X1214925Y1563608D03*
X1216500Y1566336D03*
X1205477Y1563608D03*
X1210201D03*
X1207051Y1566336D03*
X1211776D03*
X1219650Y1549970D03*
X1224374D03*
X1229099D03*
X1221225Y1552698D03*
X1225949D03*
X1230673D03*
X1229099Y1563608D03*
X1230673Y1566336D03*
X1219650Y1563608D03*
X1224374D03*
X1221225Y1566336D03*
X1225949D03*
X1243272Y1549970D03*
X1233823D03*
X1238547D03*
X1244847Y1552698D03*
X1235398D03*
X1240122D03*
X1243272Y1563608D03*
X1244847Y1566336D03*
X1233823Y1563608D03*
X1238547D03*
X1235398Y1566336D03*
X1240122D03*
X1247996Y1549970D03*
X1252721D03*
X1257445D03*
X1249571Y1552698D03*
X1254295D03*
X1259020D03*
X1262170Y1549970D03*
Y1563608D03*
X1259020Y1566336D03*
X1247996Y1563608D03*
X1252721D03*
X1257445D03*
X1249571Y1566336D03*
X1254295D03*
X1266894Y1549970D03*
X1263744Y1552698D03*
X1268469D03*
X1266894Y1563608D03*
X1263744Y1566336D03*
X1268469D03*
X1294099Y886001D03*
X1299650Y889190D03*
X1295949D03*
X1301500Y892379D03*
X1295949Y895568D03*
X1299650D03*
X1294099Y892379D03*
X1307052Y889190D03*
Y895568D03*
X1294099Y898757D03*
X1301500D03*
X1307052Y908324D03*
Y901946D03*
X1295949Y908324D03*
X1301500Y911512D03*
X1299650Y901946D03*
X1295949D03*
X1301500Y905134D03*
X1294099D03*
X1299650Y908324D03*
X1294099Y911512D03*
Y917890D03*
X1299650Y921079D03*
X1295949D03*
X1301500Y924268D03*
X1294099D03*
X1295949Y914701D03*
X1299650D03*
X1301500Y917890D03*
X1307052Y921079D03*
Y914701D03*
Y927457D03*
X1299650D03*
X1295949D03*
X1307052Y940213D03*
Y933835D03*
X1301500Y930646D03*
X1294099Y937024D03*
X1299650Y940213D03*
X1295949D03*
Y933835D03*
X1299650D03*
X1294099Y930646D03*
X1301500Y937024D03*
Y943402D03*
X1294099D03*
X1299650Y946591D03*
X1295949D03*
X1301500Y949780D03*
X1294099Y956158D03*
X1295949Y952969D03*
X1299650D03*
X1294099Y949780D03*
X1301500Y956158D03*
X1307052Y946591D03*
Y952969D03*
Y965725D03*
Y959347D03*
X1294099Y962536D03*
X1299650Y965725D03*
X1295949D03*
X1301500Y968914D03*
X1299650Y959347D03*
X1295949D03*
X1301500Y962536D03*
X1294099Y968914D03*
X1295949Y972103D03*
X1299650D03*
X1307052D03*
X1299650Y984859D03*
X1294099Y975292D03*
X1299650Y978481D03*
X1295949D03*
X1301500Y981670D03*
Y975292D03*
X1307052Y978481D03*
X1301500Y988048D03*
X1307052Y997615D03*
Y991237D03*
X1294099Y994426D03*
X1295949Y997615D03*
X1299650D03*
X1301500Y1000804D03*
X1294099D03*
X1295949Y991237D03*
X1301500Y994426D03*
X1295949Y1010371D03*
X1294099Y1007182D03*
X1295949Y1003993D03*
X1299650D03*
X1301500Y1007182D03*
X1307052Y1010371D03*
Y1003993D03*
X1302681Y1031244D03*
X1300831Y1034433D03*
X1297130D03*
X1295280Y1037622D03*
X1302681D03*
X1300831Y1040811D03*
X1297130D03*
X1295280Y1044000D03*
X1300831Y1047189D03*
X1302681Y1050378D03*
X1297130Y1059945D03*
X1295280Y1050378D03*
X1297130Y1053567D03*
X1302681Y1063134D03*
X1295280D03*
X1297130Y1072701D03*
X1300831Y1066323D03*
X1302681Y1069512D03*
X1295280D03*
X1300831Y1072701D03*
X1297130Y1066323D03*
X1302681Y1075890D03*
X1295280D03*
X1302681Y1082268D03*
Y1088646D03*
X1300831Y1079079D03*
X1297130D03*
X1295280Y1082268D03*
X1300831Y1085457D03*
X1295280Y1088646D03*
X1297130Y1085457D03*
Y1091835D03*
X1300831D03*
X1295280Y1101402D03*
X1300831Y1104591D03*
X1302681Y1095024D03*
X1295280D03*
X1300831Y1098213D03*
X1297130D03*
X1302681Y1101402D03*
X1297130Y1104591D03*
X1302681Y1107780D03*
X1295280D03*
X1302681Y1114158D03*
X1297130Y1110969D03*
X1295280Y1114158D03*
X1300831Y1117347D03*
X1297130D03*
X1300831Y1110969D03*
X1302681Y1120536D03*
X1295280D03*
X1300831Y1123725D03*
X1297130Y1130102D03*
X1302681Y1133292D03*
X1295280D03*
Y1126914D03*
X1302681D03*
X1297130Y1123725D03*
X1300831Y1130102D03*
Y1136480D03*
X1297130D03*
X1302681Y1139669D03*
Y1146047D03*
X1295280Y1139669D03*
X1300831Y1142858D03*
X1297130Y1149236D03*
X1295280Y1146047D03*
X1297130Y1142858D03*
X1300831Y1149236D03*
X1302681Y1152425D03*
X1295280D03*
X1300831Y1155614D03*
X1308902Y886001D03*
X1314453Y889190D03*
X1312603Y892379D03*
X1314453Y895568D03*
X1308902Y892379D03*
X1320004Y886001D03*
X1321855Y889190D03*
Y895568D03*
X1320004Y892379D03*
Y898757D03*
X1308902D03*
X1312603D03*
X1321855Y908324D03*
Y901946D03*
X1320004Y905134D03*
Y911512D03*
X1312603D03*
X1314453Y901946D03*
X1312603Y905134D03*
X1308902D03*
X1314453Y908324D03*
X1308902Y911512D03*
Y917890D03*
X1314453Y921079D03*
X1312603Y924268D03*
X1308902D03*
X1314453Y914701D03*
X1312603Y917890D03*
X1320004D03*
X1321855Y921079D03*
X1320004Y924268D03*
X1321855Y914701D03*
Y927457D03*
X1314453D03*
X1320004Y937024D03*
X1321855Y940213D03*
Y933835D03*
X1320004Y930646D03*
X1312603D03*
X1308902Y937024D03*
X1314453Y940213D03*
Y933835D03*
X1308902Y930646D03*
X1312603Y937024D03*
Y943402D03*
X1308902D03*
X1320004D03*
X1314453Y946591D03*
X1312603Y949780D03*
X1308902Y956158D03*
X1314453Y952969D03*
X1308902Y949780D03*
X1312603Y956158D03*
X1321855Y946591D03*
X1320004Y956158D03*
X1321855Y952969D03*
X1320004Y949780D03*
Y962536D03*
X1321855Y965725D03*
Y959347D03*
X1320004Y968914D03*
X1308902Y962536D03*
X1314453Y965725D03*
X1312603Y968914D03*
X1314453Y959347D03*
X1312603Y962536D03*
X1308902Y968914D03*
X1314453Y972103D03*
X1321855D03*
X1314453Y984859D03*
X1308902Y975292D03*
X1314453Y978481D03*
X1312603Y981670D03*
Y975292D03*
X1320004D03*
X1321855Y978481D03*
X1312603Y988048D03*
X1320004Y994426D03*
X1321855Y997615D03*
X1320004Y1000804D03*
X1321855Y991237D03*
X1308902Y994426D03*
X1314453Y997615D03*
X1312603Y1000804D03*
X1308902D03*
X1312603Y994426D03*
X1308902Y1007182D03*
X1314453Y1003993D03*
X1312603Y1007182D03*
X1321855Y1010371D03*
X1320004Y1007182D03*
X1321855Y1003993D03*
X1313784Y1031244D03*
X1315634Y1034433D03*
X1308233D03*
X1310083Y1037622D03*
X1313784D03*
X1315634Y1040811D03*
X1308233D03*
X1310083Y1044000D03*
X1321185Y1037622D03*
Y1044000D03*
X1315634Y1047189D03*
X1321185Y1050378D03*
X1313784D03*
X1308233Y1059945D03*
X1310083Y1050378D03*
X1308233Y1053567D03*
X1313784Y1063134D03*
X1310083D03*
X1321185D03*
X1308233Y1072701D03*
X1315634Y1066323D03*
X1313784Y1069512D03*
X1310083D03*
X1315634Y1072701D03*
X1308233Y1066323D03*
X1321185Y1069512D03*
Y1075890D03*
X1313784D03*
X1310083D03*
X1321185Y1082268D03*
Y1088646D03*
X1315634Y1079079D03*
X1308233D03*
X1313784Y1082268D03*
X1310083D03*
X1315634Y1085457D03*
X1310083Y1088646D03*
X1313784D03*
X1308233Y1085457D03*
Y1091835D03*
X1315634D03*
X1310083Y1101402D03*
X1315634Y1104591D03*
X1313784Y1095024D03*
X1310083D03*
X1315634Y1098213D03*
X1308233D03*
X1313784Y1101402D03*
X1308233Y1104591D03*
X1321185Y1101402D03*
Y1095024D03*
Y1107780D03*
X1310083D03*
X1313784D03*
X1321185Y1114158D03*
X1308233Y1110969D03*
X1313784Y1114158D03*
X1310083D03*
X1315634Y1117347D03*
X1308233D03*
X1315634Y1110969D03*
X1313784Y1120536D03*
X1310083D03*
X1321185D03*
X1315634Y1123725D03*
X1308233Y1130102D03*
X1313784Y1133292D03*
X1310083D03*
Y1126914D03*
X1313784D03*
X1308233Y1123725D03*
X1315634Y1130102D03*
X1321185Y1133292D03*
Y1126914D03*
X1315634Y1136480D03*
X1308233D03*
X1321185Y1139669D03*
Y1146047D03*
X1313784Y1139669D03*
X1310083D03*
X1315634Y1142858D03*
X1308233Y1149236D03*
X1310083Y1146047D03*
X1313784D03*
X1308233Y1142858D03*
X1315634Y1149236D03*
X1313784Y1152425D03*
X1310083D03*
X1321185D03*
X1308233Y1155614D03*
X1325556Y889190D03*
X1327406Y892379D03*
X1325556Y895568D03*
X1334807Y886001D03*
X1332957Y889190D03*
Y895568D03*
X1334807Y892379D03*
Y898757D03*
X1327406D03*
X1332957Y908324D03*
Y901946D03*
X1334807Y905134D03*
Y911512D03*
X1327406D03*
X1325556Y901946D03*
X1327406Y905134D03*
X1325556Y908324D03*
Y921079D03*
X1327406Y924268D03*
X1325556Y914701D03*
X1327406Y917890D03*
X1334807D03*
X1332957Y921079D03*
X1334807Y924268D03*
X1332957Y914701D03*
Y927457D03*
X1325556D03*
X1334807Y937024D03*
X1332957Y940213D03*
Y933835D03*
X1334807Y930646D03*
X1327406D03*
X1325556Y940213D03*
Y933835D03*
X1327406Y937024D03*
Y943402D03*
X1334807D03*
X1325556Y946591D03*
X1327406Y949780D03*
X1325556Y952969D03*
X1327406Y956158D03*
X1332957Y946591D03*
X1334807Y956158D03*
X1332957Y952969D03*
X1334807Y949780D03*
Y962536D03*
X1332957Y965725D03*
Y959347D03*
X1334807Y968914D03*
X1325556Y965725D03*
X1327406Y968914D03*
X1325556Y959347D03*
X1327406Y962536D03*
X1325556Y972103D03*
X1332957D03*
X1325556Y984859D03*
Y978481D03*
X1327406Y981670D03*
Y975292D03*
X1334807D03*
X1332957Y978481D03*
X1327406Y988048D03*
X1334807Y994426D03*
X1332957Y997615D03*
X1334807Y1000804D03*
X1332957Y991237D03*
X1325556Y997615D03*
X1327406Y1000804D03*
Y994426D03*
X1325556Y1003993D03*
X1327406Y1007182D03*
X1332957Y1010371D03*
X1334807Y1007182D03*
X1332957Y1003993D03*
X1328587Y1031244D03*
X1326737Y1034433D03*
X1323036D03*
X1328587Y1037622D03*
X1326737Y1040811D03*
X1323036D03*
X1334138Y1034433D03*
Y1040811D03*
X1335989Y1037622D03*
Y1044000D03*
X1326737Y1047189D03*
X1334138Y1059945D03*
X1335989Y1050378D03*
X1334138Y1053567D03*
X1328587Y1050378D03*
X1323036Y1059945D03*
Y1053567D03*
X1328587Y1063134D03*
X1335989D03*
X1323036Y1072701D03*
X1326737Y1066323D03*
X1328587Y1069512D03*
X1326737Y1072701D03*
X1323036Y1066323D03*
X1334138Y1072701D03*
Y1066323D03*
X1335989Y1069512D03*
Y1075890D03*
X1328587D03*
X1334138Y1079079D03*
X1335989Y1082268D03*
Y1088646D03*
X1334138Y1085457D03*
X1326737Y1079079D03*
X1323036D03*
X1328587Y1082268D03*
X1326737Y1085457D03*
X1328587Y1088646D03*
X1323036Y1085457D03*
Y1091835D03*
X1326737D03*
X1334138D03*
X1326737Y1104591D03*
X1328587Y1095024D03*
X1326737Y1098213D03*
X1323036D03*
X1328587Y1101402D03*
X1323036Y1104591D03*
X1334138Y1098213D03*
Y1104591D03*
X1335989Y1101402D03*
Y1095024D03*
Y1107780D03*
X1328587D03*
X1334138Y1110969D03*
X1335989Y1114158D03*
X1334138Y1117347D03*
X1323036Y1110969D03*
X1328587Y1114158D03*
X1326737Y1117347D03*
X1323036D03*
X1326737Y1110969D03*
X1328587Y1120536D03*
X1335989D03*
X1326737Y1123725D03*
X1323036Y1130102D03*
X1328587Y1133292D03*
Y1126914D03*
X1323036Y1123725D03*
X1326737Y1130102D03*
X1334138D03*
Y1123725D03*
X1335989Y1133292D03*
Y1126914D03*
X1334138Y1136480D03*
X1326737D03*
X1323036D03*
X1335989Y1139669D03*
X1334138Y1149236D03*
X1335989Y1146047D03*
X1334138Y1142858D03*
X1328587Y1139669D03*
X1326737Y1142858D03*
X1323036Y1149236D03*
X1328587Y1146047D03*
X1323036Y1142858D03*
X1326737Y1149236D03*
X1328587Y1152425D03*
X1335989D03*
X1326737Y1155614D03*
X1334138D03*
X1324090Y1549970D03*
X1328814D03*
X1333539D03*
X1325665Y1552698D03*
X1330389D03*
X1335113D03*
X1333539Y1563608D03*
X1335113Y1566336D03*
X1324090Y1563608D03*
X1328814D03*
X1325665Y1566336D03*
X1330389D03*
X1345910Y886001D03*
X1347760Y889190D03*
Y895568D03*
X1345910Y892379D03*
X1340359Y889190D03*
X1338508Y892379D03*
X1340359Y895568D03*
X1351461Y889190D03*
Y895568D03*
X1345910Y898757D03*
X1338508D03*
X1347760Y908324D03*
X1351461Y901946D03*
X1347760D03*
X1351461Y908324D03*
X1345910Y905134D03*
Y911512D03*
X1338508D03*
X1340359Y901946D03*
X1338508Y905134D03*
X1340359Y908324D03*
X1345910Y917890D03*
X1347760Y921079D03*
X1345910Y924268D03*
X1347760Y914701D03*
X1340359Y921079D03*
X1338508Y924268D03*
X1340359Y914701D03*
X1338508Y917890D03*
X1351461Y921079D03*
Y914701D03*
Y927457D03*
X1347760D03*
X1340359D03*
X1351461Y940213D03*
X1347760D03*
Y933835D03*
X1351461D03*
X1345910Y937024D03*
Y930646D03*
X1338508D03*
X1340359Y940213D03*
Y933835D03*
X1338508Y937024D03*
X1345910Y943402D03*
X1338508D03*
X1347760Y946591D03*
X1345910Y956158D03*
X1347760Y952969D03*
X1345910Y949780D03*
X1340359Y946591D03*
X1338508Y949780D03*
X1340359Y952969D03*
X1338508Y956158D03*
X1351461Y946591D03*
Y952969D03*
Y965725D03*
X1347760D03*
X1351461Y959347D03*
X1347760D03*
X1345910Y962536D03*
Y968914D03*
X1340359Y965725D03*
X1338508Y968914D03*
X1340359Y959347D03*
X1338508Y962536D03*
X1347760Y972103D03*
X1340359D03*
X1351461D03*
X1345910Y975292D03*
X1347760Y978481D03*
X1340359Y984859D03*
Y978481D03*
X1338508Y981670D03*
Y975292D03*
X1351461Y984859D03*
Y978481D03*
X1338508Y988048D03*
X1347760Y997615D03*
X1351461D03*
X1347760Y991237D03*
X1345910Y994426D03*
Y1000804D03*
X1340359Y997615D03*
X1338508Y1000804D03*
Y994426D03*
X1347760Y1010371D03*
X1345910Y1007182D03*
X1347760Y1003993D03*
X1340359D03*
X1338508Y1007182D03*
X1351461Y1003993D03*
X1339689Y1031244D03*
X1348941Y1034433D03*
X1347091Y1037622D03*
X1348941Y1040811D03*
X1347091Y1044000D03*
X1341540Y1034433D03*
X1339689Y1037622D03*
X1341540Y1040811D03*
Y1047189D03*
X1348941Y1059945D03*
Y1053567D03*
X1347091Y1050378D03*
X1339689D03*
X1347091Y1063134D03*
X1339689D03*
X1348941Y1072701D03*
X1347091Y1069512D03*
X1348941Y1066323D03*
X1341540D03*
X1339689Y1069512D03*
X1341540Y1072701D03*
X1347091Y1075890D03*
X1339689D03*
X1348941Y1079079D03*
Y1085457D03*
X1347091Y1082268D03*
Y1088646D03*
X1341540Y1079079D03*
X1339689Y1082268D03*
X1341540Y1085457D03*
X1339689Y1088646D03*
X1348941Y1091835D03*
X1341540D03*
X1347091Y1101402D03*
Y1095024D03*
X1348941Y1098213D03*
Y1104591D03*
X1341540D03*
X1339689Y1095024D03*
X1341540Y1098213D03*
X1339689Y1101402D03*
X1347091Y1107780D03*
X1339689D03*
X1348941Y1110969D03*
Y1117347D03*
X1347091Y1114158D03*
X1339689D03*
X1341540Y1117347D03*
Y1110969D03*
X1347091Y1120536D03*
X1339689D03*
X1348941Y1130102D03*
X1347091Y1133292D03*
Y1126914D03*
X1348941Y1123725D03*
X1341540D03*
X1339689Y1133292D03*
Y1126914D03*
X1341540Y1130102D03*
X1348941Y1136480D03*
X1341540D03*
X1348941Y1149236D03*
Y1142858D03*
X1347091Y1139669D03*
Y1146047D03*
X1339689Y1139669D03*
X1341540Y1142858D03*
X1339689Y1146047D03*
X1341540Y1149236D03*
X1347091Y1152425D03*
X1339689D03*
X1338263Y1549970D03*
X1342987D03*
X1347712D03*
X1339838Y1552698D03*
X1344562D03*
X1349287D03*
X1347712Y1563608D03*
X1349287Y1566336D03*
X1338263Y1563608D03*
X1342987D03*
X1339838Y1566336D03*
X1344562D03*
X1364414Y892379D03*
X1360713D03*
X1353311D03*
X1364414Y898757D03*
X1360713D03*
X1353311D03*
X1364414Y905134D03*
Y911512D03*
X1360713Y905134D03*
Y911512D03*
X1353311D03*
Y905134D03*
X1364414Y917890D03*
Y924268D03*
X1360713Y917890D03*
Y924268D03*
X1353311D03*
Y917890D03*
X1364414Y930646D03*
X1360713D03*
X1353311D03*
Y937024D03*
X1360713Y943402D03*
X1364414D03*
X1353311D03*
X1360713Y956158D03*
Y949780D03*
X1364414Y956158D03*
Y949780D03*
X1353311D03*
Y956158D03*
X1364414Y962536D03*
Y968914D03*
X1360713Y962536D03*
Y968914D03*
X1353311D03*
Y962536D03*
X1360713Y975292D03*
X1364414D03*
X1353311Y981670D03*
Y975292D03*
Y988048D03*
Y1000804D03*
Y994426D03*
Y1007182D03*
X1354493Y1031244D03*
X1352642Y1034433D03*
X1354493Y1037622D03*
X1352642Y1040811D03*
Y1047189D03*
X1354493Y1050378D03*
Y1063134D03*
X1352642Y1066323D03*
X1354493Y1069512D03*
X1352642Y1072701D03*
X1354493Y1075890D03*
X1352642Y1079079D03*
X1354493Y1082268D03*
X1352642Y1085457D03*
X1354493Y1088646D03*
X1352642Y1091835D03*
Y1104591D03*
X1354493Y1095024D03*
X1352642Y1098213D03*
X1354493Y1101402D03*
X1365595Y1107780D03*
X1354493D03*
X1361894D03*
X1365595Y1114158D03*
X1354493D03*
X1352642Y1117347D03*
Y1110969D03*
X1361894Y1114158D03*
X1354493Y1120536D03*
X1361894D03*
X1365595D03*
X1352642Y1123725D03*
X1354493Y1133292D03*
Y1126914D03*
X1352642Y1130102D03*
X1361894Y1126914D03*
Y1133292D03*
X1365595Y1126914D03*
Y1133292D03*
X1352642Y1136480D03*
X1365595Y1139669D03*
Y1146047D03*
X1354493Y1139669D03*
X1352642Y1142858D03*
X1354493Y1146047D03*
X1352642Y1149236D03*
X1361894Y1139669D03*
Y1146047D03*
X1354493Y1152425D03*
X1361894D03*
X1365595D03*
X1352642Y1155614D03*
X1361894Y1158803D03*
X1358193D03*
X1352436Y1549970D03*
X1357161D03*
X1361885D03*
X1354011Y1552698D03*
X1358735D03*
X1363460D03*
X1366609Y1549970D03*
Y1563608D03*
X1363460Y1566336D03*
X1352436Y1563608D03*
X1357161D03*
X1361885D03*
X1354011Y1566336D03*
X1358735D03*
X1375516Y892379D03*
X1371815D03*
X1375516Y898757D03*
X1371815D03*
X1375516Y905134D03*
X1371815D03*
X1375516Y911512D03*
X1371815D03*
X1375516Y917890D03*
Y924268D03*
X1371815Y917890D03*
Y924268D03*
X1375516Y930646D03*
X1371815D03*
Y943402D03*
X1375516D03*
X1371815Y956158D03*
Y949780D03*
X1375516Y956158D03*
Y949780D03*
X1371815Y962536D03*
Y968914D03*
X1375516Y962536D03*
Y968914D03*
X1371815Y975292D03*
X1375516D03*
X1376697Y1107780D03*
X1372997D03*
X1376697Y1114158D03*
X1372997D03*
X1376697Y1120536D03*
X1372997D03*
X1376697Y1126914D03*
X1372997D03*
X1376697Y1133292D03*
X1372997D03*
X1376697Y1139669D03*
Y1146047D03*
X1372997Y1139669D03*
Y1146047D03*
X1376697Y1152425D03*
X1372997D03*
Y1158803D03*
X1369296D03*
X1380398D03*
X1371334Y1549970D03*
X1376058D03*
X1372909Y1552698D03*
X1377633D03*
X1368184D03*
X1380783Y1549970D03*
Y1563608D03*
X1377633Y1566336D03*
X1371334Y1563608D03*
X1376058D03*
X1372909Y1566336D03*
X1368184D03*
X1386619Y892379D03*
X1394020D03*
X1382918D03*
X1394020Y898757D03*
X1386619D03*
X1382918D03*
X1394020Y905134D03*
Y911512D03*
X1386619Y905134D03*
X1382918D03*
X1386619Y911512D03*
X1382918D03*
X1386619Y924268D03*
Y917890D03*
X1394020Y924268D03*
Y917890D03*
X1382918Y924268D03*
Y917890D03*
X1394020Y937024D03*
Y943402D03*
X1382918D03*
X1386619D03*
X1394020Y956158D03*
Y949780D03*
X1382918Y956158D03*
Y949780D03*
X1386619Y956158D03*
Y949780D03*
X1394020Y962536D03*
Y968914D03*
X1382918Y962536D03*
Y968914D03*
X1386619Y962536D03*
Y968914D03*
X1394020Y975292D03*
X1382918D03*
X1386619D03*
X1395201Y1114158D03*
X1387800D03*
X1384099D03*
X1387800Y1120536D03*
X1384099D03*
X1395201D03*
X1387800Y1126914D03*
X1384099D03*
X1387800Y1133292D03*
X1384099D03*
X1395201Y1126914D03*
Y1133292D03*
Y1139669D03*
Y1146047D03*
X1387800Y1139669D03*
Y1146047D03*
X1384099Y1139669D03*
Y1146047D03*
X1387800Y1152425D03*
X1384099D03*
X1395201D03*
X1384099Y1158803D03*
X1391500D03*
X1395201D03*
X1385507Y1549970D03*
X1390232D03*
X1382357Y1552698D03*
X1387082D03*
X1391806D03*
X1394956Y1549970D03*
X1396531Y1552698D03*
X1394956Y1563608D03*
X1396531Y1566336D03*
X1385507Y1563608D03*
X1390232D03*
X1382357Y1566336D03*
X1387082D03*
X1391806D03*
X1406973Y895568D03*
X1397721Y892379D03*
X1403272Y895568D03*
X1397721Y898757D03*
X1406973Y908324D03*
Y901946D03*
X1397721Y905134D03*
X1403272Y908324D03*
Y901946D03*
X1397721Y911512D03*
X1406973Y921079D03*
Y914701D03*
X1397721Y924268D03*
Y917890D03*
X1403272Y921079D03*
Y914701D03*
X1406973Y927457D03*
X1403272D03*
Y940213D03*
X1406973D03*
X1397721Y937024D03*
Y943402D03*
X1403272Y952969D03*
Y946591D03*
X1406973Y952969D03*
Y946591D03*
X1397721Y956158D03*
Y949780D03*
X1403272Y959347D03*
Y965725D03*
X1406973Y959347D03*
Y965725D03*
X1397721Y962536D03*
Y968914D03*
X1403272Y972103D03*
X1406973D03*
X1403272Y978481D03*
X1406973D03*
X1397721Y975292D03*
X1408154Y1117347D03*
Y1110969D03*
X1398902Y1114158D03*
X1404453Y1117347D03*
Y1110969D03*
X1398902Y1120536D03*
Y1126914D03*
X1408154Y1123725D03*
X1404453D03*
X1398902Y1133292D03*
X1408154Y1130102D03*
X1404453D03*
X1408154Y1136480D03*
X1404453D03*
X1408154Y1142858D03*
X1398902Y1139669D03*
Y1146047D03*
X1404453Y1142858D03*
X1398902Y1152425D03*
X1425452Y895568D03*
Y901946D03*
Y908324D03*
Y914701D03*
Y921079D03*
Y927457D03*
Y940213D03*
Y946591D03*
Y952969D03*
Y965725D03*
Y959347D03*
Y972103D03*
Y978481D03*
X1434704Y892379D03*
X1438405D03*
X1429153Y895568D03*
X1438405Y898757D03*
X1434704D03*
X1438405Y905134D03*
Y911512D03*
X1434704Y905134D03*
X1429153Y901946D03*
Y908324D03*
X1434704Y911512D03*
Y917890D03*
Y924268D03*
X1438405Y917890D03*
Y924268D03*
X1429153Y914701D03*
Y921079D03*
Y927457D03*
X1438405Y937024D03*
X1429153Y940213D03*
X1434704Y937024D03*
X1438405Y943402D03*
X1434704D03*
X1438405Y956158D03*
X1429153Y946591D03*
Y952969D03*
X1438405Y949780D03*
X1434704Y956158D03*
Y949780D03*
X1438405Y962536D03*
Y968914D03*
X1429153Y965725D03*
Y959347D03*
X1434704Y962536D03*
Y968914D03*
X1429153Y972103D03*
X1438405Y975292D03*
X1429153Y978481D03*
X1434704Y975292D03*
X1439586Y1114158D03*
X1426633Y1110969D03*
Y1117347D03*
X1435885Y1114158D03*
X1430334Y1110969D03*
Y1117347D03*
X1435885Y1120536D03*
X1439586D03*
X1430334Y1130102D03*
X1426633D03*
Y1123725D03*
X1435885Y1126914D03*
X1430334Y1123725D03*
X1435885Y1133292D03*
X1439586Y1126914D03*
Y1133292D03*
X1426633Y1136480D03*
X1430334D03*
X1439586Y1146047D03*
Y1139669D03*
X1435885Y1146047D03*
Y1139669D03*
X1426633Y1142858D03*
X1430334D03*
X1445806Y892379D03*
X1449507D03*
X1445806Y898757D03*
X1449507D03*
X1445806Y905134D03*
X1449507D03*
X1445806Y911512D03*
X1449507D03*
X1445806Y917890D03*
Y924268D03*
X1449507Y917890D03*
Y924268D03*
Y943402D03*
X1445806D03*
X1449507Y949780D03*
Y956158D03*
X1445806Y949780D03*
Y956158D03*
X1449507Y968914D03*
Y962536D03*
X1445806Y968914D03*
Y962536D03*
X1449507Y975292D03*
X1445806D03*
X1446987Y1114158D03*
X1450688D03*
X1446987Y1120536D03*
X1450688D03*
X1446987Y1126914D03*
X1450688D03*
X1446987Y1133292D03*
X1450688D03*
X1446987Y1139669D03*
X1450688D03*
X1446987Y1146047D03*
X1450688D03*
X1460609Y879623D03*
X1464310D03*
X1468011Y892379D03*
X1456909D03*
X1460609D03*
Y886001D03*
X1456909D03*
X1468011Y898757D03*
X1456909D03*
X1460609D03*
X1468011Y911512D03*
Y905134D03*
X1456909D03*
X1460609D03*
X1456909Y911512D03*
X1460609D03*
X1468011Y924268D03*
Y917890D03*
X1456909Y924268D03*
Y917890D03*
X1460609Y924268D03*
Y917890D03*
X1468011Y930646D03*
X1456909D03*
X1460609D03*
Y943402D03*
X1468011D03*
X1456909D03*
X1460609Y949780D03*
Y956158D03*
X1468011Y949780D03*
Y956158D03*
X1456909Y949780D03*
Y956158D03*
X1468011Y968914D03*
Y962536D03*
X1460609Y968914D03*
Y962536D03*
X1456909Y968914D03*
Y962536D03*
X1460609Y975292D03*
X1468011D03*
X1456909D03*
X1469192Y1107780D03*
X1458090D03*
X1461791D03*
X1469192Y1114158D03*
X1458090D03*
X1461791D03*
X1458090Y1120536D03*
X1461791D03*
X1469192D03*
X1458090Y1133292D03*
X1461791D03*
X1458090Y1126914D03*
X1461791D03*
X1469192Y1133292D03*
Y1126914D03*
Y1146047D03*
Y1139669D03*
X1458090Y1146047D03*
Y1139669D03*
X1461791Y1146047D03*
Y1139669D03*
X1461777Y1552698D03*
X1460202Y1549970D03*
X1464926D03*
X1466501Y1552698D03*
X1469651Y1549970D03*
X1471225Y1552698D03*
X1469651Y1563608D03*
X1471225Y1566336D03*
X1460202Y1563608D03*
X1464926D03*
X1461777Y1566336D03*
X1466501D03*
X1471712Y892379D03*
X1480964Y889190D03*
X1479113Y892379D03*
X1480964Y895568D03*
X1484665Y889190D03*
Y895568D03*
X1471712Y898757D03*
X1479113D03*
X1484665Y908324D03*
Y901946D03*
X1471712Y911512D03*
Y905134D03*
X1479113Y911512D03*
X1480964Y901946D03*
X1479113Y905134D03*
X1480964Y908324D03*
Y921079D03*
X1479113Y924268D03*
X1480964Y914701D03*
X1479113Y917890D03*
X1471712Y924268D03*
Y917890D03*
X1484665Y921079D03*
Y914701D03*
Y927457D03*
X1480964D03*
X1484665Y940213D03*
Y933835D03*
X1479113Y930646D03*
X1480964Y940213D03*
Y933835D03*
X1479113Y937024D03*
X1471712Y930646D03*
Y943402D03*
X1479113D03*
X1471712Y949780D03*
Y956158D03*
X1480964Y946591D03*
X1479113Y949780D03*
X1480964Y952969D03*
X1479113Y956158D03*
X1484665Y946591D03*
Y952969D03*
Y965725D03*
Y959347D03*
X1480964Y965725D03*
X1479113Y968914D03*
X1480964Y959347D03*
X1479113Y962536D03*
X1471712Y968914D03*
Y962536D03*
X1480964Y972103D03*
X1484665D03*
X1480964Y984859D03*
Y978481D03*
X1479113Y981670D03*
Y975292D03*
X1471712D03*
X1484665Y978481D03*
X1479113Y988048D03*
X1484665Y997615D03*
X1480964D03*
X1479113Y1000804D03*
X1480964Y991237D03*
Y1003993D03*
X1479113Y1007182D03*
X1484665Y1010371D03*
Y1003993D03*
X1480295Y1031244D03*
X1482145Y1034433D03*
X1480295Y1037622D03*
X1482145Y1040811D03*
X1480295Y1044000D03*
X1485846Y1034433D03*
Y1040811D03*
X1482145Y1047189D03*
X1485846Y1059945D03*
Y1053567D03*
X1480295Y1050378D03*
Y1063134D03*
X1482145Y1066323D03*
X1480295Y1069512D03*
X1482145Y1072701D03*
X1485846D03*
Y1066323D03*
X1480295Y1075890D03*
X1482145Y1079079D03*
X1485846D03*
X1482145Y1085457D03*
X1485846D03*
X1480295Y1082268D03*
Y1088646D03*
X1482145Y1091835D03*
X1485846D03*
X1482145Y1104591D03*
X1480295Y1095024D03*
X1482145Y1098213D03*
X1480295Y1101402D03*
X1485846Y1098213D03*
Y1104591D03*
X1480295Y1107780D03*
X1472893D03*
X1485846Y1110969D03*
X1482145Y1117347D03*
X1485846D03*
X1482145Y1110969D03*
X1480295Y1114158D03*
X1472893D03*
X1480295Y1120536D03*
X1472893D03*
X1482145Y1123725D03*
X1480295Y1133292D03*
Y1126914D03*
X1482145Y1130102D03*
X1472893Y1133292D03*
Y1126914D03*
X1485846Y1130102D03*
Y1123725D03*
X1482145Y1136480D03*
X1485846D03*
X1482145Y1142858D03*
X1485846Y1149236D03*
Y1142858D03*
X1482145Y1149236D03*
X1480295Y1139669D03*
Y1146047D03*
X1472893D03*
Y1139669D03*
X1480295Y1152425D03*
X1482145Y1155614D03*
X1479099Y1549970D03*
X1483824D03*
X1480674Y1552698D03*
X1474375Y1549970D03*
X1475950Y1552698D03*
X1485399D03*
X1483824Y1563608D03*
X1485399Y1566336D03*
X1474375Y1563608D03*
X1479099D03*
X1475950Y1566336D03*
X1480674D03*
X1486515Y886001D03*
Y892379D03*
X1497617Y886001D03*
X1492066Y889190D03*
X1493917Y892379D03*
X1492066Y895568D03*
X1497617Y892379D03*
X1499468Y889190D03*
Y895568D03*
X1497617Y898757D03*
X1486515D03*
X1493917D03*
X1499468Y908324D03*
Y901946D03*
X1497617Y905134D03*
Y911512D03*
X1486515Y905134D03*
Y911512D03*
X1493917D03*
X1492066Y901946D03*
X1493917Y905134D03*
X1492066Y908324D03*
X1486515Y917890D03*
Y924268D03*
X1497617Y917890D03*
X1492066Y921079D03*
X1493917Y924268D03*
X1497617D03*
X1492066Y914701D03*
X1493917Y917890D03*
X1499468Y921079D03*
Y914701D03*
Y927457D03*
X1492066D03*
X1497617Y937024D03*
X1499468Y940213D03*
Y933835D03*
X1497617Y930646D03*
X1486515Y937024D03*
Y930646D03*
X1493917D03*
X1492066Y940213D03*
Y933835D03*
X1493917Y937024D03*
X1486515Y943402D03*
X1493917D03*
X1497617D03*
X1486515Y956158D03*
Y949780D03*
X1492066Y946591D03*
X1493917Y949780D03*
X1497617Y956158D03*
X1492066Y952969D03*
X1497617Y949780D03*
X1493917Y956158D03*
X1499468Y946591D03*
Y952969D03*
X1497617Y962536D03*
X1499468Y965725D03*
Y959347D03*
X1497617Y968914D03*
X1486515Y962536D03*
Y968914D03*
X1492066Y965725D03*
X1493917Y968914D03*
X1492066Y959347D03*
X1493917Y962536D03*
X1492066Y972103D03*
X1499468D03*
X1486515Y975292D03*
X1492066Y984859D03*
X1497617Y975292D03*
X1492066Y978481D03*
X1493917Y981670D03*
Y975292D03*
X1499468Y978481D03*
X1497617Y988048D03*
X1486515D03*
X1493917D03*
X1497617Y994426D03*
X1499468Y997615D03*
X1497617Y1000804D03*
X1486515Y994426D03*
Y1000804D03*
X1492066Y997615D03*
X1493917Y1000804D03*
X1492066Y991237D03*
X1486515Y1007182D03*
X1497617D03*
X1492066Y1003993D03*
X1493917Y1007182D03*
X1499468Y1010371D03*
Y1003993D03*
X1495098Y1031244D03*
X1487696Y1037622D03*
X1493247Y1034433D03*
X1498799Y1037622D03*
X1495098D03*
X1493247Y1040811D03*
X1495098Y1044000D03*
X1500649Y1034433D03*
Y1040811D03*
X1493247Y1047189D03*
X1500649Y1059945D03*
X1498799Y1050378D03*
X1500649Y1053567D03*
X1487696Y1050378D03*
X1495098D03*
X1487696Y1063134D03*
X1495098D03*
X1498799D03*
X1487696Y1069512D03*
X1493247Y1066323D03*
X1495098Y1069512D03*
X1498799D03*
X1493247Y1072701D03*
X1500649D03*
Y1066323D03*
X1498799Y1075890D03*
X1487696D03*
X1495098D03*
X1500649Y1079079D03*
X1498799Y1082268D03*
Y1088646D03*
X1500649Y1085457D03*
X1487696Y1082268D03*
Y1088646D03*
X1493247Y1079079D03*
X1495098Y1082268D03*
X1493247Y1085457D03*
X1495098Y1088646D03*
X1493247Y1091835D03*
X1500649D03*
X1487696Y1101402D03*
Y1095024D03*
X1498799Y1101402D03*
X1493247Y1104591D03*
X1495098Y1095024D03*
X1498799D03*
X1493247Y1098213D03*
X1495098Y1101402D03*
X1500649Y1098213D03*
Y1104591D03*
X1498799Y1107780D03*
X1487696D03*
X1495098D03*
X1500649Y1110969D03*
X1498799Y1114158D03*
X1500649Y1117347D03*
X1487696Y1114158D03*
X1495098D03*
X1493247Y1117347D03*
Y1110969D03*
X1487696Y1120536D03*
X1495098D03*
X1498799D03*
X1487696Y1133292D03*
Y1126914D03*
X1493247Y1123725D03*
X1495098Y1133292D03*
X1498799D03*
Y1126914D03*
X1495098D03*
X1493247Y1130102D03*
X1500649D03*
Y1123725D03*
Y1136480D03*
X1493247D03*
X1498799Y1139669D03*
X1500649Y1149236D03*
X1498799Y1146047D03*
X1500649Y1142858D03*
X1487696Y1139669D03*
Y1146047D03*
X1495098Y1139669D03*
X1493247Y1142858D03*
X1495098Y1146047D03*
X1493247Y1149236D03*
X1487696Y1152425D03*
X1495098D03*
X1498799D03*
X1500649Y1155614D03*
X1497997Y1549970D03*
X1488548D03*
X1493273D03*
X1490123Y1552698D03*
X1494847D03*
X1499572D03*
X1497997Y1563608D03*
X1499572Y1566336D03*
X1488548Y1563608D03*
X1493273D03*
X1490123Y1566336D03*
X1494847D03*
X1512421Y886001D03*
X1506869Y889190D03*
X1510570D03*
X1505019Y892379D03*
X1510570Y895568D03*
X1506869D03*
X1512421Y892379D03*
Y898757D03*
X1505019D03*
X1512421Y905134D03*
Y911512D03*
X1510570Y908324D03*
X1505019Y911512D03*
X1506869Y901946D03*
X1510570D03*
X1505019Y905134D03*
X1506869Y908324D03*
X1512421Y917890D03*
X1506869Y921079D03*
X1510570D03*
X1505019Y924268D03*
X1512421D03*
X1510570Y914701D03*
X1506869D03*
X1505019Y917890D03*
X1506869Y927457D03*
X1510570D03*
X1512421Y937024D03*
Y930646D03*
X1505019D03*
X1506869Y940213D03*
X1510570D03*
Y933835D03*
X1506869D03*
X1505019Y937024D03*
Y943402D03*
X1512421D03*
X1506869Y946591D03*
X1510570D03*
X1505019Y949780D03*
X1512421Y956158D03*
X1510570Y952969D03*
X1506869D03*
X1512421Y949780D03*
X1505019Y956158D03*
X1512421Y962536D03*
Y968914D03*
X1506869Y965725D03*
X1510570D03*
X1505019Y968914D03*
X1506869Y959347D03*
X1510570D03*
X1505019Y962536D03*
X1510570Y972103D03*
X1506869D03*
Y984859D03*
X1512421Y975292D03*
X1506869Y978481D03*
X1510570D03*
X1505019Y981670D03*
Y975292D03*
X1512421Y988048D03*
X1505019D03*
X1512421Y994426D03*
Y1000804D03*
X1510570Y997615D03*
X1506869D03*
X1505019Y1000804D03*
X1506869Y991237D03*
X1510570Y1010371D03*
X1512421Y1007182D03*
X1510570Y1003993D03*
X1506869D03*
X1505019Y1007182D03*
X1506200Y1031244D03*
X1508050Y1034433D03*
X1511751D03*
X1513602Y1037622D03*
X1506200D03*
X1508050Y1040811D03*
X1511751D03*
X1506200Y1044000D03*
X1508050Y1047189D03*
X1511751Y1059945D03*
X1513602Y1050378D03*
X1511751Y1053567D03*
X1506200Y1050378D03*
Y1063134D03*
X1513602D03*
X1511751Y1072701D03*
X1508050Y1066323D03*
X1506200Y1069512D03*
X1513602D03*
X1508050Y1072701D03*
X1511751Y1066323D03*
X1513602Y1075890D03*
X1506200D03*
X1511751Y1079079D03*
X1513602Y1082268D03*
Y1088646D03*
X1511751Y1085457D03*
X1508050Y1079079D03*
X1506200Y1082268D03*
X1508050Y1085457D03*
X1506200Y1088646D03*
X1511751Y1091835D03*
X1508050D03*
X1513602Y1101402D03*
X1508050Y1104591D03*
X1506200Y1095024D03*
X1513602D03*
X1508050Y1098213D03*
X1511751D03*
X1506200Y1101402D03*
X1511751Y1104591D03*
X1513602Y1107780D03*
X1506200D03*
X1511751Y1110969D03*
X1513602Y1114158D03*
X1511751Y1117347D03*
X1506200Y1114158D03*
X1508050Y1117347D03*
Y1110969D03*
X1506200Y1120536D03*
X1513602D03*
X1508050Y1123725D03*
X1511751Y1130102D03*
X1506200Y1133292D03*
X1513602D03*
Y1126914D03*
X1506200D03*
X1511751Y1123725D03*
X1508050Y1130102D03*
X1511751Y1136480D03*
X1508050D03*
X1513602Y1139669D03*
X1511751Y1149236D03*
X1513602Y1146047D03*
X1511751Y1142858D03*
X1506200Y1139669D03*
X1508050Y1142858D03*
X1506200Y1146047D03*
X1508050Y1149236D03*
X1506200Y1152425D03*
X1513602D03*
X1508050Y1155614D03*
X1507446Y1549970D03*
X1512170D03*
X1502721D03*
X1509021Y1552698D03*
X1513745D03*
X1504296D03*
X1512170Y1563608D03*
X1513745Y1566336D03*
X1507446Y1563608D03*
X1502721D03*
X1509021Y1566336D03*
X1504296D03*
X1523523Y886001D03*
X1517972Y889190D03*
X1525373D03*
X1519822Y892379D03*
X1525373Y895568D03*
X1517972D03*
X1523523Y892379D03*
X1530925D03*
Y898757D03*
X1523523D03*
X1519822D03*
X1530925Y911512D03*
Y905134D03*
X1525373Y908324D03*
X1519822Y911512D03*
X1517972Y901946D03*
X1525373D03*
X1519822Y905134D03*
X1523523D03*
X1517972Y908324D03*
X1523523Y911512D03*
Y917890D03*
X1517972Y921079D03*
X1525373D03*
X1519822Y924268D03*
X1523523D03*
X1525373Y914701D03*
X1517972D03*
X1519822Y917890D03*
X1530925Y924268D03*
Y917890D03*
X1517972Y927457D03*
X1525373D03*
X1530925Y930646D03*
Y937024D03*
X1519822Y930646D03*
X1523523Y937024D03*
X1517972Y940213D03*
X1525373D03*
Y933835D03*
X1517972D03*
X1523523Y930646D03*
X1519822Y937024D03*
Y943402D03*
X1523523D03*
X1530925D03*
X1517972Y946591D03*
X1525373D03*
X1519822Y949780D03*
X1523523Y956158D03*
X1525373Y952969D03*
X1517972D03*
X1523523Y949780D03*
X1519822Y956158D03*
X1530925Y949780D03*
Y956158D03*
Y968914D03*
Y962536D03*
X1523523D03*
X1517972Y965725D03*
X1525373D03*
X1519822Y968914D03*
X1517972Y959347D03*
X1525373D03*
X1519822Y962536D03*
X1523523Y968914D03*
X1525373Y972103D03*
X1517972D03*
Y984859D03*
X1523523Y975292D03*
X1517972Y978481D03*
X1525373D03*
X1519822Y981670D03*
Y975292D03*
X1530925Y981670D03*
Y975292D03*
Y988048D03*
X1519822D03*
X1523523D03*
X1530925Y1000804D03*
X1523523Y994426D03*
X1525373Y997615D03*
X1517972D03*
X1519822Y1000804D03*
X1523523D03*
X1517972Y991237D03*
X1525373Y1010371D03*
X1523523Y1007182D03*
X1525373Y1003993D03*
X1517972D03*
X1519822Y1007182D03*
X1530925D03*
X1521003Y1031244D03*
X1519153Y1034433D03*
X1526554D03*
X1524704Y1037622D03*
X1521003D03*
X1519153Y1040811D03*
X1526554D03*
X1521003Y1044000D03*
X1519153Y1047189D03*
X1526554Y1059945D03*
Y1053567D03*
X1521003Y1050378D03*
X1524704D03*
X1521003Y1063134D03*
X1524704D03*
X1526554Y1072701D03*
X1519153Y1066323D03*
X1521003Y1069512D03*
X1524704D03*
X1519153Y1072701D03*
X1526554Y1066323D03*
X1521003Y1075890D03*
X1524704D03*
X1526554Y1079079D03*
Y1085457D03*
X1519153Y1079079D03*
X1521003Y1082268D03*
X1524704D03*
X1519153Y1085457D03*
X1524704Y1088646D03*
X1521003D03*
X1526554Y1091835D03*
X1519153D03*
X1524704Y1101402D03*
X1519153Y1104591D03*
X1521003Y1095024D03*
X1524704D03*
X1519153Y1098213D03*
X1526554D03*
X1521003Y1101402D03*
X1526554Y1104591D03*
X1524704Y1107780D03*
X1521003D03*
X1526554Y1110969D03*
Y1117347D03*
X1521003Y1114158D03*
X1524704D03*
X1519153Y1117347D03*
Y1110969D03*
X1521003Y1120536D03*
X1524704D03*
X1519153Y1123725D03*
X1526554Y1130102D03*
X1521003Y1133292D03*
X1524704D03*
Y1126914D03*
X1521003D03*
X1526554Y1123725D03*
X1519153Y1130102D03*
X1526554Y1136480D03*
X1519153D03*
X1526554Y1149236D03*
Y1142858D03*
X1521003Y1139669D03*
X1524704D03*
X1519153Y1142858D03*
X1524704Y1146047D03*
X1521003D03*
X1519153Y1149236D03*
X1521003Y1152425D03*
X1524704D03*
X1526554Y1155614D03*
X1516895Y1549970D03*
X1521619D03*
X1526344D03*
X1518469Y1552698D03*
X1523194D03*
X1527918D03*
X1526344Y1563608D03*
X1527918Y1566336D03*
X1516895Y1563608D03*
X1521619D03*
X1518469Y1566336D03*
X1523194D03*
X1538326Y886001D03*
X1532775Y889190D03*
X1536476D03*
Y895568D03*
X1532775D03*
X1538326Y892379D03*
Y898757D03*
X1536476Y908324D03*
X1532775Y901946D03*
X1536476D03*
X1538326Y905134D03*
X1532775Y908324D03*
X1538326Y911512D03*
Y917890D03*
X1532775Y921079D03*
X1536476D03*
X1538326Y924268D03*
X1536476Y914701D03*
X1532775D03*
Y927457D03*
X1536476D03*
X1538326Y937024D03*
X1532775Y940213D03*
X1536476D03*
Y933835D03*
X1532775D03*
X1538326Y930646D03*
Y943402D03*
X1532775Y946591D03*
X1536476D03*
X1538326Y956158D03*
X1536476Y952969D03*
X1532775D03*
X1538326Y949780D03*
Y962536D03*
X1532775Y965725D03*
X1536476D03*
X1532775Y959347D03*
X1536476D03*
X1538326Y968914D03*
X1536476Y972103D03*
X1532775D03*
Y984859D03*
X1538326Y975292D03*
X1532775Y978481D03*
X1536476D03*
X1538326Y988048D03*
Y994426D03*
X1536476Y997615D03*
X1532775D03*
X1538326Y1000804D03*
X1532775Y991237D03*
X1536476Y1010371D03*
X1538326Y1007182D03*
X1536476Y1003993D03*
X1532775D03*
X1532106Y1031244D03*
X1533956Y1034433D03*
X1537657D03*
X1539507Y1037622D03*
X1532106D03*
X1533956Y1040811D03*
X1537657D03*
X1532106Y1044000D03*
X1533956Y1047189D03*
X1532106Y1050378D03*
X1537657Y1059945D03*
X1539507Y1050378D03*
X1537657Y1053567D03*
X1532106Y1063134D03*
X1539507D03*
X1537657Y1072701D03*
X1533956Y1066323D03*
X1532106Y1069512D03*
X1539507D03*
X1533956Y1072701D03*
X1537657Y1066323D03*
X1532106Y1075890D03*
X1539507D03*
X1533956Y1079079D03*
X1537657D03*
X1532106Y1082268D03*
X1539507D03*
X1533956Y1085457D03*
X1539507Y1088646D03*
X1532106D03*
X1537657Y1085457D03*
Y1091835D03*
X1533956D03*
X1539507Y1101402D03*
X1533956Y1104591D03*
X1532106Y1095024D03*
X1539507D03*
X1533956Y1098213D03*
X1537657D03*
X1532106Y1101402D03*
X1537657Y1104591D03*
X1539507Y1107780D03*
X1532106D03*
X1537657Y1110969D03*
X1532106Y1114158D03*
X1539507D03*
X1533956Y1117347D03*
X1537657D03*
X1533956Y1110969D03*
X1532106Y1120536D03*
X1539507D03*
X1533956Y1123725D03*
X1537657Y1130102D03*
X1532106Y1133292D03*
X1539507D03*
Y1126914D03*
X1532106D03*
X1537657Y1123725D03*
X1533956Y1130102D03*
Y1136480D03*
X1537657D03*
X1532106Y1139669D03*
X1539507D03*
X1533956Y1142858D03*
X1537657Y1149236D03*
X1539507Y1146047D03*
X1532106D03*
X1537657Y1142858D03*
X1533956Y1149236D03*
X1532106Y1152425D03*
X1539507D03*
X1533956Y1155614D03*
X1531068Y1549970D03*
X1532643Y1552698D03*
X1531068Y1563608D03*
X1532643Y1566336D03*
X1588264Y1549970D03*
X1589839Y1552698D03*
X1588264Y1563608D03*
X1589839Y1566336D03*
X1592988Y1549970D03*
X1597713D03*
X1602437D03*
X1594563Y1552698D03*
X1599287D03*
X1604012D03*
X1602437Y1563608D03*
X1604012Y1566336D03*
X1592988Y1563608D03*
X1597713D03*
X1594563Y1566336D03*
X1599287D03*
X1607161Y1549970D03*
X1611886D03*
X1616610D03*
X1608736Y1552698D03*
X1613461D03*
X1618185D03*
X1616610Y1563608D03*
X1618185Y1566336D03*
X1607161Y1563608D03*
X1611886D03*
X1608736Y1566336D03*
X1613461D03*
X1621335Y1549970D03*
X1626059D03*
X1630783D03*
X1622909Y1552698D03*
X1627634D03*
X1632358D03*
X1630783Y1563608D03*
X1632358Y1566336D03*
X1621335Y1563608D03*
X1626059D03*
X1622909Y1566336D03*
X1627634D03*
X1635508Y1549970D03*
X1640232D03*
X1644957D03*
X1637083Y1552698D03*
X1641807D03*
X1646531D03*
X1649681Y1549970D03*
Y1563608D03*
X1646531Y1566336D03*
X1635508Y1563608D03*
X1640232D03*
X1644957D03*
X1637083Y1566336D03*
X1641807D03*
X1654406Y1549970D03*
X1659130D03*
X1651256Y1552698D03*
X1655980D03*
X1660705D03*
Y1566336D03*
X1654406Y1563608D03*
X1659130D03*
X1651256Y1566336D03*
X1655980D03*
X5116564Y144366D03*
X5116530Y417185D03*
X5119120Y688356D03*
X5121120Y995856D03*
X5120120Y1309856D03*
Y1625356D03*
G54D31*
X676509Y224606D03*
X2392820Y95406D03*
G54D40*
X1225530Y60384D03*
X1233404D03*
X1241278D03*
X1249152D03*
X1439049Y87432D03*
X1431175D03*
X1454797D03*
X1446923D03*
X2392820Y1100106D03*
G54D13*
X11782Y167036D03*
X18691Y167208D03*
X22409Y230021D03*
X19684Y237154D03*
X17292Y290137D03*
X35689Y301357D03*
X35740Y363337D03*
X39320Y392269D03*
X29962Y401000D03*
X39967Y526709D03*
X30562Y533055D03*
X45423Y197224D03*
Y212224D03*
Y202224D03*
Y207224D03*
X42449Y282916D03*
Y277798D03*
X47892Y290137D03*
X41492Y298207D03*
X47892Y295452D03*
X40500Y288500D03*
X55254Y292892D03*
X42449Y312916D03*
Y307798D03*
X55190Y360862D03*
X42809D03*
X40940Y387302D03*
X53825Y421746D03*
X55099Y1298676D03*
Y1292676D03*
X47735Y1584885D03*
X47973Y1589981D03*
X43633Y1606896D03*
X43933Y1613818D03*
X47633Y1600896D03*
X53633Y1629896D03*
X41208Y1619896D03*
X41427Y1668587D03*
X52052Y1684027D03*
X66650Y265316D03*
X62930Y282866D03*
X66289Y301357D03*
X62930Y312866D03*
X62142Y539495D03*
X61620Y768510D03*
X56440Y766180D03*
X66229Y1549536D03*
X57811Y1598061D03*
X58633Y1587481D03*
X63633D03*
X58633Y1629896D03*
X64133Y1627896D03*
X64633Y1632896D03*
X70127Y1687362D03*
X82026Y143491D03*
X71659Y149191D03*
X71779Y161194D03*
X71772Y421746D03*
X80948Y525513D03*
Y521613D03*
X76378Y1406622D03*
X83441Y1430500D03*
X72375Y1604365D03*
X74133Y1610896D03*
X70567Y1625603D03*
X72255Y1616730D03*
X74134Y1621396D03*
X75380Y1627622D03*
X79164Y1636992D03*
X78127Y1687362D03*
X82500Y1698511D03*
Y1706511D03*
X82000Y1716331D03*
Y1724331D03*
X92197Y143853D03*
X87137Y143663D03*
X93775Y197241D03*
Y212241D03*
Y207241D03*
Y202241D03*
X87654Y376026D03*
X87520Y386502D03*
X94474Y766871D03*
X90150Y1314560D03*
X93000Y1444500D03*
X93296Y1549142D03*
X96101Y1696469D03*
X96555Y1705508D03*
X95400Y1719741D03*
X95460Y1725241D03*
X104829Y151191D03*
X107931Y158767D03*
X100818Y165506D03*
Y168906D03*
X101995Y1388247D03*
X108817Y1380530D03*
X111600Y1403100D03*
X113500Y1398600D03*
X101637Y1432938D03*
X102076Y1427833D03*
X102398Y1440000D03*
X113500Y1455600D03*
X112100Y1467500D03*
X100439Y1667361D03*
X100915Y1679564D03*
X106448Y1696436D03*
X107500Y1707450D03*
X120016Y300654D03*
Y320631D03*
X124174Y766871D03*
X122050Y1403750D03*
X129200Y1401000D03*
X124700D03*
X126000Y1414000D03*
X116700Y1415700D03*
Y1410500D03*
X120700Y1408100D03*
X116900Y1449000D03*
X119100Y1460300D03*
X121500Y1467400D03*
X124312Y1633488D03*
X115353Y1695941D03*
X127710Y1700166D03*
X120052Y1712450D03*
X127290Y1705666D03*
X125183Y1716741D03*
X127168Y1721695D03*
X129020Y1726741D03*
X134812Y530955D03*
X140471Y670445D03*
X134902Y668506D03*
X140600Y683029D03*
X134902Y686074D03*
X138000Y1400600D03*
X134800Y1408100D03*
X141500Y1433500D03*
X139500Y1446000D03*
X133100Y1444100D03*
X138013Y1440487D03*
X141514Y1436500D03*
X133120Y1454751D03*
X141028Y1454705D03*
X137386Y1626412D03*
X131353Y1696062D03*
X139353D03*
X143000Y1701011D03*
Y1709166D03*
X149231Y224204D03*
X148228Y216118D03*
X158380Y419760D03*
X147450Y423860D03*
X154770Y441830D03*
X147810Y475710D03*
X146982Y526997D03*
X159513Y674855D03*
X152705Y683218D03*
X153875Y766871D03*
X156477Y1447733D03*
X154305Y1453101D03*
X159000Y1525480D03*
X149171Y1616759D03*
X159427Y1687843D03*
Y1696652D03*
X152605Y1715941D03*
X149338Y1705603D03*
X146000Y1718241D03*
X155740Y1729726D03*
X146483Y1725636D03*
X162830Y396930D03*
X172010Y474900D03*
X163372Y670863D03*
X172725Y667898D03*
X162482Y679319D03*
X161735Y684456D03*
X172725Y679230D03*
X163148Y1474504D03*
X172180Y1490210D03*
X172070Y1495550D03*
X162740Y1713172D03*
X171925Y1708428D03*
X171945Y1730693D03*
X162740Y1723886D03*
X187250Y129674D03*
X189290Y396730D03*
X177675Y419260D03*
X185160Y419220D03*
X181550Y441290D03*
X183576Y766871D03*
X184139Y1651088D03*
X182533Y1676854D03*
X185124Y1701851D03*
X185084Y1691988D03*
X184340Y1718000D03*
X178385Y1715441D03*
X178376Y1720559D03*
X195979Y109462D03*
X204088Y138912D03*
X203061Y131158D03*
X200754Y595174D03*
X200405Y632385D03*
X198698Y1662215D03*
X199747Y1675603D03*
X197780Y1696973D03*
X200478Y1701758D03*
X200448Y1690771D03*
X202076Y1717845D03*
X189760Y1713061D03*
X203510Y1712441D03*
X189760Y1723041D03*
X203655Y1723000D03*
X214107Y113022D03*
X205489Y142790D03*
X217687Y522453D03*
X208818Y766871D03*
X211862Y1701100D03*
X212365Y1705403D03*
X224055Y127146D03*
X233284Y137195D03*
X233653Y162074D03*
X223687Y522453D03*
X229687D03*
X233493Y676906D03*
X238059Y26235D03*
X235697Y21585D03*
X241306Y20325D03*
X246356Y26855D03*
X248816Y48965D03*
X239816Y54365D03*
X248487Y68690D03*
X242920Y67915D03*
X238846Y72977D03*
X235186Y98067D03*
X243813Y132383D03*
X242215Y151788D03*
X236104Y151996D03*
X245486Y159705D03*
X240413Y360867D03*
X240200Y766300D03*
X251106Y12615D03*
X257516Y51565D03*
X251793Y100846D03*
X252800Y114800D03*
X252195Y144320D03*
X249735Y152694D03*
X262886Y147391D03*
X262239Y649587D03*
X257071Y772770D03*
X275116Y28565D03*
X275896Y48875D03*
X266420Y39120D03*
X265365Y49171D03*
X273616Y96665D03*
X264293Y120972D03*
X269487Y121095D03*
X275793Y120248D03*
X266000Y125800D03*
X276821Y140465D03*
X264574Y159206D03*
X269925Y217700D03*
X274993Y522052D03*
X265100Y595078D03*
X273208Y588237D03*
X267601Y608378D03*
X271571Y644796D03*
X270857Y668515D03*
X271161Y780588D03*
X274282Y786741D03*
X264085Y1339175D03*
X286996Y20365D03*
X290795Y28365D03*
X287988Y54893D03*
X293157Y50525D03*
X286996Y139865D03*
X290865Y609470D03*
X295516Y26365D03*
X300244Y28365D03*
X299496Y22865D03*
X303252Y38199D03*
X296337Y55855D03*
X298542Y51088D03*
X303711Y50860D03*
X301107Y75676D03*
X305820Y73693D03*
X301780Y82900D03*
X299002Y88700D03*
X307816Y95727D03*
X299628Y149203D03*
X299624Y158706D03*
X306528Y256528D03*
X294299Y577188D03*
X302130Y584160D03*
X304449Y609570D03*
X304301Y679037D03*
X323036Y73125D03*
X310455Y75895D03*
X320190Y77648D03*
X322871Y84321D03*
X316982Y89003D03*
X323646Y147120D03*
Y152120D03*
X314780Y545716D03*
X322955Y556148D03*
X311349Y609632D03*
X326475Y182855D03*
X331780Y182900D03*
X324406Y367744D03*
X334744Y566086D03*
X343036Y122525D03*
X343446Y131170D03*
X339914Y165170D03*
X344984Y199299D03*
X341895Y233980D03*
X352000Y230643D03*
Y235643D03*
X351157Y550415D03*
Y590415D03*
X366874Y135157D03*
X366771Y127665D03*
X355910Y223847D03*
X365739Y221871D03*
X365559Y238896D03*
X365071Y551038D03*
X362200Y566750D03*
X364047Y556773D03*
X360261Y561044D03*
X361922Y1206891D03*
X357271Y1208988D03*
X375920Y146577D03*
X377118Y222229D03*
X370327Y228951D03*
X370352Y235455D03*
X382184Y466351D03*
X378976Y479226D03*
X371962Y524954D03*
X375410Y552254D03*
X375271Y542191D03*
X379689Y586040D03*
X368798Y587938D03*
X369271Y600138D03*
X373477Y593338D03*
X375050Y1639400D03*
X371823Y1644516D03*
X370533Y1658605D03*
X374962Y1648511D03*
X372953Y1653197D03*
X373330Y1668539D03*
X391600Y121178D03*
X387712Y147441D03*
X395590Y147010D03*
X391635Y161091D03*
X397184Y507101D03*
X387440Y525154D03*
X388985Y554870D03*
X395171Y559463D03*
X394168Y568482D03*
X395157Y573815D03*
X387103Y584506D03*
X395267Y1358621D03*
X389276Y1568413D03*
X393322Y1573347D03*
X388784Y1581801D03*
X393005Y1592304D03*
X387805Y1604802D03*
X394824Y1629713D03*
X394000Y1621500D03*
X389824Y1629713D03*
X389000Y1621500D03*
X384824Y1629713D03*
X406243Y100076D03*
X403734Y110326D03*
X410678Y159140D03*
X411299Y212096D03*
X411940Y240501D03*
X410984Y496649D03*
X399657Y546915D03*
X410111Y572608D03*
X408895Y1553644D03*
X407198Y1564990D03*
X401249Y1564422D03*
X405758Y1557900D03*
X403163Y1579357D03*
X404669Y1594317D03*
X400380Y1621500D03*
X404640Y1637425D03*
X412000Y1647177D03*
X403844Y1665769D03*
X405000Y1683500D03*
X416549Y66365D03*
Y71665D03*
X427300Y71300D03*
X419900Y96620D03*
X414100D03*
X422936Y223501D03*
X420115Y230323D03*
Y240501D03*
Y235442D03*
X419984Y508000D03*
X424488Y1565400D03*
X413540Y1556646D03*
X419254Y1566828D03*
X427081Y1581620D03*
X423500Y1652500D03*
X420000Y1668075D03*
X417000Y1683500D03*
X433673Y73960D03*
X428149Y65016D03*
X429685Y88657D03*
X431359Y82589D03*
X429997Y166400D03*
X441997D03*
X436103Y158594D03*
X438200Y212096D03*
X431299Y212095D03*
X437440Y237270D03*
X442710Y237990D03*
X435710Y250340D03*
X440710D03*
X437084Y501865D03*
X442084Y511870D03*
X430793Y686423D03*
X439935Y1532600D03*
X431923Y1565790D03*
X433440Y1581700D03*
X429947Y1594398D03*
X433012Y1621612D03*
X432000Y1650000D03*
X445267Y82124D03*
X448038Y158659D03*
X445997Y170701D03*
X448499Y212036D03*
X443299Y212095D03*
X456231Y227764D03*
Y232883D03*
X446710Y249340D03*
X453269Y478388D03*
X443683Y502256D03*
X447084Y511870D03*
X457084D03*
X444128Y1604200D03*
X446182Y1625555D03*
X465997Y166400D03*
X457997D03*
X471371Y227764D03*
Y222764D03*
X460567Y225205D03*
Y235442D03*
X460624Y230323D03*
X470243Y285693D03*
X460441Y499842D03*
X468638Y514096D03*
X465766Y524991D03*
X463193Y661823D03*
X459500Y1659000D03*
X468350Y1645351D03*
X468075Y1662500D03*
X470309Y1689000D03*
X468575Y1704000D03*
Y1731000D03*
X479400Y90574D03*
X486682Y197516D03*
X487620Y270400D03*
X479870D03*
X483823Y285893D03*
X474808Y291492D03*
X482893Y291293D03*
X484063Y305669D03*
X483500Y1658500D03*
X479500Y1666500D03*
X473500Y1662500D03*
X476000Y1680000D03*
X478500Y1701000D03*
X474000Y1704000D03*
X478500Y1714500D03*
X500674Y116261D03*
X495232Y189516D03*
X496831Y205030D03*
X494144Y221370D03*
X500209Y227881D03*
Y233000D03*
X491859D03*
X500119Y243173D03*
X488405Y578572D03*
X501171Y630087D03*
X495839Y635323D03*
X516020Y105370D03*
Y109270D03*
X502750Y111276D03*
X505315Y196944D03*
X504351Y202776D03*
X512076Y206404D03*
X508001Y220166D03*
X524713Y33346D03*
X529713D03*
X519601Y196117D03*
X529095Y452049D03*
X544721Y42892D03*
X539721Y42862D03*
X535170Y111230D03*
Y115130D03*
X534277Y224930D03*
X538613Y227882D03*
Y238119D03*
X534277Y230441D03*
X538613Y233000D03*
X534455Y428561D03*
X553651Y48842D03*
X550972Y42902D03*
X561721Y41024D03*
X556351Y41538D03*
X548610Y48082D03*
X547821Y79372D03*
X551721D03*
X549248Y237652D03*
Y230441D03*
X561808Y300492D03*
X562030Y372872D03*
X562208Y383668D03*
Y404717D03*
Y397599D03*
X555727Y479968D03*
X565185Y47982D03*
X575331Y47672D03*
X573191Y42912D03*
X570209Y47982D03*
X566771Y41133D03*
X563951Y153640D03*
Y148640D03*
Y160644D03*
X572003Y164356D03*
X569004Y225496D03*
X570823Y294893D03*
X569893Y300293D03*
X571063Y314669D03*
X575913Y413287D03*
X570863Y410728D03*
X572121Y437038D03*
X564407Y431638D03*
X563763Y486350D03*
X591938Y46308D03*
X591070Y60201D03*
X586953Y63441D03*
X590501Y86909D03*
X580098Y96439D03*
X586394Y95948D03*
X591811Y97421D03*
X589203Y164356D03*
Y169415D03*
X588215Y214079D03*
X588968Y240112D03*
X585585Y372052D03*
X577482Y383668D03*
X587710Y399287D03*
Y404287D03*
X588798Y435949D03*
X588723Y427949D03*
X589507Y462559D03*
X583116Y476745D03*
X581335Y472100D03*
X584271Y1263988D03*
X602837Y32910D03*
X603064Y48023D03*
X599284Y42481D03*
X597956Y48047D03*
X606585Y43529D03*
X599295Y100747D03*
X606183Y95873D03*
X597275Y94922D03*
X596068Y106798D03*
X597769Y153640D03*
Y148640D03*
X604293Y193185D03*
X597293Y193186D03*
X602294Y203786D03*
X598968Y238878D03*
X598208Y383668D03*
X593758Y415850D03*
X597500Y483500D03*
X595253Y1266668D03*
X596944Y1270115D03*
X605771Y1263098D03*
X598112Y1264365D03*
X619563Y49193D03*
X615587Y45611D03*
X618182Y100786D03*
X610009Y100748D03*
X614282Y95873D03*
X618801Y165356D03*
Y175534D03*
Y170415D03*
X608794Y203786D03*
X621585Y331358D03*
X613565Y350819D03*
X613482Y383668D03*
X617985Y401728D03*
X618680Y511302D03*
X611896Y538178D03*
X607091Y528168D03*
X615591Y1282038D03*
X608148Y1373890D03*
X624634Y48104D03*
X627881Y57120D03*
X622207Y60573D03*
X626642Y71365D03*
X622156Y95948D03*
X626208Y100861D03*
X630900Y118920D03*
X626705Y285305D03*
X622705D03*
X636500Y360362D03*
X634105Y404652D03*
X635058Y399700D03*
X627925Y421966D03*
X622800Y461348D03*
X627880Y455310D03*
X627364Y478823D03*
X634794Y590504D03*
X635567Y671774D03*
X633406Y1358576D03*
X634776Y1353739D03*
X624795Y1373257D03*
X624976Y1378313D03*
X630195Y1384263D03*
X625195Y1383457D03*
X622352Y1393285D03*
X630523Y1392554D03*
X635849Y1393376D03*
X633422Y1673488D03*
X635491Y1696845D03*
X635472Y1711808D03*
X642157Y44695D03*
X639876Y49193D03*
X651042Y41545D03*
X647987Y47606D03*
X646042Y41545D03*
X640653Y58274D03*
X650846Y74074D03*
X647938Y83795D03*
X642607Y94116D03*
X642394Y131172D03*
X645752Y134988D03*
X649871Y181942D03*
X642617Y389299D03*
X637314Y393680D03*
X651279Y404458D03*
X648500Y453862D03*
X644849Y495582D03*
X640076Y497964D03*
X649592Y540078D03*
X646151Y535227D03*
X648314Y571169D03*
X644414D03*
X638694Y590504D03*
X650258Y590316D03*
X646358D03*
X650228Y674761D03*
X638967Y671774D03*
X642804Y766871D03*
X638053Y1384491D03*
X642716Y1653939D03*
X637218Y1654131D03*
X644905Y1646491D03*
X639800Y1646650D03*
X647460Y1662952D03*
X640846Y1665189D03*
X650158Y1687189D03*
X643041Y1682883D03*
X651143Y1706162D03*
X644975Y1725236D03*
X654117Y29099D03*
X654582Y45448D03*
X661601Y75562D03*
X657166Y79131D03*
X661588Y69662D03*
X658228Y88447D03*
X666200Y84862D03*
X654037Y96041D03*
X654326Y174437D03*
X663915Y234476D03*
X658905Y341885D03*
X653523Y399987D03*
X652954Y394284D03*
X662000Y433862D03*
X666000Y429844D03*
X652763Y427866D03*
X657622Y437819D03*
X651853Y439518D03*
X666000Y473844D03*
X660215Y483109D03*
X665689Y550294D03*
X660175Y679517D03*
X653376Y1365793D03*
X653101Y1369862D03*
X652651Y1375308D03*
X661710Y1514148D03*
X666092Y1553650D03*
X657430Y1555228D03*
X653542Y1649059D03*
X660389Y1654481D03*
X663431Y1645780D03*
X659837Y1698400D03*
X660930Y1730277D03*
X662120Y1720404D03*
X680864Y38190D03*
X674647D03*
X674036Y74522D03*
X667941Y80142D03*
X680800Y380280D03*
X676000Y378100D03*
X667090Y385150D03*
X679940Y400933D03*
X678000Y477862D03*
Y482862D03*
X681213Y495658D03*
X680488Y504784D03*
X672505Y766871D03*
X667971Y1654404D03*
X669178Y1646627D03*
X673480Y1662668D03*
X671631Y1690786D03*
X667701Y1705043D03*
X684611Y41857D03*
X682291Y46822D03*
X692390Y46939D03*
X687835Y37850D03*
X687345Y46940D03*
X690028Y70142D03*
X686891Y115868D03*
X685200Y377820D03*
X690105Y401775D03*
X684794Y402268D03*
X692996Y418358D03*
X694299Y413108D03*
X689269Y410420D03*
X695796Y430957D03*
Y437256D03*
Y468672D03*
X690452Y486984D03*
X687310Y500453D03*
Y522141D03*
X690718Y578913D03*
X694996Y575081D03*
X684350Y1448911D03*
X693495Y1519305D03*
X692209Y1620037D03*
X686808Y1643500D03*
X685578Y1637479D03*
X705666Y48010D03*
X697678Y47132D03*
X704201Y72112D03*
X699476Y69982D03*
X699398Y123668D03*
X704709Y125586D03*
X707500Y368862D03*
X700300Y382502D03*
X707500Y382362D03*
X700000Y386790D03*
X703500Y401290D03*
X708584Y404868D03*
X708395Y427807D03*
X705245Y437256D03*
X698946Y449854D03*
X708395Y456074D03*
Y478121D03*
Y471822D03*
Y484420D03*
X703774Y513463D03*
X708500Y517362D03*
X708210Y537816D03*
X704500Y529862D03*
X697018Y537577D03*
X700500Y545862D03*
X704500Y555862D03*
X710429Y545752D03*
X708056Y575081D03*
X704056Y583081D03*
X698996D03*
X702806Y613264D03*
X696928Y613207D03*
X705158Y645357D03*
X708418Y650389D03*
X702206Y766871D03*
X699247Y1508062D03*
X699140Y1513772D03*
X707050Y1531700D03*
X709150Y1536250D03*
X703290Y1551700D03*
X707050Y1548400D03*
Y1541800D03*
X703290Y1545100D03*
X708500Y1560500D03*
X708994Y1568507D03*
X699610Y1580523D03*
X708600Y1572523D03*
X710420Y1585173D03*
X710550Y1576523D03*
X710080Y1581683D03*
X709836Y1594721D03*
X710360Y1589296D03*
X709382Y1601210D03*
X709260Y1617903D03*
X714471Y46670D03*
X724621Y40062D03*
X719821Y45862D03*
X714322Y56286D03*
X714096Y73686D03*
X712717Y68541D03*
X719416Y68738D03*
Y74036D03*
X725016Y86952D03*
X720016D03*
X712341Y128093D03*
X723531Y368862D03*
X715500D03*
X719640Y386862D03*
X717843Y434106D03*
X720993Y427807D03*
Y468672D03*
X724143Y471822D03*
X714694Y468672D03*
X711544Y474971D03*
X724143Y481271D03*
X720993Y484420D03*
X716500Y521862D03*
X724500Y517362D03*
X720400Y517440D03*
X720500Y555862D03*
X719710Y612831D03*
X713343Y633842D03*
X724000Y633906D03*
X725812Y654713D03*
X715371Y654726D03*
X716373Y1398539D03*
X724110Y1561825D03*
X714900Y1571273D03*
X721440Y1570963D03*
X723590Y1595323D03*
X718892Y1597152D03*
X714372Y1594679D03*
X720106Y1609542D03*
X713718Y1610235D03*
X718129Y1624330D03*
X722889Y1622491D03*
X740101Y41162D03*
X736621Y45262D03*
X733315Y40862D03*
X728721Y43562D03*
X736864Y74943D03*
X731864D03*
X739824Y91052D03*
X734380Y80518D03*
X729380D03*
X736650Y102350D03*
X735771Y94988D03*
X730660Y108484D03*
X739500Y368862D03*
X731500D03*
X739553Y388270D03*
X727500Y386862D03*
X727292Y424657D03*
X739811Y430957D03*
X733512Y471822D03*
X727292Y487570D03*
X728938Y517520D03*
X739185Y521394D03*
X728576Y537476D03*
X736500Y537862D03*
X736647Y529772D03*
X740500Y545862D03*
X738260Y553625D03*
X728714Y554190D03*
X732520Y545988D03*
X736528Y579615D03*
X727253Y610689D03*
X730770Y644218D03*
X727448Y766871D03*
X735739Y1323048D03*
X730782Y1555496D03*
X726475Y1571293D03*
X726550Y1599358D03*
X728454Y1690491D03*
X732852Y1695701D03*
X746101Y46262D03*
X745901Y40362D03*
X747488Y71429D03*
X750701Y106642D03*
X754783Y96553D03*
X741309Y108742D03*
X743050Y139182D03*
X744911Y166887D03*
X751575Y184252D03*
X746522Y308804D03*
X747594Y319106D03*
X752926Y361021D03*
X755135Y368907D03*
X754813Y374362D03*
X743500Y386962D03*
X747629Y406163D03*
X755559Y421508D03*
X749260Y427807D03*
X752409Y440405D03*
Y462373D03*
X746110Y474971D03*
X752409Y478121D03*
X752500Y513362D03*
X753951Y521801D03*
X752965Y537678D03*
X748000Y537862D03*
X752500Y545862D03*
X753483Y648749D03*
X745201Y1400702D03*
X747150Y1583247D03*
X747110Y1579863D03*
X747160Y1587773D03*
X749167Y1591967D03*
X754635Y1592571D03*
X749261Y1628208D03*
X753770Y1636083D03*
X751521Y1659158D03*
X754030Y1669256D03*
X746766Y1696036D03*
X752187Y1691058D03*
X763221Y65132D03*
X757188Y91829D03*
X757576Y112575D03*
X770073Y143438D03*
X758111Y172636D03*
X758510Y298620D03*
X757937Y303908D03*
X763500Y386862D03*
X759500Y402098D03*
X767500Y401470D03*
X757258Y408763D03*
X765975Y414414D03*
X769648Y430511D03*
X758709Y427807D03*
X770530Y423460D03*
X758709Y434106D03*
X768301Y438223D03*
X770918Y442510D03*
X770042Y446829D03*
X758709Y465523D03*
Y459223D03*
X770590Y470940D03*
X765008Y474971D03*
X758709Y478121D03*
X764500Y513340D03*
X756800Y517050D03*
X764600Y517022D03*
X760660Y537862D03*
X761608Y766871D03*
X758163Y1506538D03*
X757826Y1514412D03*
X766950Y1581233D03*
X757610Y1584023D03*
X761510Y1638434D03*
X762030Y1668583D03*
X757557Y1684444D03*
X767381Y1676594D03*
X768463Y1687769D03*
X768733Y1694485D03*
X771356Y167518D03*
X771427Y158026D03*
X784500Y367500D03*
X775388Y390862D03*
X784498Y396353D03*
X782700Y415284D03*
X783256Y409340D03*
X783770Y422454D03*
X772610Y434690D03*
X783821Y431534D03*
X772677Y451374D03*
X780877Y443344D03*
X783877Y475344D03*
X783759Y479344D03*
X772427Y487344D03*
X783358Y495344D03*
X771039Y511292D03*
X777166Y504477D03*
X772100Y532700D03*
X781699Y536425D03*
X773463Y563455D03*
X785520Y1292160D03*
X782115Y1334173D03*
X778850Y1556133D03*
X794058Y301569D03*
X793221Y296062D03*
X793897Y309026D03*
X799226Y328467D03*
X792302Y357537D03*
X786571Y403455D03*
X796283Y415344D03*
X786877Y427344D03*
X796283Y423344D03*
X786999Y435476D03*
X786877Y443344D03*
X796333Y439344D03*
X786887Y451344D03*
X797463Y476159D03*
X786440Y480769D03*
X786102Y507536D03*
X790503Y501826D03*
X799450Y511801D03*
X800674Y504130D03*
X800500Y540500D03*
X792782Y565323D03*
X799742Y628983D03*
X791308Y766871D03*
X796020Y1292160D03*
X799150Y1581379D03*
X803302Y265848D03*
X810139Y274098D03*
X812070Y341590D03*
X805425Y395502D03*
X802270Y435372D03*
X802459Y443218D03*
X813114Y443344D03*
X802533Y449802D03*
X801552Y463318D03*
X802752Y459344D03*
X813114Y455344D03*
X812983Y476159D03*
X801874Y471344D03*
X802752Y480159D03*
X801762Y495344D03*
X802752Y487344D03*
X805150Y623843D03*
X801614Y1339062D03*
X811771Y1355488D03*
X810150Y1574633D03*
X810050Y1584033D03*
X820901Y147112D03*
X816232Y341584D03*
X818157Y381020D03*
X824653Y405347D03*
X817497Y427060D03*
X816239Y435344D03*
X816117Y443552D03*
X816236Y439279D03*
X816109Y449802D03*
X816000Y463578D03*
X816170Y458524D03*
X816109Y471344D03*
X816409Y467568D03*
X830212Y483892D03*
X827000Y489055D03*
X826552Y543612D03*
X823777Y560988D03*
X816550Y766871D03*
X822883Y780334D03*
X822982Y791245D03*
X822494Y802941D03*
X820850Y1556133D03*
X836780Y68008D03*
X839899Y87248D03*
X841585Y94181D03*
X831298Y104206D03*
X842865Y110296D03*
X835115Y115223D03*
X845221Y135862D03*
Y129362D03*
X837161Y213207D03*
X844527Y204968D03*
X838821Y206872D03*
X837161Y218212D03*
X836181Y275686D03*
X834430Y434634D03*
X838000Y423362D03*
X833800Y444700D03*
X841854Y504972D03*
X838342Y514610D03*
X841660Y558200D03*
X831505Y897291D03*
X831582Y905153D03*
X844250Y1266759D03*
X833756Y1330156D03*
X833963Y1339464D03*
X838963Y1345974D03*
X841039Y1358082D03*
X839244Y1352094D03*
X841472Y1365050D03*
X850016Y87341D03*
X847473Y94754D03*
X851895Y160141D03*
X856213Y191545D03*
X847581Y232222D03*
X856244Y286447D03*
X860071Y304850D03*
X851517Y411745D03*
X846000Y423362D03*
X847303Y485788D03*
X849772Y494585D03*
X849351Y499070D03*
X848097Y503315D03*
X847941Y538325D03*
X850684Y1310000D03*
X852050Y1584033D03*
X874295Y163862D03*
X863488Y176332D03*
X875170Y185113D03*
X867529Y231788D03*
X863104Y273103D03*
X868104D03*
X867701Y267537D03*
X863230Y280001D03*
X866619Y286801D03*
X871099Y323000D03*
X863420Y429362D03*
X860541Y446089D03*
X864361Y493001D03*
X862987Y507305D03*
X866727Y650739D03*
X869275Y750472D03*
X873175D03*
X868496Y776516D03*
X870591Y785437D03*
X865394Y801244D03*
X867651Y836820D03*
X865109Y850795D03*
X864768Y844815D03*
X864140Y856052D03*
X864003Y866609D03*
X874989Y1410441D03*
X863745Y1444560D03*
X862850Y1556133D03*
X889351Y195489D03*
X878221Y192055D03*
X881354Y267407D03*
X885764Y284361D03*
X877448Y284825D03*
X888000Y293000D03*
X884410Y794332D03*
X876923Y1239520D03*
X886707Y1235920D03*
X883379Y1417881D03*
X881987Y1449608D03*
X887519Y1444625D03*
X877226Y1441585D03*
X902376Y590172D03*
X903556Y614062D03*
X903925Y948500D03*
X900280Y1150769D03*
X891247Y1219520D03*
X896974Y1229869D03*
X904850Y1556133D03*
X894050Y1584033D03*
X894150Y1602633D03*
X917387Y184114D03*
X914575Y560027D03*
X915575Y948500D03*
X912500Y963309D03*
X907500D03*
X909000Y974000D03*
Y982000D03*
X919779Y1155658D03*
X912053Y1225520D03*
X910707Y1235920D03*
X922128Y182486D03*
X923386Y193563D03*
X920031Y577846D03*
X926449Y577806D03*
X926983Y604751D03*
X920989Y617692D03*
X930926Y664791D03*
X920234Y843349D03*
X927777Y843416D03*
X928500Y941500D03*
X923500D03*
X920107Y1229920D03*
X922000Y1324000D03*
X931326Y1328467D03*
X931216Y1323050D03*
X925500Y1333000D03*
X936454Y184015D03*
X937267Y189010D03*
X945120Y193264D03*
X949181Y280131D03*
X937310Y580755D03*
X939511Y597073D03*
X935746Y611573D03*
X935783Y631192D03*
X945602Y664653D03*
X939216Y664767D03*
X948644Y811190D03*
X938000Y862620D03*
X943000Y862823D03*
X942631Y943162D03*
X936960Y942898D03*
X937148Y1134343D03*
X947305Y1150769D03*
X946101Y1219520D03*
X935907Y1239520D03*
X945691Y1235920D03*
X935028Y1313769D03*
X949216Y1448337D03*
X944105Y1448317D03*
X961407Y205125D03*
X951102Y628662D03*
X951886Y804495D03*
X951466Y816400D03*
X955958Y1229869D03*
X964669Y1271000D03*
X963500Y1275000D03*
X954541Y1448307D03*
X961566Y1448341D03*
X963402Y1501204D03*
X958402D03*
X959584Y1550824D03*
X966907Y1225520D03*
X969691Y1235920D03*
X979091Y1229920D03*
X969519Y1452784D03*
X973255Y1456714D03*
X990579Y155248D03*
X988751Y167541D03*
X986447Y158209D03*
X989605Y175400D03*
X985922Y171861D03*
X982455Y260781D03*
Y271443D03*
X984509Y303623D03*
X988460Y358405D03*
X993460D03*
X992460Y370659D03*
X985668Y389311D03*
X980690Y387784D03*
X993650Y465315D03*
X988650D03*
X991270Y470212D03*
X988125Y485193D03*
X994056Y521014D03*
Y516014D03*
Y526074D03*
Y531074D03*
X982665Y1265474D03*
X988242Y1273193D03*
X980779Y1451545D03*
X981768Y1501204D03*
X991196Y1550840D03*
X1002736Y157943D03*
X995181Y157689D03*
X996416Y176579D03*
X1002921Y178799D03*
X1002827Y172479D03*
X1008918Y192994D03*
X1008121Y203525D03*
X1005641Y214969D03*
X1008707Y230423D03*
X997300Y234876D03*
X1006468Y301857D03*
X1003460Y358405D03*
X998460D03*
X1000460Y369535D03*
X996889Y374156D03*
X998359Y451675D03*
X1003909Y454662D03*
Y460162D03*
X996320Y470364D03*
X1002056Y521014D03*
Y516014D03*
Y526074D03*
Y531074D03*
X999304Y1282574D03*
Y1289215D03*
X995000Y1362000D03*
X1005134Y1501204D03*
X1023221Y191574D03*
X1011120Y198114D03*
X1011068Y207667D03*
X1021440Y226423D03*
X1019356Y222423D03*
X1010909Y213708D03*
X1011721Y233699D03*
X1023110Y287311D03*
X1023000Y298311D03*
X1009815Y404896D03*
X1020748Y420902D03*
X1023420Y462921D03*
X1017220Y464155D03*
X1023515Y454397D03*
X1019205Y457687D03*
X1023420Y468039D03*
X1017350Y472155D03*
X1022874Y474545D03*
X1019210Y480155D03*
X1013306Y532501D03*
X1019161Y554757D03*
X1024161D03*
X1017961Y545074D03*
X1009905Y1305500D03*
X1012500Y1322500D03*
Y1341580D03*
X1013500Y1332740D03*
X1016000Y1361000D03*
X1012500Y1347500D03*
X1022796Y1550840D03*
X1034214Y351601D03*
X1034409Y429618D03*
X1039015Y444404D03*
X1024509Y500168D03*
X1037254Y521014D03*
X1036708Y514883D03*
X1037254Y526074D03*
X1025631Y540104D03*
X1036021Y534990D03*
X1030000Y554500D03*
X1028500Y563000D03*
X1025493Y761819D03*
X1036427Y770532D03*
X1038867Y774960D03*
X1025493Y765719D03*
X1028500Y1501204D03*
X1042015Y444404D03*
X1043991Y540979D03*
X1039407Y547723D03*
X1042628Y556845D03*
X1040915Y766870D03*
X1051866Y1501204D03*
X1050866Y1659548D03*
X1053290Y1652082D03*
X1045545Y1663089D03*
X1055934Y388988D03*
X1068143Y380188D03*
X1055934Y381988D03*
X1062640Y449155D03*
X1057276Y458155D03*
X1062173Y479655D03*
X1062250Y484672D03*
X1056960Y482262D03*
X1058231Y523238D03*
X1060719Y512359D03*
Y516059D03*
X1054396Y1550840D03*
X1063751Y1653834D03*
X1068221Y1662778D03*
X1071698Y270702D03*
X1078400Y391226D03*
X1074654Y380188D03*
X1074249Y387795D03*
X1082866Y403068D03*
X1072738Y411322D03*
Y416763D03*
Y421922D03*
X1077873Y463444D03*
X1071710Y483655D03*
Y488782D03*
X1072232Y667749D03*
X1070616Y766870D03*
X1080555Y1380511D03*
X1075232Y1501204D03*
X1086714Y353515D03*
X1090061Y428019D03*
X1084840Y438234D03*
Y443515D03*
Y460005D03*
X1085851Y465978D03*
X1096473Y484391D03*
Y489391D03*
X1095730Y509362D03*
X1089934Y1550784D03*
X1097000Y1629500D03*
X1096469Y1643468D03*
X1096768Y1635080D03*
X1087141Y1688914D03*
X1089030Y1717841D03*
Y1722841D03*
X1107300Y456944D03*
X1111076Y464388D03*
X1108076Y646774D03*
X1100316Y766870D03*
X1109201Y1382574D03*
X1099098Y1501204D03*
X1102248Y1496186D03*
X1112529Y1547661D03*
X1111701Y1558640D03*
X1100961Y1622543D03*
X1105000Y1682132D03*
X1099108Y1691229D03*
X1121628Y401915D03*
X1121077Y511498D03*
X1126387Y615658D03*
X1120321Y635832D03*
X1119067Y1551457D03*
X1115394Y1620306D03*
X1116000Y1671029D03*
X1122610Y1677976D03*
X1124091Y1683983D03*
X1113948Y1711244D03*
X1142830Y53186D03*
X1142144Y63186D03*
X1141267Y500296D03*
X1129387Y615658D03*
X1138387D03*
X1130017Y766870D03*
X1142639Y1562789D03*
X1138480Y1576364D03*
X1132168Y1620860D03*
X1132981Y1634531D03*
X1132209Y1672033D03*
X1151679Y72258D03*
X1151036Y501627D03*
X1155282Y766806D03*
X1147814Y1562823D03*
X1154336Y1555979D03*
X1149278Y1589453D03*
X1158343Y1658514D03*
X1151985Y1666685D03*
X1152114Y1672517D03*
X1152211Y1682373D03*
X1168687Y74202D03*
X1158764Y489516D03*
X1162067Y570050D03*
X1159718Y766870D03*
X1163485Y1546195D03*
X1161492Y1551175D03*
X1172523Y1573250D03*
X1165806Y1658934D03*
X1159688Y1665427D03*
X1169098Y1666278D03*
X1169187Y1687117D03*
X1183354Y77685D03*
X1185913Y93634D03*
X1174031Y403519D03*
X1181000Y402500D03*
X1185952Y432202D03*
Y440202D03*
Y448202D03*
X1178340Y447734D03*
X1185707Y465272D03*
X1186040Y481691D03*
X1182950Y577030D03*
X1178000Y572602D03*
X1182594Y587759D03*
X1178000Y592673D03*
X1182256Y632368D03*
X1184960Y766870D03*
X1178932Y1686698D03*
X1185676Y1697249D03*
X1198694Y57015D03*
X1191488Y87125D03*
X1200518Y100875D03*
X1200037Y160987D03*
X1189701Y173187D03*
X1201157Y431875D03*
X1193040Y481691D03*
X1199370Y578154D03*
X1195236Y581407D03*
X1195336Y586606D03*
X1194296Y1396500D03*
X1203242Y1417440D03*
X1202548Y1407453D03*
X1202857Y1412454D03*
X1202411Y1427410D03*
X1203117Y1422452D03*
X1202475Y1432468D03*
X1203040Y1437500D03*
X1194000Y1442500D03*
X1197980Y1688270D03*
X1189263Y1682551D03*
X1190830Y1675710D03*
X1189462Y1691366D03*
X1197612Y1703334D03*
X1192612D03*
X1196767Y1712261D03*
X1199294Y1721143D03*
X1196814Y1726261D03*
X1206580Y94846D03*
X1208431Y128748D03*
X1215528Y172395D03*
X1214094Y269008D03*
Y282948D03*
Y287948D03*
X1213866Y455376D03*
X1208733Y585986D03*
X1204334Y668138D03*
X1211555Y1380511D03*
X1210400Y1440000D03*
X1212954Y1703343D03*
X1207954D03*
X1207770Y1717011D03*
X1223455Y91346D03*
X1227803Y94210D03*
X1221411Y134230D03*
X1221512Y128239D03*
X1231118Y142125D03*
X1230094Y269008D03*
X1222094D03*
X1230094Y287948D03*
Y282948D03*
X1222094D03*
Y292066D03*
Y305216D03*
X1226094Y314216D03*
X1218430Y421012D03*
X1228800Y1391300D03*
X1219650Y1392050D03*
X1219500Y1398900D03*
X1224200Y1393500D03*
X1219500Y1436000D03*
X1221837Y1438800D03*
X1220200Y1449100D03*
X1219738Y1713861D03*
Y1708861D03*
Y1722861D03*
Y1727861D03*
X1239218Y128239D03*
Y137239D03*
X1247834Y159844D03*
X1246094Y269008D03*
X1238094D03*
X1233468Y419742D03*
X1242429Y443255D03*
X1242692Y483435D03*
X1239800Y1389500D03*
X1235400Y1391200D03*
X1238500Y1400900D03*
X1234900Y1404400D03*
X1233700Y1395600D03*
X1238200Y1395500D03*
X1235679Y1418908D03*
X1249152Y72895D03*
X1256064Y101100D03*
X1249065Y241594D03*
Y236594D03*
Y251594D03*
Y246594D03*
X1262094Y269008D03*
X1254094D03*
X1262094Y282948D03*
X1254094D03*
X1262094Y287948D03*
X1260107Y399125D03*
X1260227Y411128D03*
X1256137Y459182D03*
Y453872D03*
X1248902Y470733D03*
X1257016Y467253D03*
X1275981Y85114D03*
X1269146Y121022D03*
X1263146D03*
X1267037Y180565D03*
X1270094Y269008D03*
Y282948D03*
Y292066D03*
X1275585Y393597D03*
X1269840Y411128D03*
X1287486Y134165D03*
X1278137Y171551D03*
Y184987D03*
X1279447Y213292D03*
X1278094Y269008D03*
X1286094D03*
X1278094Y282948D03*
X1286094D03*
Y292066D03*
X1289352Y421950D03*
X1279525Y1432000D03*
X1287700Y1431700D03*
X1299196Y76209D03*
X1305685Y74748D03*
X1300668Y125739D03*
X1306431Y149330D03*
X1300668Y145739D03*
X1294094Y269008D03*
X1302094D03*
X1294094Y287948D03*
Y282948D03*
X1302094D03*
Y292066D03*
X1293277Y401125D03*
X1296228Y408125D03*
X1302500Y664500D03*
X1296000Y1427700D03*
X1301900D03*
X1295700Y1421800D03*
X1300800D03*
X1302390Y1530430D03*
X1319667Y87587D03*
Y105227D03*
X1310094Y269008D03*
X1318094D03*
X1310094Y287948D03*
Y282948D03*
X1318094D03*
X1309870Y552788D03*
X1316266Y564514D03*
X1309776Y559831D03*
X1308900Y1525510D03*
X1312700Y1579596D03*
X1319349Y1585567D03*
X1327541Y105227D03*
X1337399Y98084D03*
X1326094Y269008D03*
X1334094D03*
Y287948D03*
X1326094Y282948D03*
X1334094D03*
X1326094Y292066D03*
X1330820Y525165D03*
Y518265D03*
X1330658Y538749D03*
X1329585Y561806D03*
X1351750Y72826D03*
X1339840Y72860D03*
X1344958Y85358D03*
X1342094Y269008D03*
X1350094D03*
Y287948D03*
X1342094Y282948D03*
X1350094D03*
X1342094Y292066D03*
X1361550Y67264D03*
X1356868Y85324D03*
X1364369Y120380D03*
X1358094Y269008D03*
X1366094D03*
Y287948D03*
X1358094Y282948D03*
X1366094D03*
X1358094Y292066D03*
X1369808Y87587D03*
X1377682D03*
X1371259Y98000D03*
X1373862Y511052D03*
X1381457Y511050D03*
X1382123Y614130D03*
X1382045Y1700038D03*
X1383715Y236594D03*
Y241594D03*
X1385068Y1664907D03*
X1390738Y1664938D03*
X1390179Y1733118D03*
X1411000Y460362D03*
X1403232Y1579519D03*
X1409286Y1605796D03*
X1400029Y1615796D03*
X1406447Y1619572D03*
X1417000Y460362D03*
X1414823Y647030D03*
X1414157Y670665D03*
X1416862Y1582871D03*
X1419811Y1599084D03*
X1416709Y1592819D03*
X1413836Y1586944D03*
X1418000Y1607500D03*
X1421392Y1621706D03*
X1421890Y1635500D03*
X1418755Y1654999D03*
X1431262Y61392D03*
X1435584Y1596545D03*
X1438565Y1612583D03*
X1430319Y1623504D03*
X1430238Y1617137D03*
X1429072Y1643655D03*
X1433618Y1659331D03*
X1433157Y1651977D03*
X1438078Y1669992D03*
X1439316Y1675080D03*
X1454769Y163842D03*
X1449769Y174217D03*
X1456500Y457000D03*
X1441898Y576755D03*
X1447423Y679610D03*
X1446757Y703265D03*
X1447026Y1577299D03*
X1455461Y1585567D03*
X1455579Y1665701D03*
X1466681Y78590D03*
X1462682Y450372D03*
X1456982Y437362D03*
X1472129Y56083D03*
X1472647Y539478D03*
X1473444Y555208D03*
X1473408Y547948D03*
X1478147Y547728D03*
X1473362Y558380D03*
X1481898Y585476D03*
X1484347Y580388D03*
X1479757Y722865D03*
X1480677Y813488D03*
X1486000Y1686000D03*
X1497386Y464980D03*
X1495682Y473302D03*
X1492514Y539657D03*
X1488510Y542816D03*
X1487660Y585748D03*
X1492789Y576602D03*
X1500500Y809063D03*
X1498177Y829359D03*
X1488875Y1677385D03*
X1514576Y219730D03*
X1502085Y545432D03*
X1507109Y550059D03*
X1507644Y554372D03*
X1507468Y564357D03*
X1502757Y570977D03*
X1509757Y575477D03*
X1501821Y577664D03*
X1512757Y722897D03*
X1529384Y201245D03*
X1519120Y479215D03*
X1519457Y556338D03*
X1527853Y560264D03*
X1536422Y292816D03*
X1536542Y304819D03*
X1534584Y467067D03*
X1539693Y543613D03*
X1532824Y555981D03*
X1539693Y558943D03*
X1539344Y1579519D03*
X1556960Y287478D03*
X1551900Y287288D03*
X1548772Y291916D03*
X1551779Y530698D03*
X1546257Y701097D03*
X1551113Y1238088D03*
X1560454Y1279004D03*
X1555222Y1302757D03*
X1569592Y294816D03*
X1572283Y301816D03*
X1564506Y310334D03*
X1572436Y582433D03*
Y574022D03*
X1570021Y682038D03*
X1567737Y1271411D03*
X1568456Y1311533D03*
X1572416Y1303160D03*
X1564268Y1338440D03*
X1572331Y1348205D03*
X1574966Y1577038D03*
X1576843Y674425D03*
X1585290Y1285098D03*
X1584156Y1381419D03*
X1586000Y1387641D03*
X1590723Y1381589D03*
X1583523Y1585567D03*
X1603970Y222956D03*
X1599837Y295328D03*
X1604890Y531226D03*
X1596299Y536344D03*
X1590921Y1309276D03*
X1597621Y1365384D03*
X1592788Y1388318D03*
X1597234Y1382689D03*
X1619909Y298742D03*
Y293742D03*
X1616084Y549105D03*
X1616198Y556364D03*
X1618859Y542820D03*
X1607369Y561330D03*
X1618356Y609137D03*
X1617200Y766870D03*
X1629597Y221842D03*
X1631657Y392925D03*
X1622391Y564169D03*
X1635281Y1422450D03*
X1635227Y1436528D03*
X1642135Y414202D03*
X1647110Y434177D03*
X1635944Y609510D03*
X1645123Y624478D03*
X1644188Y766870D03*
X1644001Y1408069D03*
X1646483Y1412741D03*
X1635619Y1430536D03*
X1639834Y1434478D03*
X1636167Y1446746D03*
X1642400Y1439674D03*
X1650400Y1437820D03*
X1641167Y1446746D03*
X1648337Y1451313D03*
X1645029Y1715609D03*
Y1710609D03*
Y1725759D03*
Y1730759D03*
X1652525Y141762D03*
X1661110Y434177D03*
X1654110D03*
X1657194Y599956D03*
X1651194D03*
X1657194Y609450D03*
X1651194D03*
X1654147Y616523D03*
X1664106Y1397828D03*
X1661807Y1416948D03*
X1663777Y1421568D03*
X1656101Y1671720D03*
X1651101Y1671833D03*
X1651698Y1665045D03*
X1656101Y1701094D03*
X1673100Y121762D03*
Y136762D03*
X1668516Y599956D03*
X1674516D03*
X1668516Y609450D03*
X1674516D03*
X1673889Y766870D03*
X1671079Y1435069D03*
X1676685Y1537893D03*
X1671034Y1546934D03*
X1676971Y1668582D03*
X1670202Y1663150D03*
X1675290Y1663157D03*
X1680029Y1710609D03*
Y1715609D03*
X1695100Y121762D03*
Y136762D03*
Y131762D03*
Y146762D03*
Y156762D03*
Y161762D03*
Y166762D03*
X1682408Y228337D03*
X1692429Y403985D03*
X1694050Y416643D03*
X1690208Y421855D03*
X1692450Y436772D03*
X1692934Y1399991D03*
X1681538Y1451522D03*
X1689062Y1451496D03*
X1684172Y1538135D03*
X1686675Y1659287D03*
X1680367Y1663367D03*
X1684733Y1698952D03*
X1695102Y1698947D03*
X1689184Y1702095D03*
X1680877Y1723593D03*
X1702959Y404243D03*
X1697161Y406602D03*
X1707780Y410738D03*
X1695455Y422287D03*
X1707568Y420370D03*
X1701124Y423802D03*
X1707544Y431745D03*
X1701661Y644554D03*
X1705561D03*
X1699500Y654738D03*
Y673738D03*
X1708049Y766870D03*
X1709964Y1597490D03*
X1709833Y1612940D03*
Y1606340D03*
X1701984Y1671618D03*
X1695987D03*
X1717148Y19910D03*
X1722085Y25908D03*
X1717055D03*
X1723241Y48822D03*
X1721646Y68115D03*
X1716558Y67866D03*
X1712686Y111908D03*
X1713399Y132858D03*
X1721384Y135373D03*
X1718465Y657982D03*
X1720050Y649142D03*
X1716030Y668182D03*
X1718686Y676154D03*
X1718425Y1468245D03*
X1715693Y1597190D03*
X1719893Y1612940D03*
Y1603040D03*
X1713593Y1609640D03*
Y1603040D03*
X1719181Y1706712D03*
X1721172Y1712115D03*
X1719218Y1727265D03*
X1719148Y1721530D03*
X1728965Y112941D03*
X1729046Y118178D03*
X1739686Y120938D03*
X1725344Y359334D03*
X1733043Y657091D03*
X1736848Y650974D03*
X1737002Y671494D03*
X1737850Y766794D03*
X1726604Y1540970D03*
X1736479Y1584330D03*
X1735463Y1651965D03*
X1730381Y1647386D03*
X1734500Y1656965D03*
X1734589Y1666203D03*
X1734962Y1662965D03*
X1734963Y1673465D03*
X1734763Y1680465D03*
X1731936Y1690165D03*
X1732251Y1708265D03*
X1748708Y26641D03*
X1751031Y39063D03*
X1743491Y92827D03*
X1748686Y97408D03*
X1750786Y120018D03*
X1744976Y122998D03*
X1754339Y128242D03*
X1744510Y377452D03*
X1744380Y382892D03*
X1742306Y661032D03*
X1746779Y1583378D03*
X1751558Y1579332D03*
X1750463Y1654465D03*
X1744963Y1656465D03*
X1744463Y1651229D03*
X1751340Y1686140D03*
X1744620Y1716018D03*
X1747120Y1710824D03*
X1765920Y17031D03*
Y22031D03*
X1767266Y48748D03*
X1765527Y53692D03*
X1767956Y76843D03*
X1767136Y83653D03*
X1764644Y122973D03*
X1768041Y556537D03*
X1767450Y766870D03*
X1769054Y1585705D03*
X1755463Y1654465D03*
X1767888Y1664465D03*
X1765163Y1670543D03*
X1765463Y1677465D03*
X1761463Y1683465D03*
X1770920Y17031D03*
Y22031D03*
X1775920D03*
X1773830Y49000D03*
X1779377Y50738D03*
X1775546Y73376D03*
X1781451Y88238D03*
X1773577Y88339D03*
X1776930Y179051D03*
X1770520Y364148D03*
X1782376Y558324D03*
X1780579Y1582178D03*
X1787826Y37548D03*
X1785108Y76078D03*
X1787756Y85178D03*
X1797692Y146285D03*
X1787390Y156834D03*
X1785320Y193072D03*
X1784915Y186053D03*
X1789771Y367866D03*
X1797929Y385293D03*
X1786260Y379059D03*
X1792507Y403932D03*
X1792335Y418775D03*
X1792450Y410615D03*
X1792220Y425432D03*
X1788376Y558324D03*
X1792692Y766870D03*
X1807546Y59443D03*
X1806470Y186866D03*
X1811274Y198098D03*
X1808429Y218837D03*
X1811606Y226438D03*
X1803129Y362293D03*
X1802929Y385293D03*
X1818828Y175241D03*
X1817275Y180619D03*
X1816190Y208879D03*
X1820307Y373829D03*
X1828669Y379552D03*
X1820656Y388051D03*
X1820144Y398052D03*
X1819374Y410432D03*
X1818874Y423932D03*
X1822394Y436225D03*
X1829732Y371329D03*
X2392820Y1395606D03*
G54D14*
X27048Y1533228D03*
X79590Y1369350D03*
X137284Y1533228D03*
X215418Y658055D03*
X276440Y1357539D03*
X420125Y656008D03*
X443764Y1339823D03*
X523173Y578174D03*
X681440Y1385138D03*
X791678D03*
X873622Y1145275D03*
X983858D03*
X1052960Y1369350D03*
X1249812Y1357539D03*
X1370284Y582303D03*
X1417134Y1339823D03*
X1533552Y682342D03*
X1629732Y1383523D03*
X1664890Y642972D03*
X1714330Y1570984D03*
X1739968Y1383527D03*
X1761575Y159134D03*
X1824566Y1570988D03*
X1838150Y201929D03*
X2392820Y568206D03*
G54D41*
X1225530Y67471D03*
X1454797Y80345D03*
X2392820Y154506D03*
G54D32*
X766889Y1486756D03*
Y1530256D03*
X2392820Y331806D03*
G54D23*
X230905Y1649173D03*
Y1653897D03*
Y1644448D03*
Y1649173D03*
Y1653897D03*
Y1663346D03*
Y1668070D03*
Y1658621D03*
Y1663346D03*
Y1668070D03*
Y1672795D03*
Y1677519D03*
Y1682244D03*
Y1677519D03*
Y1682244D03*
Y1686968D03*
Y1691692D03*
Y1696417D03*
Y1691692D03*
Y1696417D03*
Y1701141D03*
Y1705866D03*
Y1710590D03*
Y1705866D03*
Y1710590D03*
Y1715314D03*
Y1720039D03*
Y1724763D03*
Y1720039D03*
Y1724763D03*
Y1729488D03*
Y1734212D03*
X238779Y1653110D03*
Y1657834D03*
X246653Y1644448D03*
X238779Y1643661D03*
X246653Y1649173D03*
X238779Y1648385D03*
X246653Y1653897D03*
X238779Y1653110D03*
X246653Y1663346D03*
Y1668070D03*
Y1658621D03*
X238779Y1657834D03*
X246653Y1663346D03*
X238779Y1662558D03*
X246653Y1668070D03*
X238779Y1667283D03*
X246653Y1672795D03*
X238779Y1672007D03*
X246653Y1677519D03*
Y1682244D03*
X238779Y1681456D03*
Y1686180D03*
X246653Y1677519D03*
X238779Y1676732D03*
X246653Y1682244D03*
X238779Y1681456D03*
X246653Y1686968D03*
X238779Y1686180D03*
X246653Y1691692D03*
Y1696417D03*
X238779Y1695629D03*
Y1700354D03*
X246653Y1691692D03*
X238779Y1690905D03*
X246653Y1696417D03*
X238779Y1695629D03*
X246653Y1701141D03*
X238779Y1700354D03*
X246653Y1705866D03*
Y1710590D03*
X238779Y1709803D03*
Y1714527D03*
X246653Y1705866D03*
X238779Y1705078D03*
X246653Y1710590D03*
X238779Y1709803D03*
X246653Y1715314D03*
X238779Y1714527D03*
X246653Y1720039D03*
Y1724763D03*
X238779Y1723976D03*
Y1728700D03*
X246653Y1720039D03*
X238779Y1719251D03*
X246653Y1724763D03*
X238779Y1723976D03*
X246653Y1729488D03*
X238779Y1728700D03*
X246653Y1734212D03*
X238779Y1733425D03*
X254527Y1643661D03*
Y1648385D03*
Y1653110D03*
Y1667283D03*
Y1672007D03*
Y1657834D03*
Y1662558D03*
Y1667283D03*
Y1672007D03*
X262401Y1677519D03*
Y1682244D03*
X254527Y1681456D03*
Y1686180D03*
Y1676732D03*
Y1681456D03*
Y1686180D03*
Y1695629D03*
Y1700354D03*
X262401Y1691692D03*
Y1696417D03*
X254527Y1690905D03*
Y1695629D03*
Y1700354D03*
X262401Y1705866D03*
Y1710590D03*
X254527Y1709803D03*
Y1714527D03*
Y1705078D03*
Y1709803D03*
Y1714527D03*
Y1723976D03*
Y1728700D03*
X262401Y1720039D03*
Y1724763D03*
X254527Y1719251D03*
Y1723976D03*
Y1728700D03*
Y1733425D03*
X278149Y1649173D03*
Y1653897D03*
X270275Y1653110D03*
Y1657834D03*
Y1643661D03*
X262401Y1644448D03*
X270275Y1648385D03*
X262401Y1649173D03*
X270275Y1653110D03*
X262401Y1653897D03*
X270275Y1667283D03*
Y1672007D03*
X278149Y1663346D03*
Y1668070D03*
X270275Y1657834D03*
X262401Y1658621D03*
X270275Y1662558D03*
X262401Y1663346D03*
X270275Y1667283D03*
X262401Y1668070D03*
X270275Y1672007D03*
X262401Y1672795D03*
X278149Y1677519D03*
Y1682244D03*
X270275Y1681456D03*
Y1686180D03*
Y1676732D03*
X262401Y1677519D03*
X270275Y1681456D03*
X262401Y1682244D03*
X270275Y1686180D03*
X262401Y1686968D03*
X270275Y1695629D03*
Y1700354D03*
X278149Y1691692D03*
Y1696417D03*
X270275Y1690905D03*
X262401Y1691692D03*
X270275Y1695629D03*
X262401Y1696417D03*
X270275Y1700354D03*
X262401Y1701141D03*
X278149Y1705866D03*
Y1710590D03*
X270275Y1709803D03*
Y1714527D03*
Y1705078D03*
X262401Y1705866D03*
X270275Y1709803D03*
X262401Y1710590D03*
X270275Y1714527D03*
X262401Y1715314D03*
X270275Y1723976D03*
Y1728700D03*
X278149Y1720039D03*
Y1724763D03*
X270275Y1719251D03*
X262401Y1720039D03*
X270275Y1723976D03*
X262401Y1724763D03*
X270275Y1728700D03*
X262401Y1729488D03*
X270275Y1733425D03*
X262401Y1734212D03*
X286023Y1653110D03*
Y1657834D03*
Y1643661D03*
X278149Y1644448D03*
X286023Y1648385D03*
X278149Y1649173D03*
X286023Y1653110D03*
X278149Y1653897D03*
X286023Y1667283D03*
Y1672007D03*
Y1657834D03*
X278149Y1658621D03*
X286023Y1662558D03*
X278149Y1663346D03*
X286023Y1667283D03*
X278149Y1668070D03*
X286023Y1672007D03*
X278149Y1672795D03*
X286023Y1681456D03*
Y1686180D03*
Y1676732D03*
X278149Y1677519D03*
X286023Y1681456D03*
X278149Y1682244D03*
X286023Y1686180D03*
X278149Y1686968D03*
X286023Y1695629D03*
Y1700354D03*
Y1690905D03*
X278149Y1691692D03*
X286023Y1695629D03*
X278149Y1696417D03*
X286023Y1700354D03*
X278149Y1701141D03*
X286023Y1709803D03*
Y1714527D03*
Y1705078D03*
X278149Y1705866D03*
X286023Y1709803D03*
X278149Y1710590D03*
X286023Y1714527D03*
X278149Y1715314D03*
X286023Y1723976D03*
Y1728700D03*
Y1719251D03*
X278149Y1720039D03*
X286023Y1723976D03*
X278149Y1724763D03*
X286023Y1728700D03*
X278149Y1729488D03*
X286023Y1733425D03*
X278149Y1734212D03*
X305709Y1672007D03*
X297835Y1672795D03*
X305709Y1681456D03*
Y1686180D03*
X297835Y1677519D03*
Y1682244D03*
X305709Y1676732D03*
X297835Y1677519D03*
X305709Y1681456D03*
X297835Y1682244D03*
X305709Y1686180D03*
X297835Y1686968D03*
Y1691692D03*
X305709Y1695629D03*
X297835Y1696417D03*
X305709Y1700354D03*
Y1690905D03*
X297835Y1691692D03*
X305709Y1695629D03*
X297835Y1696417D03*
X305709Y1700354D03*
X297835Y1701141D03*
X305709Y1709803D03*
Y1714527D03*
X297835Y1705866D03*
Y1710590D03*
X305709Y1705078D03*
X297835Y1705866D03*
X305709Y1709803D03*
X297835Y1710590D03*
X305709Y1714527D03*
X297835Y1715314D03*
Y1720039D03*
X305709Y1723976D03*
X297835Y1724763D03*
X305709Y1728700D03*
Y1719251D03*
X297835Y1720039D03*
X305709Y1723976D03*
X297835Y1724763D03*
X305709Y1728700D03*
X297835Y1729488D03*
X305709Y1733425D03*
X297835Y1734212D03*
X321457Y1672007D03*
X313583Y1672795D03*
X321457Y1681456D03*
Y1686180D03*
X313583Y1677519D03*
Y1682244D03*
X321457Y1676732D03*
X313583Y1677519D03*
X321457Y1681456D03*
X313583Y1682244D03*
X321457Y1686180D03*
X313583Y1686968D03*
Y1691692D03*
X321457Y1695629D03*
X313583Y1696417D03*
X321457Y1700354D03*
Y1690905D03*
X313583Y1691692D03*
X321457Y1695629D03*
X313583Y1696417D03*
X321457Y1700354D03*
X313583Y1701141D03*
X321457Y1709803D03*
Y1714527D03*
X313583Y1705866D03*
Y1710590D03*
X321457Y1705078D03*
X313583Y1705866D03*
X321457Y1709803D03*
X313583Y1710590D03*
X321457Y1714527D03*
X313583Y1715314D03*
Y1720039D03*
X321457Y1723976D03*
X313583Y1724763D03*
X321457Y1728700D03*
Y1719251D03*
X313583Y1720039D03*
X321457Y1723976D03*
X313583Y1724763D03*
X321457Y1728700D03*
X313583Y1729488D03*
X321457Y1733425D03*
X313583Y1734212D03*
X329331Y1672795D03*
X337205Y1681456D03*
Y1686180D03*
X329331Y1677519D03*
Y1682244D03*
Y1677519D03*
Y1682244D03*
Y1686968D03*
Y1691692D03*
Y1696417D03*
X337205Y1695629D03*
Y1700354D03*
X329331Y1691692D03*
Y1696417D03*
Y1701141D03*
X337205Y1709803D03*
Y1714527D03*
X329331Y1705866D03*
Y1710590D03*
Y1705866D03*
Y1710590D03*
Y1715314D03*
Y1720039D03*
Y1724763D03*
X337205Y1723976D03*
Y1728700D03*
X329331Y1720039D03*
Y1724763D03*
Y1729488D03*
Y1734212D03*
X345079Y1672795D03*
X337205Y1672007D03*
X352953Y1681456D03*
Y1686180D03*
X345079Y1677519D03*
Y1682244D03*
Y1677519D03*
X337205Y1676732D03*
X345079Y1682244D03*
X337205Y1681456D03*
X345079Y1686968D03*
X337205Y1686180D03*
X345079Y1691692D03*
Y1696417D03*
X352953Y1695629D03*
Y1700354D03*
X345079Y1691692D03*
X337205Y1690905D03*
X345079Y1696417D03*
X337205Y1695629D03*
X345079Y1701141D03*
X337205Y1700354D03*
X352953Y1709803D03*
Y1714527D03*
X345079Y1705866D03*
Y1710590D03*
Y1705866D03*
X337205Y1705078D03*
X345079Y1710590D03*
X337205Y1709803D03*
X345079Y1715314D03*
X337205Y1714527D03*
X345079Y1720039D03*
Y1724763D03*
X352953Y1723976D03*
Y1728700D03*
X345079Y1720039D03*
X337205Y1719251D03*
X345079Y1724763D03*
X337205Y1723976D03*
X345079Y1729488D03*
X337205Y1728700D03*
X345079Y1734212D03*
X337205Y1733425D03*
X352953Y1672007D03*
Y1676732D03*
Y1681456D03*
Y1686180D03*
Y1690905D03*
Y1695629D03*
Y1700354D03*
Y1705078D03*
Y1709803D03*
Y1714527D03*
Y1719251D03*
Y1723976D03*
Y1728700D03*
Y1733425D03*
X495078Y1672795D03*
Y1677519D03*
Y1682244D03*
Y1677519D03*
Y1682244D03*
Y1686968D03*
Y1691692D03*
Y1696417D03*
Y1691692D03*
Y1696417D03*
Y1701141D03*
Y1705866D03*
Y1710590D03*
Y1705866D03*
Y1710590D03*
Y1715314D03*
Y1720039D03*
Y1724763D03*
Y1720039D03*
Y1724763D03*
Y1729488D03*
Y1734212D03*
X510826Y1672795D03*
X502952Y1672007D03*
X510826Y1677519D03*
Y1682244D03*
X502952Y1681456D03*
Y1686180D03*
X510826Y1677519D03*
X502952Y1676732D03*
X510826Y1682244D03*
X502952Y1681456D03*
X510826Y1686968D03*
X502952Y1686180D03*
X510826Y1691692D03*
Y1696417D03*
X502952Y1695629D03*
Y1700354D03*
X510826Y1691692D03*
X502952Y1690905D03*
X510826Y1696417D03*
X502952Y1695629D03*
X510826Y1701141D03*
X502952Y1700354D03*
X510826Y1705866D03*
Y1710590D03*
X502952Y1709803D03*
Y1714527D03*
X510826Y1705866D03*
X502952Y1705078D03*
X510826Y1710590D03*
X502952Y1709803D03*
X510826Y1715314D03*
X502952Y1714527D03*
X510826Y1720039D03*
Y1724763D03*
X502952Y1723976D03*
Y1728700D03*
X510826Y1720039D03*
X502952Y1719251D03*
X510826Y1724763D03*
X502952Y1723976D03*
X510826Y1729488D03*
X502952Y1728700D03*
X510826Y1734212D03*
X502952Y1733425D03*
X518700Y1672007D03*
X526574Y1672795D03*
X518700Y1681456D03*
Y1686180D03*
X526574Y1677519D03*
Y1682244D03*
X518700Y1676732D03*
Y1681456D03*
Y1686180D03*
X526574Y1677519D03*
Y1682244D03*
Y1686968D03*
X518700Y1695629D03*
Y1700354D03*
X526574Y1691692D03*
Y1696417D03*
X518700Y1690905D03*
Y1695629D03*
Y1700354D03*
X526574Y1691692D03*
Y1696417D03*
Y1701141D03*
X518700Y1709803D03*
Y1714527D03*
X526574Y1705866D03*
Y1710590D03*
X518700Y1705078D03*
Y1709803D03*
Y1714527D03*
X526574Y1705866D03*
Y1710590D03*
Y1715314D03*
X518700Y1723976D03*
Y1728700D03*
X526574Y1720039D03*
Y1724763D03*
X518700Y1719251D03*
Y1723976D03*
Y1728700D03*
X526574Y1720039D03*
Y1724763D03*
Y1729488D03*
X518700Y1733425D03*
X526574Y1734212D03*
X542322Y1672795D03*
X534448Y1672007D03*
X542322Y1677519D03*
Y1682244D03*
X534448Y1681456D03*
Y1686180D03*
X542322Y1677519D03*
X534448Y1676732D03*
X542322Y1682244D03*
X534448Y1681456D03*
X542322Y1686968D03*
X534448Y1686180D03*
X542322Y1691692D03*
Y1696417D03*
X534448Y1695629D03*
Y1700354D03*
X542322Y1691692D03*
X534448Y1690905D03*
X542322Y1696417D03*
X534448Y1695629D03*
X542322Y1701141D03*
X534448Y1700354D03*
X542322Y1705866D03*
Y1710590D03*
X534448Y1709803D03*
Y1714527D03*
X542322Y1705866D03*
X534448Y1705078D03*
X542322Y1710590D03*
X534448Y1709803D03*
X542322Y1715314D03*
X534448Y1714527D03*
X542322Y1720039D03*
Y1724763D03*
X534448Y1723976D03*
Y1728700D03*
X542322Y1720039D03*
X534448Y1719251D03*
X542322Y1724763D03*
X534448Y1723976D03*
X542322Y1729488D03*
X534448Y1728700D03*
X542322Y1734212D03*
X534448Y1733425D03*
X550196Y1672007D03*
Y1681456D03*
Y1686180D03*
Y1676732D03*
Y1681456D03*
Y1686180D03*
Y1695629D03*
Y1700354D03*
Y1690905D03*
Y1695629D03*
Y1700354D03*
Y1709803D03*
Y1714527D03*
Y1705078D03*
Y1709803D03*
Y1714527D03*
Y1723976D03*
Y1728700D03*
Y1719251D03*
Y1723976D03*
Y1728700D03*
Y1733425D03*
X569882Y1672007D03*
X562008Y1672795D03*
Y1677519D03*
X569882Y1681456D03*
X562008Y1682244D03*
X569882Y1686180D03*
Y1676732D03*
X562008Y1677519D03*
X569882Y1681456D03*
X562008Y1682244D03*
X569882Y1686180D03*
X562008Y1686968D03*
Y1691692D03*
X569882Y1695629D03*
X562008Y1696417D03*
X569882Y1700354D03*
Y1690905D03*
X562008Y1691692D03*
X569882Y1695629D03*
X562008Y1696417D03*
X569882Y1700354D03*
X562008Y1701141D03*
Y1705866D03*
X569882Y1709803D03*
X562008Y1710590D03*
X569882Y1714527D03*
Y1705078D03*
X562008Y1705866D03*
X569882Y1709803D03*
X562008Y1710590D03*
X569882Y1714527D03*
X562008Y1715314D03*
Y1720039D03*
X569882Y1723976D03*
X562008Y1724763D03*
X569882Y1728700D03*
Y1719251D03*
X562008Y1720039D03*
X569882Y1723976D03*
X562008Y1724763D03*
X569882Y1728700D03*
X562008Y1729488D03*
X569882Y1733425D03*
X562008Y1734212D03*
X585630Y1672007D03*
X577756Y1672795D03*
Y1677519D03*
X585630Y1681456D03*
X577756Y1682244D03*
X585630Y1686180D03*
Y1676732D03*
X577756Y1677519D03*
X585630Y1681456D03*
X577756Y1682244D03*
X585630Y1686180D03*
X577756Y1686968D03*
Y1691692D03*
X585630Y1695629D03*
X577756Y1696417D03*
X585630Y1700354D03*
Y1690905D03*
X577756Y1691692D03*
X585630Y1695629D03*
X577756Y1696417D03*
X585630Y1700354D03*
X577756Y1701141D03*
Y1705866D03*
X585630Y1709803D03*
X577756Y1710590D03*
X585630Y1714527D03*
Y1705078D03*
X577756Y1705866D03*
X585630Y1709803D03*
X577756Y1710590D03*
X585630Y1714527D03*
X577756Y1715314D03*
Y1720039D03*
X585630Y1723976D03*
X577756Y1724763D03*
X585630Y1728700D03*
Y1719251D03*
X577756Y1720039D03*
X585630Y1723976D03*
X577756Y1724763D03*
X585630Y1728700D03*
X577756Y1729488D03*
X585630Y1733425D03*
X577756Y1734212D03*
X601378Y1672007D03*
X593504Y1672795D03*
Y1677519D03*
X601378Y1681456D03*
X593504Y1682244D03*
X601378Y1686180D03*
Y1676732D03*
X593504Y1677519D03*
X601378Y1681456D03*
X593504Y1682244D03*
X601378Y1686180D03*
X593504Y1686968D03*
Y1691692D03*
X601378Y1695629D03*
X593504Y1696417D03*
X601378Y1700354D03*
Y1690905D03*
X593504Y1691692D03*
X601378Y1695629D03*
X593504Y1696417D03*
X601378Y1700354D03*
X593504Y1701141D03*
Y1705866D03*
X601378Y1709803D03*
X593504Y1710590D03*
X601378Y1714527D03*
Y1705078D03*
X593504Y1705866D03*
X601378Y1709803D03*
X593504Y1710590D03*
X601378Y1714527D03*
X593504Y1715314D03*
Y1720039D03*
X601378Y1723976D03*
X593504Y1724763D03*
X601378Y1728700D03*
Y1719251D03*
X593504Y1720039D03*
X601378Y1723976D03*
X593504Y1724763D03*
X601378Y1728700D03*
X593504Y1729488D03*
X601378Y1733425D03*
X593504Y1734212D03*
X617126Y1672007D03*
X609252Y1672795D03*
X617126Y1681456D03*
Y1686180D03*
X609252Y1677519D03*
Y1682244D03*
X617126Y1676732D03*
X609252Y1677519D03*
X617126Y1681456D03*
X609252Y1682244D03*
X617126Y1686180D03*
X609252Y1686968D03*
Y1691692D03*
X617126Y1695629D03*
X609252Y1696417D03*
X617126Y1700354D03*
Y1690905D03*
X609252Y1691692D03*
X617126Y1695629D03*
X609252Y1696417D03*
X617126Y1700354D03*
X609252Y1701141D03*
X617126Y1709803D03*
Y1714527D03*
X609252Y1705866D03*
Y1710590D03*
X617126Y1705078D03*
X609252Y1705866D03*
X617126Y1709803D03*
X609252Y1710590D03*
X617126Y1714527D03*
X609252Y1715314D03*
Y1720039D03*
X617126Y1723976D03*
X609252Y1724763D03*
X617126Y1728700D03*
Y1719251D03*
X609252Y1720039D03*
X617126Y1723976D03*
X609252Y1724763D03*
X617126Y1728700D03*
X609252Y1729488D03*
X617126Y1733425D03*
X609252Y1734212D03*
X828780Y1684890D03*
X818780D03*
X828780Y1694890D03*
X818780D03*
X828780Y1704890D03*
X818780D03*
X828780Y1714890D03*
X818780D03*
X853780Y1684890D03*
Y1694890D03*
Y1704890D03*
Y1714890D03*
X863780Y1684890D03*
Y1694890D03*
Y1704890D03*
Y1714890D03*
X888780Y1684890D03*
Y1694890D03*
Y1704890D03*
Y1714890D03*
X898780Y1684890D03*
Y1694890D03*
Y1704890D03*
Y1714890D03*
X918780Y1684890D03*
Y1694890D03*
Y1704890D03*
Y1714890D03*
X928780Y1684890D03*
Y1694890D03*
Y1704890D03*
Y1714890D03*
X938780Y1684890D03*
Y1694890D03*
Y1704890D03*
Y1714890D03*
X958780Y1684890D03*
Y1694890D03*
Y1704890D03*
Y1714890D03*
X968780Y1684890D03*
Y1694890D03*
Y1704890D03*
Y1714890D03*
X993780Y1684890D03*
Y1694890D03*
Y1704890D03*
Y1714890D03*
X1003780Y1684890D03*
Y1694890D03*
Y1704890D03*
Y1714890D03*
X1028780Y1684890D03*
X1038780D03*
X1028780Y1694890D03*
X1038780D03*
X1028780Y1704890D03*
Y1714890D03*
X1038780Y1704890D03*
Y1714890D03*
X1238778Y1672795D03*
X1246652Y1681456D03*
Y1686180D03*
X1238778Y1677519D03*
Y1682244D03*
Y1677519D03*
Y1682244D03*
Y1686968D03*
Y1691692D03*
Y1696417D03*
X1246652Y1695629D03*
Y1700354D03*
X1238778Y1691692D03*
Y1696417D03*
Y1701141D03*
X1246652Y1709803D03*
Y1714527D03*
X1238778Y1705866D03*
Y1710590D03*
Y1705866D03*
Y1710590D03*
Y1715314D03*
Y1720039D03*
Y1724763D03*
X1246652Y1723976D03*
Y1728700D03*
X1238778Y1720039D03*
Y1724763D03*
Y1729488D03*
Y1734212D03*
X1254526Y1672795D03*
X1246652Y1672007D03*
X1262400Y1681456D03*
Y1686180D03*
X1254526Y1677519D03*
Y1682244D03*
Y1677519D03*
X1246652Y1676732D03*
X1254526Y1682244D03*
X1246652Y1681456D03*
X1254526Y1686968D03*
X1246652Y1686180D03*
X1254526Y1691692D03*
Y1696417D03*
X1262400Y1695629D03*
Y1700354D03*
X1254526Y1691692D03*
X1246652Y1690905D03*
X1254526Y1696417D03*
X1246652Y1695629D03*
X1254526Y1701141D03*
X1246652Y1700354D03*
X1262400Y1709803D03*
Y1714527D03*
X1254526Y1705866D03*
Y1710590D03*
Y1705866D03*
X1246652Y1705078D03*
X1254526Y1710590D03*
X1246652Y1709803D03*
X1254526Y1715314D03*
X1246652Y1714527D03*
X1254526Y1720039D03*
Y1724763D03*
X1262400Y1723976D03*
Y1728700D03*
X1254526Y1720039D03*
X1246652Y1719251D03*
X1254526Y1724763D03*
X1246652Y1723976D03*
X1254526Y1729488D03*
X1246652Y1728700D03*
X1254526Y1734212D03*
X1246652Y1733425D03*
X1262400Y1672007D03*
X1270274Y1672795D03*
Y1677519D03*
Y1682244D03*
X1262400Y1676732D03*
Y1681456D03*
Y1686180D03*
X1270274Y1677519D03*
Y1682244D03*
Y1686968D03*
Y1691692D03*
Y1696417D03*
X1262400Y1690905D03*
Y1695629D03*
Y1700354D03*
X1270274Y1691692D03*
Y1696417D03*
Y1701141D03*
Y1705866D03*
Y1710590D03*
X1262400Y1705078D03*
Y1709803D03*
Y1714527D03*
X1270274Y1705866D03*
Y1710590D03*
Y1715314D03*
Y1720039D03*
Y1724763D03*
X1262400Y1719251D03*
Y1723976D03*
Y1728700D03*
X1270274Y1720039D03*
Y1724763D03*
Y1729488D03*
X1262400Y1733425D03*
X1270274Y1734212D03*
X1286022Y1672795D03*
X1278148Y1672007D03*
X1286022Y1677519D03*
Y1682244D03*
X1278148Y1681456D03*
Y1686180D03*
X1286022Y1677519D03*
X1278148Y1676732D03*
X1286022Y1682244D03*
X1278148Y1681456D03*
X1286022Y1686968D03*
X1278148Y1686180D03*
X1286022Y1691692D03*
Y1696417D03*
X1278148Y1695629D03*
Y1700354D03*
X1286022Y1691692D03*
X1278148Y1690905D03*
X1286022Y1696417D03*
X1278148Y1695629D03*
X1286022Y1701141D03*
X1278148Y1700354D03*
X1286022Y1705866D03*
Y1710590D03*
X1278148Y1709803D03*
Y1714527D03*
X1286022Y1705866D03*
X1278148Y1705078D03*
X1286022Y1710590D03*
X1278148Y1709803D03*
X1286022Y1715314D03*
X1278148Y1714527D03*
X1286022Y1720039D03*
Y1724763D03*
X1278148Y1723976D03*
Y1728700D03*
X1286022Y1720039D03*
X1278148Y1719251D03*
X1286022Y1724763D03*
X1278148Y1723976D03*
X1286022Y1729488D03*
X1278148Y1728700D03*
X1286022Y1734212D03*
X1278148Y1733425D03*
X1305708Y1672795D03*
X1293896Y1672007D03*
X1305708Y1677519D03*
Y1682244D03*
X1293896Y1681456D03*
Y1686180D03*
X1305708Y1686968D03*
X1293896Y1676732D03*
Y1681456D03*
Y1686180D03*
Y1695629D03*
Y1700354D03*
X1305708Y1691692D03*
Y1696417D03*
Y1701141D03*
X1293896Y1690905D03*
Y1695629D03*
Y1700354D03*
X1305708Y1705866D03*
Y1710590D03*
X1293896Y1709803D03*
Y1714527D03*
X1305708Y1715314D03*
X1293896Y1705078D03*
Y1709803D03*
Y1714527D03*
Y1723976D03*
Y1728700D03*
X1305708Y1720039D03*
Y1724763D03*
Y1729488D03*
X1293896Y1719251D03*
Y1723976D03*
Y1728700D03*
Y1733425D03*
X1313582Y1672007D03*
X1321456Y1677519D03*
Y1682244D03*
X1313582Y1681456D03*
Y1686180D03*
Y1676732D03*
X1305708Y1677519D03*
X1313582Y1681456D03*
X1305708Y1682244D03*
X1313582Y1686180D03*
Y1695629D03*
Y1700354D03*
X1321456Y1691692D03*
Y1696417D03*
X1313582Y1690905D03*
X1305708Y1691692D03*
X1313582Y1695629D03*
X1305708Y1696417D03*
X1313582Y1700354D03*
X1321456Y1705866D03*
Y1710590D03*
X1313582Y1709803D03*
Y1714527D03*
Y1705078D03*
X1305708Y1705866D03*
X1313582Y1709803D03*
X1305708Y1710590D03*
X1313582Y1714527D03*
Y1723976D03*
Y1728700D03*
X1321456Y1720039D03*
Y1724763D03*
X1313582Y1719251D03*
X1305708Y1720039D03*
X1313582Y1723976D03*
X1305708Y1724763D03*
X1313582Y1728700D03*
Y1733425D03*
X1305708Y1734212D03*
X1329330Y1672007D03*
X1321456Y1672795D03*
X1329330Y1681456D03*
Y1686180D03*
Y1676732D03*
X1321456Y1677519D03*
X1329330Y1681456D03*
X1321456Y1682244D03*
X1329330Y1686180D03*
X1321456Y1686968D03*
X1329330Y1695629D03*
Y1700354D03*
Y1690905D03*
X1321456Y1691692D03*
X1329330Y1695629D03*
X1321456Y1696417D03*
X1329330Y1700354D03*
X1321456Y1701141D03*
X1329330Y1709803D03*
Y1714527D03*
Y1705078D03*
X1321456Y1705866D03*
X1329330Y1709803D03*
X1321456Y1710590D03*
X1329330Y1714527D03*
X1321456Y1715314D03*
X1329330Y1723976D03*
Y1728700D03*
Y1719251D03*
X1321456Y1720039D03*
X1329330Y1723976D03*
X1321456Y1724763D03*
X1329330Y1728700D03*
X1321456Y1729488D03*
X1329330Y1733425D03*
X1321456Y1734212D03*
X1345078Y1672007D03*
X1337204Y1672795D03*
Y1677519D03*
X1345078Y1681456D03*
X1337204Y1682244D03*
X1345078Y1686180D03*
Y1676732D03*
X1337204Y1677519D03*
X1345078Y1681456D03*
X1337204Y1682244D03*
X1345078Y1686180D03*
X1337204Y1686968D03*
Y1691692D03*
X1345078Y1695629D03*
X1337204Y1696417D03*
X1345078Y1700354D03*
Y1690905D03*
X1337204Y1691692D03*
X1345078Y1695629D03*
X1337204Y1696417D03*
X1345078Y1700354D03*
X1337204Y1701141D03*
Y1705866D03*
X1345078Y1709803D03*
X1337204Y1710590D03*
X1345078Y1714527D03*
Y1705078D03*
X1337204Y1705866D03*
X1345078Y1709803D03*
X1337204Y1710590D03*
X1345078Y1714527D03*
X1337204Y1715314D03*
Y1720039D03*
X1345078Y1723976D03*
X1337204Y1724763D03*
X1345078Y1728700D03*
Y1719251D03*
X1337204Y1720039D03*
X1345078Y1723976D03*
X1337204Y1724763D03*
X1345078Y1728700D03*
X1337204Y1729488D03*
X1345078Y1733425D03*
X1337204Y1734212D03*
X1360826Y1672007D03*
X1352952Y1672795D03*
Y1677519D03*
X1360826Y1681456D03*
X1352952Y1682244D03*
X1360826Y1686180D03*
Y1676732D03*
X1352952Y1677519D03*
X1360826Y1681456D03*
X1352952Y1682244D03*
X1360826Y1686180D03*
X1352952Y1686968D03*
Y1691692D03*
X1360826Y1695629D03*
X1352952Y1696417D03*
X1360826Y1700354D03*
Y1690905D03*
X1352952Y1691692D03*
X1360826Y1695629D03*
X1352952Y1696417D03*
X1360826Y1700354D03*
X1352952Y1701141D03*
Y1705866D03*
X1360826Y1709803D03*
X1352952Y1710590D03*
X1360826Y1714527D03*
Y1705078D03*
X1352952Y1705866D03*
X1360826Y1709803D03*
X1352952Y1710590D03*
X1360826Y1714527D03*
X1352952Y1715314D03*
Y1720039D03*
X1360826Y1723976D03*
X1352952Y1724763D03*
X1360826Y1728700D03*
Y1719251D03*
X1352952Y1720039D03*
X1360826Y1723976D03*
X1352952Y1724763D03*
X1360826Y1728700D03*
X1352952Y1729488D03*
X1360826Y1733425D03*
X1352952Y1734212D03*
X1510826Y1672007D03*
X1502952Y1672795D03*
Y1677519D03*
X1510826Y1681456D03*
X1502952Y1682244D03*
X1510826Y1686180D03*
Y1676732D03*
X1502952Y1677519D03*
X1510826Y1681456D03*
X1502952Y1682244D03*
X1510826Y1686180D03*
X1502952Y1686968D03*
Y1691692D03*
X1510826Y1695629D03*
X1502952Y1696417D03*
X1510826Y1700354D03*
Y1690905D03*
X1502952Y1691692D03*
X1510826Y1695629D03*
X1502952Y1696417D03*
X1510826Y1700354D03*
X1502952Y1701141D03*
Y1705866D03*
X1510826Y1709803D03*
X1502952Y1710590D03*
X1510826Y1714527D03*
Y1705078D03*
X1502952Y1705866D03*
X1510826Y1709803D03*
X1502952Y1710590D03*
X1510826Y1714527D03*
X1502952Y1715314D03*
Y1720039D03*
X1510826Y1723976D03*
X1502952Y1724763D03*
X1510826Y1728700D03*
Y1719251D03*
X1502952Y1720039D03*
X1510826Y1723976D03*
X1502952Y1724763D03*
X1510826Y1728700D03*
X1502952Y1729488D03*
X1510826Y1733425D03*
X1502952Y1734212D03*
X1526574Y1672007D03*
X1518700Y1672795D03*
X1526574Y1681456D03*
Y1686180D03*
X1518700Y1677519D03*
Y1682244D03*
X1526574Y1676732D03*
X1518700Y1677519D03*
X1526574Y1681456D03*
X1518700Y1682244D03*
X1526574Y1686180D03*
X1518700Y1686968D03*
Y1691692D03*
X1526574Y1695629D03*
X1518700Y1696417D03*
X1526574Y1700354D03*
Y1690905D03*
X1518700Y1691692D03*
X1526574Y1695629D03*
X1518700Y1696417D03*
X1526574Y1700354D03*
X1518700Y1701141D03*
X1526574Y1709803D03*
Y1714527D03*
X1518700Y1705866D03*
Y1710590D03*
X1526574Y1705078D03*
X1518700Y1705866D03*
X1526574Y1709803D03*
X1518700Y1710590D03*
X1526574Y1714527D03*
X1518700Y1715314D03*
Y1720039D03*
X1526574Y1723976D03*
X1518700Y1724763D03*
X1526574Y1728700D03*
Y1719251D03*
X1518700Y1720039D03*
X1526574Y1723976D03*
X1518700Y1724763D03*
X1526574Y1728700D03*
X1518700Y1729488D03*
X1526574Y1733425D03*
X1518700Y1734212D03*
X1542322Y1672007D03*
X1534448Y1672795D03*
X1542322Y1681456D03*
Y1686180D03*
X1534448Y1677519D03*
Y1682244D03*
X1542322Y1676732D03*
X1534448Y1677519D03*
X1542322Y1681456D03*
X1534448Y1682244D03*
X1542322Y1686180D03*
X1534448Y1686968D03*
Y1691692D03*
X1542322Y1695629D03*
X1534448Y1696417D03*
X1542322Y1700354D03*
Y1690905D03*
X1534448Y1691692D03*
X1542322Y1695629D03*
X1534448Y1696417D03*
X1542322Y1700354D03*
X1534448Y1701141D03*
X1542322Y1709803D03*
Y1714527D03*
X1534448Y1705866D03*
Y1710590D03*
X1542322Y1705078D03*
X1534448Y1705866D03*
X1542322Y1709803D03*
X1534448Y1710590D03*
X1542322Y1714527D03*
X1534448Y1715314D03*
Y1720039D03*
X1542322Y1723976D03*
X1534448Y1724763D03*
X1542322Y1728700D03*
Y1719251D03*
X1534448Y1720039D03*
X1542322Y1723976D03*
X1534448Y1724763D03*
X1542322Y1728700D03*
X1534448Y1729488D03*
X1542322Y1733425D03*
X1534448Y1734212D03*
X1558070Y1672007D03*
X1550196Y1672795D03*
X1558070Y1681456D03*
Y1686180D03*
X1550196Y1677519D03*
Y1682244D03*
X1558070Y1676732D03*
X1550196Y1677519D03*
X1558070Y1681456D03*
X1550196Y1682244D03*
X1558070Y1686180D03*
X1550196Y1686968D03*
Y1691692D03*
X1558070Y1695629D03*
X1550196Y1696417D03*
X1558070Y1700354D03*
Y1690905D03*
X1550196Y1691692D03*
X1558070Y1695629D03*
X1550196Y1696417D03*
X1558070Y1700354D03*
X1550196Y1701141D03*
X1558070Y1709803D03*
Y1714527D03*
X1550196Y1705866D03*
Y1710590D03*
X1558070Y1705078D03*
X1550196Y1705866D03*
X1558070Y1709803D03*
X1550196Y1710590D03*
X1558070Y1714527D03*
X1550196Y1715314D03*
Y1720039D03*
X1558070Y1723976D03*
X1550196Y1724763D03*
X1558070Y1728700D03*
Y1719251D03*
X1550196Y1720039D03*
X1558070Y1723976D03*
X1550196Y1724763D03*
X1558070Y1728700D03*
X1550196Y1729488D03*
X1558070Y1733425D03*
X1550196Y1734212D03*
X1569882Y1672795D03*
Y1677519D03*
Y1682244D03*
Y1677519D03*
Y1682244D03*
Y1686968D03*
Y1691692D03*
Y1696417D03*
Y1691692D03*
Y1696417D03*
Y1701141D03*
Y1705866D03*
Y1710590D03*
Y1705866D03*
Y1710590D03*
Y1715314D03*
Y1720039D03*
Y1724763D03*
Y1720039D03*
Y1724763D03*
Y1729488D03*
Y1734212D03*
X1585630Y1672795D03*
X1577756Y1672007D03*
X1585630Y1677519D03*
Y1682244D03*
X1577756Y1681456D03*
Y1686180D03*
X1585630Y1677519D03*
X1577756Y1676732D03*
X1585630Y1682244D03*
X1577756Y1681456D03*
X1585630Y1686968D03*
X1577756Y1686180D03*
X1585630Y1691692D03*
Y1696417D03*
X1577756Y1695629D03*
Y1700354D03*
X1585630Y1691692D03*
X1577756Y1690905D03*
X1585630Y1696417D03*
X1577756Y1695629D03*
X1585630Y1701141D03*
X1577756Y1700354D03*
X1585630Y1705866D03*
Y1710590D03*
X1577756Y1709803D03*
Y1714527D03*
X1585630Y1705866D03*
X1577756Y1705078D03*
X1585630Y1710590D03*
X1577756Y1709803D03*
X1585630Y1715314D03*
X1577756Y1714527D03*
X1585630Y1720039D03*
Y1724763D03*
X1577756Y1723976D03*
Y1728700D03*
X1585630Y1720039D03*
X1577756Y1719251D03*
X1585630Y1724763D03*
X1577756Y1723976D03*
X1585630Y1729488D03*
X1577756Y1728700D03*
X1585630Y1734212D03*
X1577756Y1733425D03*
X1593504Y1672007D03*
X1601378Y1672795D03*
Y1677519D03*
Y1682244D03*
X1593504Y1681456D03*
Y1686180D03*
Y1676732D03*
Y1681456D03*
Y1686180D03*
X1601378Y1677519D03*
Y1682244D03*
Y1686968D03*
X1593504Y1695629D03*
Y1700354D03*
X1601378Y1691692D03*
Y1696417D03*
X1593504Y1690905D03*
Y1695629D03*
Y1700354D03*
X1601378Y1691692D03*
Y1696417D03*
Y1701141D03*
Y1705866D03*
Y1710590D03*
X1593504Y1709803D03*
Y1714527D03*
Y1705078D03*
Y1709803D03*
Y1714527D03*
X1601378Y1705866D03*
Y1710590D03*
Y1715314D03*
X1593504Y1723976D03*
Y1728700D03*
X1601378Y1720039D03*
Y1724763D03*
X1593504Y1719251D03*
Y1723976D03*
Y1728700D03*
X1601378Y1720039D03*
Y1724763D03*
Y1729488D03*
X1593504Y1733425D03*
X1601378Y1734212D03*
X1617126Y1672795D03*
X1609252Y1672007D03*
X1617126Y1677519D03*
Y1682244D03*
X1609252Y1681456D03*
Y1686180D03*
X1617126Y1677519D03*
X1609252Y1676732D03*
X1617126Y1682244D03*
X1609252Y1681456D03*
X1617126Y1686968D03*
X1609252Y1686180D03*
X1617126Y1691692D03*
Y1696417D03*
X1609252Y1695629D03*
Y1700354D03*
X1617126Y1691692D03*
X1609252Y1690905D03*
X1617126Y1696417D03*
X1609252Y1695629D03*
X1617126Y1701141D03*
X1609252Y1700354D03*
X1617126Y1705866D03*
Y1710590D03*
X1609252Y1709803D03*
Y1714527D03*
X1617126Y1705866D03*
X1609252Y1705078D03*
X1617126Y1710590D03*
X1609252Y1709803D03*
X1617126Y1715314D03*
X1609252Y1714527D03*
X1617126Y1720039D03*
Y1724763D03*
X1609252Y1723976D03*
Y1728700D03*
X1617126Y1720039D03*
X1609252Y1719251D03*
X1617126Y1724763D03*
X1609252Y1723976D03*
X1617126Y1729488D03*
X1609252Y1728700D03*
X1617126Y1734212D03*
X1609252Y1733425D03*
X1625000Y1672007D03*
Y1681456D03*
Y1686180D03*
Y1676732D03*
Y1681456D03*
Y1686180D03*
Y1695629D03*
Y1700354D03*
Y1690905D03*
Y1695629D03*
Y1700354D03*
Y1709803D03*
Y1714527D03*
Y1705078D03*
Y1709803D03*
Y1714527D03*
Y1723976D03*
Y1728700D03*
Y1719251D03*
Y1723976D03*
Y1728700D03*
Y1733425D03*
X2392820Y922806D03*
Y1218306D03*
Y1277406D03*
X4304707Y-112085D03*
X5121120Y920856D03*
X5120120Y1234856D03*
Y1550356D03*
G54D24*
X250326Y185236D03*
X368437D03*
X2392820Y-554694D03*
G54D15*
X44000Y154200D03*
X31818Y1424257D03*
X441043Y1672205D03*
Y1698268D03*
Y1718465D03*
X1416437Y1698268D03*
Y1672205D03*
Y1718465D03*
X1800449Y126194D03*
X1804650Y1667292D03*
X2392820Y-200094D03*
Y-140994D03*
G54D42*
X1766929Y1714960D03*
X2392820Y-81894D03*
G54D33*
X791280Y1704890D03*
X1066280D03*
X2392820Y-22794D03*
G54D43*
X1859986Y1403418D03*
X1859706Y1709011D03*
X1866790Y463389D03*
X1871790Y476573D03*
X1861790D03*
X1870648Y783729D03*
X1860648D03*
X1865648Y796913D03*
X1867295Y837583D03*
X1862295Y850767D03*
X1872295D03*
X1871790Y1158071D03*
X1861790D03*
X1866790Y1171255D03*
X1864986Y1390234D03*
X1869986Y1403418D03*
X1869706Y1709011D03*
X1864706Y1722195D03*
X1886862Y94107D03*
X1881862Y107291D03*
X1882340Y410829D03*
X1887340Y424013D03*
X1887711Y463680D03*
X1882711Y476864D03*
X1882240Y783474D03*
X1887240Y796658D03*
X1888273Y837632D03*
X1883273Y850816D03*
X1882579Y1158348D03*
X1887579Y1171532D03*
X1886223Y1391283D03*
X1881223Y1404467D03*
X1881177Y1709323D03*
X1886177Y1722507D03*
X1891862Y107291D03*
X1892340Y410829D03*
X1892711Y476864D03*
X1892240Y783474D03*
X1893273Y850816D03*
X1892579Y1158348D03*
X1891223Y1404467D03*
X1891177Y1709323D03*
X2077012Y95128D03*
X2082012Y108312D03*
X2072012D03*
X2071128Y410829D03*
X2081128D03*
X2076128Y424013D03*
X2392820Y686406D03*
G54D16*
X57646Y12480D03*
X137272D03*
X186622D03*
X266858D03*
X315598D03*
X502528Y33267D03*
X582154D03*
X631504D03*
X711740D03*
X760480D03*
X1156378Y133866D03*
X1183858Y207205D03*
X1173858D03*
X1183858Y217205D03*
X1173858D03*
X1193858Y207205D03*
Y217205D03*
X1351260Y164213D03*
Y174213D03*
X1361260Y164213D03*
Y174213D03*
X1371260Y164213D03*
X1381260D03*
X1371260Y174213D03*
X1381260D03*
X1391260Y164213D03*
Y174213D03*
X1532055Y12480D03*
X1611681D03*
X1661031D03*
X1741267D03*
X1790007D03*
X2392820Y804606D03*
G54D25*
X277098Y185236D03*
X395208D03*
X2392820Y509106D03*
G54D34*
X793879Y194881D03*
X789942Y204724D03*
X793879Y214567D03*
X805690Y188976D03*
Y220472D03*
X817501Y194881D03*
X821438Y204724D03*
X817501Y214567D03*
X828390Y1420331D03*
X841240Y1407481D03*
X832154Y1411245D03*
Y1429417D03*
X841240Y1433181D03*
X850326Y1411245D03*
Y1429417D03*
X854090Y1420331D03*
X916546Y309460D03*
X911495Y321654D03*
X916546Y333848D03*
X928740Y304409D03*
Y338899D03*
X940934Y309460D03*
X945985Y321654D03*
X940934Y333848D03*
X1007154Y1411245D03*
X1003390Y1420331D03*
X1007154Y1429417D03*
X1016240Y1407481D03*
Y1433181D03*
X1025326Y1411245D03*
Y1429417D03*
X1029090Y1420331D03*
X1045848Y194881D03*
X1041911Y204724D03*
X1045848Y214567D03*
X1057659Y188976D03*
Y220472D03*
X1069470Y194881D03*
X1073407Y204724D03*
X1069470Y214567D03*
X2392820Y1159206D03*
G54D17*
X60303Y20354D03*
X312921Y24291D03*
X505185Y41141D03*
X757803Y45078D03*
X929331Y160413D03*
X922441Y237697D03*
X1534712Y20354D03*
X1787330Y24291D03*
X2392820Y213606D03*
G54D26*
X274913Y1019214D03*
X320189Y838505D03*
Y1199923D03*
X561133Y838505D03*
Y1199923D03*
X606409Y1019214D03*
X841240Y1420331D03*
X1016240D03*
X1251055Y1019213D03*
X1296331Y838504D03*
Y1199922D03*
X1537275Y838504D03*
Y1199922D03*
X1582551Y1019213D03*
X2392820Y-259194D03*
G54D44*
X1900275Y-39973D03*
Y-29973D03*
Y562227D03*
Y572227D03*
X1898799Y1208198D03*
Y1198198D03*
Y1800398D03*
Y1810398D03*
X1910275Y-39973D03*
Y-29973D03*
Y562227D03*
Y572227D03*
X1908799Y1208198D03*
Y1198198D03*
Y1800398D03*
Y1810398D03*
X1921395Y-39963D03*
X1931395D03*
X1921395Y-29963D03*
X1931395D03*
Y562237D03*
X1921395D03*
X1931395Y582237D03*
Y572237D03*
X1921395D03*
Y582237D03*
X1931395Y572237D03*
X1921395D03*
Y1174437D03*
X1931395D03*
X1921395Y1184437D03*
X1931395D03*
X1929766Y1198160D03*
X1919766D03*
X1929766Y1208160D03*
X1919766D03*
Y1800360D03*
X1929766D03*
X1919766Y1810360D03*
X1929766D03*
X1942395Y-39783D03*
Y-29783D03*
Y562417D03*
Y582417D03*
Y572417D03*
D03*
Y1174617D03*
X1940886Y1198170D03*
X1942395Y1184617D03*
X1940886Y1208170D03*
Y1800370D03*
Y1810370D03*
X1952395Y-39783D03*
X1963362Y-39821D03*
X1952395Y-29783D03*
Y562417D03*
X1963362Y572379D03*
X1952395Y572417D03*
Y582417D03*
Y572417D03*
X1963362Y572379D03*
X1952395Y1174617D03*
X1950886Y1198170D03*
X1952395Y1184617D03*
X1963362Y1184579D03*
X1961856Y1198170D03*
X1950886Y1208170D03*
X1961856D03*
X1950886Y1800370D03*
X1961856D03*
X1950886Y1810370D03*
X1961856D03*
X1973362Y-39821D03*
X1963362Y-29821D03*
X1973362D03*
Y562379D03*
X1963362D03*
X1973362Y582379D03*
Y572379D03*
X1963362Y582379D03*
X1973362Y572379D03*
X1963362Y1174579D03*
X1973362D03*
Y1184579D03*
X1971856Y1198170D03*
Y1208170D03*
Y1800370D03*
Y1810370D03*
X1984482Y-39811D03*
Y-29811D03*
Y562389D03*
Y582389D03*
Y572389D03*
D03*
Y1174589D03*
Y1184589D03*
X1982856Y1208350D03*
Y1198350D03*
X1992856D03*
X1982856Y1800550D03*
X1992856Y1810550D03*
X1982856D03*
X1994482Y-39811D03*
X2005452D03*
X1994482Y-29811D03*
X2005452D03*
X1994482Y562389D03*
X2005452D03*
Y572389D03*
Y582389D03*
X1994482Y572389D03*
Y582389D03*
Y572389D03*
X2005452D03*
X1994482Y1174589D03*
X2005452D03*
X1994482Y1184589D03*
X2005452D03*
X1992856Y1208350D03*
X2003823Y1208312D03*
Y1198312D03*
X1992856Y1800550D03*
X2003823Y1800512D03*
Y1810512D03*
X2015452Y-39811D03*
Y-29811D03*
Y562389D03*
Y582389D03*
Y572389D03*
D03*
Y1174589D03*
Y1184589D03*
X2013823Y1208312D03*
Y1198312D03*
Y1800512D03*
Y1810512D03*
X2036452Y-39631D03*
X2026452D03*
X2036452Y-29631D03*
X2026452D03*
Y562569D03*
X2036452D03*
X2026452Y582569D03*
Y572569D03*
X2036452D03*
Y582569D03*
X2026452Y572569D03*
X2036452D03*
Y1174769D03*
X2026452D03*
X2036452Y1184769D03*
X2026452D03*
X2047419Y-39669D03*
Y-29669D03*
Y562531D03*
Y572531D03*
Y582531D03*
Y572531D03*
Y1174731D03*
Y1184731D03*
X2057419Y-39669D03*
Y-29669D03*
Y562531D03*
Y582531D03*
Y572531D03*
D03*
Y1174731D03*
Y1184731D03*
X2068539Y582541D03*
Y572541D03*
X2078539D03*
Y582541D03*
Y1174741D03*
X2068539D03*
X2078539Y1184741D03*
X2068539D03*
X2392820Y1454706D03*
G54D35*
X805690Y204724D03*
X1057659D03*
X2392820Y-318294D03*
G54D45*
G01X-476840Y-884638D02*
Y2768362D01*
X5911000D01*
Y-884638D01*
X-476840D01*
G01X-286740Y270986D02*
X-291390D01*
Y283486D01*
X-286740D01*
G01X-296170Y532290D02*
X-300820D01*
Y544790D01*
X-296170D01*
G01Y599161D02*
X-300820D01*
Y611661D01*
X-296170D01*
G01X-295850Y644880D02*
X-300500D01*
Y657380D01*
X-295850D01*
G01X-297140Y676092D02*
X-301790D01*
Y688592D01*
X-297140D01*
G01X-283180Y164420D02*
X-287830D01*
Y176920D01*
X-283180D01*
G01X-283500Y191600D02*
X-288150D01*
Y204100D01*
X-283500D01*
G01X-284150Y209720D02*
X-288800D01*
Y222220D01*
X-284150D01*
G01X-284800Y576053D02*
X-289450D01*
Y588553D01*
X-284800D01*
G01X-264740Y1692018D02*
X-269390D01*
Y1704518D01*
X-264740D01*
G01X-248730Y232370D02*
X-253380D01*
Y244870D01*
X-248730D01*
G01X-217730Y232370D02*
X-213080D01*
Y244870D01*
X-217730D01*
G01X-218540Y270986D02*
X-213890D01*
Y283486D01*
X-218540D01*
G01X934685Y155197D02*
X-201690D01*
X-202020Y170670D01*
G01X-214980Y164420D02*
X-210330D01*
Y176920D01*
X-214980D01*
G01X-215300Y191600D02*
X-210650D01*
Y204100D01*
X-215300D01*
G01X-215950Y209720D02*
X-211300D01*
Y222220D01*
X-215950D01*
G01X890197Y175177D02*
X-153810D01*
X-153490Y215320D01*
X-201925Y215535D01*
G01X1047659Y204724D02*
X-139570D01*
Y238940D01*
X-203705Y238797D01*
G01X1690012Y277236D02*
X-204515D01*
G01X-215570Y532290D02*
X-210920D01*
Y544790D01*
X-215570D01*
G01X513173Y578174D02*
X-201050D01*
X-202340Y538540D01*
G01X1360284Y582303D02*
X-202575D01*
G01X-216600Y576053D02*
X-211950D01*
Y588553D01*
X-216600D01*
G01X-215570Y599161D02*
X-210920D01*
Y611661D01*
X-215570D01*
G01X-215250Y644880D02*
X-210600D01*
Y657380D01*
X-215250D01*
G01X1523552Y682342D02*
X-202515D01*
G01X-216540Y676092D02*
X-211890D01*
Y688592D01*
X-216540D01*
G01X1751575Y159134D02*
X-172250D01*
X-171930Y198170D01*
X-201275Y198096D01*
G01X1729745Y605411D02*
X-201545D01*
G01X1654890Y642972D02*
X-201690D01*
X-201050Y651460D01*
X-201225Y651459D01*
G01X-184140Y1692018D02*
X-179490D01*
Y1704518D01*
X-184140D01*
G01X1406437Y1698268D02*
X-170115D01*
G01X-106170Y-18750D02*
X-110820D01*
Y-6250D01*
X-106170D01*
G01X-87570Y-18750D02*
X-82920D01*
Y-6250D01*
X-87570D01*
G01X-10000Y0D02*
X-73545D01*
G01X8000Y-625138D02*
Y-630138D01*
G01X6543Y-625138D02*
X9457D01*
G01X14367Y-630138D02*
X11833D01*
Y-625138D01*
X14367D01*
G01X13353Y-627555D02*
X11833D01*
G01X16933Y-625138D02*
Y-630138D01*
X19467D01*
G01X23300Y-630305D02*
X23173Y-630221D01*
Y-630055D01*
X23300Y-629971D01*
X23427Y-630055D01*
Y-630221D01*
X23300Y-630305D01*
G01Y-628055D02*
X23173Y-627971D01*
Y-627805D01*
X23300Y-627721D01*
X23427Y-627805D01*
Y-627971D01*
X23300Y-628055D01*
G01X28083Y-631805D02*
X27450Y-630971D01*
X27133Y-630138D01*
Y-626805D01*
X27450Y-625971D01*
X28083Y-625138D01*
G01X33500D02*
X32993Y-625305D01*
X32613Y-625721D01*
X32360Y-626221D01*
X32170Y-626888D01*
X32107Y-627638D01*
X32170Y-628388D01*
X32360Y-629055D01*
X32613Y-629555D01*
X32993Y-629971D01*
X33500Y-630138D01*
X34007Y-629971D01*
X34387Y-629555D01*
X34640Y-629055D01*
X34830Y-628388D01*
X34893Y-627638D01*
X34830Y-626888D01*
X34640Y-626221D01*
X34387Y-625721D01*
X34007Y-625305D01*
X33500Y-625138D01*
G01X37207Y-629138D02*
X37587Y-629721D01*
X38093Y-630055D01*
X38663Y-630138D01*
X39170Y-630055D01*
X39677Y-629638D01*
X39993Y-629138D01*
X40057Y-628638D01*
X39930Y-628055D01*
X39487Y-627638D01*
X39043Y-627471D01*
X38473D01*
G01X39043D02*
X39423Y-627221D01*
X39740Y-626805D01*
X39867Y-626305D01*
X39740Y-625805D01*
X39423Y-625388D01*
X38853Y-625138D01*
X38283Y-625221D01*
X37713Y-625555D01*
G01X44017Y-631805D02*
X44650Y-630971D01*
X44967Y-630138D01*
Y-626805D01*
X44650Y-625971D01*
X44017Y-625138D01*
G01X47407Y-629138D02*
X47787Y-629721D01*
X48293Y-630055D01*
X48863Y-630138D01*
X49370Y-630055D01*
X49877Y-629638D01*
X50193Y-629138D01*
X50257Y-628638D01*
X50130Y-628055D01*
X49687Y-627638D01*
X49243Y-627471D01*
X48673D01*
G01X49243D02*
X49623Y-627221D01*
X49940Y-626805D01*
X50067Y-626305D01*
X49940Y-625805D01*
X49623Y-625388D01*
X49053Y-625138D01*
X48483Y-625221D01*
X47913Y-625555D01*
G01X52697Y-625971D02*
X53077Y-625471D01*
X53520Y-625221D01*
X54027Y-625138D01*
X54660Y-625305D01*
X55103Y-625721D01*
X55230Y-626221D01*
X55167Y-626721D01*
X54913Y-627138D01*
X53647Y-627971D01*
X53077Y-628555D01*
X52697Y-629388D01*
X52570Y-630138D01*
X55230D01*
G01X58873D02*
X59000Y-629055D01*
X59190Y-628138D01*
X59443Y-627305D01*
X59760Y-626388D01*
X60267Y-625138D01*
X57733D01*
G01X63277Y-628471D02*
X64923D01*
G01X67997Y-625971D02*
X68377Y-625471D01*
X68820Y-625221D01*
X69327Y-625138D01*
X69960Y-625305D01*
X70403Y-625721D01*
X70530Y-626221D01*
X70467Y-626721D01*
X70213Y-627138D01*
X68947Y-627971D01*
X68377Y-628555D01*
X67997Y-629388D01*
X67870Y-630138D01*
X70530D01*
G01X72907Y-629138D02*
X73287Y-629721D01*
X73793Y-630055D01*
X74363Y-630138D01*
X74870Y-630055D01*
X75377Y-629638D01*
X75693Y-629138D01*
X75757Y-628638D01*
X75630Y-628055D01*
X75187Y-627638D01*
X74743Y-627471D01*
X74173D01*
G01X74743D02*
X75123Y-627221D01*
X75440Y-626805D01*
X75567Y-626305D01*
X75440Y-625805D01*
X75123Y-625388D01*
X74553Y-625138D01*
X73983Y-625221D01*
X73413Y-625555D01*
G01X80160Y-630138D02*
Y-625138D01*
X77817Y-628721D01*
X80983D01*
G01X83107Y-629388D02*
X83487Y-629805D01*
X83930Y-630055D01*
X84500Y-630138D01*
X85070Y-629971D01*
X85513Y-629638D01*
X85830Y-629055D01*
X85893Y-628388D01*
X85767Y-627721D01*
X85450Y-627305D01*
X85007Y-626971D01*
X84563Y-626888D01*
X84120Y-626971D01*
X83550Y-627305D01*
X83740Y-625138D01*
X85450D01*
G01X93497Y-630138D02*
Y-625138D01*
X95903D01*
G01X95017Y-627555D02*
X93497D01*
G01X98217Y-630138D02*
X99800Y-625138D01*
X101383Y-630138D01*
G01X100813Y-628388D02*
X98787D01*
G01X103570Y-630138D02*
X106230Y-625138D01*
G01X103570D02*
X106230Y-630138D01*
G01X110000Y-630305D02*
X109873Y-630221D01*
Y-630055D01*
X110000Y-629971D01*
X110127Y-630055D01*
Y-630221D01*
X110000Y-630305D01*
G01Y-628055D02*
X109873Y-627971D01*
Y-627805D01*
X110000Y-627721D01*
X110127Y-627805D01*
Y-627971D01*
X110000Y-628055D01*
G01X114783Y-631805D02*
X114150Y-630971D01*
X113833Y-630138D01*
Y-626805D01*
X114150Y-625971D01*
X114783Y-625138D01*
G01X120200D02*
X119693Y-625305D01*
X119313Y-625721D01*
X119060Y-626221D01*
X118870Y-626888D01*
X118807Y-627638D01*
X118870Y-628388D01*
X119060Y-629055D01*
X119313Y-629555D01*
X119693Y-629971D01*
X120200Y-630138D01*
X120707Y-629971D01*
X121087Y-629555D01*
X121340Y-629055D01*
X121530Y-628388D01*
X121593Y-627638D01*
X121530Y-626888D01*
X121340Y-626221D01*
X121087Y-625721D01*
X120707Y-625305D01*
X120200Y-625138D01*
G01X123907Y-629138D02*
X124287Y-629721D01*
X124793Y-630055D01*
X125363Y-630138D01*
X125870Y-630055D01*
X126377Y-629638D01*
X126693Y-629138D01*
X126757Y-628638D01*
X126630Y-628055D01*
X126187Y-627638D01*
X125743Y-627471D01*
X125173D01*
G01X125743D02*
X126123Y-627221D01*
X126440Y-626805D01*
X126567Y-626305D01*
X126440Y-625805D01*
X126123Y-625388D01*
X125553Y-625138D01*
X124983Y-625221D01*
X124413Y-625555D01*
G01X130717Y-631805D02*
X131350Y-630971D01*
X131667Y-630138D01*
Y-626805D01*
X131350Y-625971D01*
X130717Y-625138D01*
G01X134107Y-629138D02*
X134487Y-629721D01*
X134993Y-630055D01*
X135563Y-630138D01*
X136070Y-630055D01*
X136577Y-629638D01*
X136893Y-629138D01*
X136957Y-628638D01*
X136830Y-628055D01*
X136387Y-627638D01*
X135943Y-627471D01*
X135373D01*
G01X135943D02*
X136323Y-627221D01*
X136640Y-626805D01*
X136767Y-626305D01*
X136640Y-625805D01*
X136323Y-625388D01*
X135753Y-625138D01*
X135183Y-625221D01*
X134613Y-625555D01*
G01X139523Y-629555D02*
X139967Y-629971D01*
X140473Y-630138D01*
X140980Y-629971D01*
X141423Y-629471D01*
X141740Y-628721D01*
X141867Y-627971D01*
Y-627055D01*
X141740Y-626305D01*
X141423Y-625638D01*
X141043Y-625305D01*
X140600Y-625138D01*
X140093Y-625305D01*
X139713Y-625638D01*
X139460Y-626138D01*
X139333Y-626805D01*
X139460Y-627388D01*
X139777Y-627971D01*
X140157Y-628305D01*
X140600Y-628388D01*
X141107Y-628221D01*
X141487Y-627805D01*
X141867Y-627055D01*
G01X145573Y-630138D02*
X145700Y-629055D01*
X145890Y-628138D01*
X146143Y-627305D01*
X146460Y-626388D01*
X146967Y-625138D01*
X144433D01*
G01X149977Y-628471D02*
X151623D01*
G01X154507Y-629138D02*
X154887Y-629721D01*
X155393Y-630055D01*
X155963Y-630138D01*
X156470Y-630055D01*
X156977Y-629638D01*
X157293Y-629138D01*
X157357Y-628638D01*
X157230Y-628055D01*
X156787Y-627638D01*
X156343Y-627471D01*
X155773D01*
G01X156343D02*
X156723Y-627221D01*
X157040Y-626805D01*
X157167Y-626305D01*
X157040Y-625805D01*
X156723Y-625388D01*
X156153Y-625138D01*
X155583Y-625221D01*
X155013Y-625555D01*
G01X159797Y-628055D02*
X160240Y-627471D01*
X160620Y-627138D01*
X161127Y-626971D01*
X161570Y-627138D01*
X161887Y-627471D01*
X162140Y-627971D01*
X162203Y-628555D01*
X162140Y-629055D01*
X161887Y-629555D01*
X161507Y-629971D01*
X161063Y-630138D01*
X160557Y-629971D01*
X160113Y-629471D01*
X159860Y-628721D01*
X159797Y-627888D01*
X159923Y-626805D01*
X160113Y-626221D01*
X160430Y-625638D01*
X160873Y-625221D01*
X161317Y-625138D01*
X161760Y-625305D01*
X162077Y-625721D01*
G01X166100Y-630138D02*
Y-625138D01*
X165340Y-626138D01*
G01Y-630138D02*
X166860D01*
G01X171960D02*
Y-625138D01*
X169617Y-628721D01*
X172783D01*
G01X-4000Y-560138D02*
Y-635138D01*
X496000D01*
Y-560138D01*
X-4000D01*
G01X18750Y-102310D02*
Y-106960D01*
X6250D01*
Y-102310D01*
G01X18750Y-83710D02*
Y-79060D01*
X6250D01*
Y-83710D01*
G01X0Y-10000D02*
Y-69685D01*
G01X39370Y10236D02*
Y-48819D01*
X0D01*
Y10236D01*
X39370D01*
G01X2306Y311361D02*
G03X0Y305794I5567J-5567D01*
G01Y54252D01*
G03X7874Y46378I7874J0D01*
G01X43709D01*
G02X51583Y38504I0J-7874D01*
G01Y1969D01*
G03X53551Y0I1968J0D01*
G01X319693D01*
G03X321661Y1969I0J1969D01*
G01Y38504D01*
G02X329535Y46378I7874J0D01*
G01X488591D01*
G02X496465Y38504I0J-7874D01*
G01Y22756D01*
G03X498433Y20787I1968J-1D01*
G01X764575D01*
G03X766543Y22756I-1J1969D01*
G01Y38504D01*
G02X774417Y46378I7874J0D01*
G01X871260D01*
G03X879134Y54252I0J7874D01*
G01Y134331D01*
G02X887008Y142205I7874J0D01*
G01X1011024D01*
G02X1018898Y134331I0J-7874D01*
G01Y54252D01*
G03X1026772Y46378I7874J0D01*
G01X1518118D01*
G02X1525992Y38504I0J-7874D01*
G01Y1969D01*
G03X1527961Y0I1969J0D01*
G01X1794102D01*
G03X1796071Y1969I0J1969D01*
G01Y38504D01*
G02X1803945Y46378I7874J0D01*
G01X1849606D01*
G03X1857480Y54252I0J7874D01*
G01Y305794D01*
G03X1855174Y311361I-7873J0D01*
G01X1846007Y320528D01*
G02X1843701Y326096I5568J5568D01*
G01Y1593983D01*
G03X1841395Y1599550I-7873J0D01*
G01X1834196Y1606749D01*
G02X1831890Y1612317I5568J5568D01*
G01Y1732244D01*
G03X1824016Y1740118I-7874J0D01*
G01X1091791D01*
G03X1089823Y1738150I0J-1968D01*
G01Y1736890D01*
G02X1087854Y1734921I-1969J0D01*
G01X769705D01*
G02X767736Y1736890I0J1969D01*
G01Y1738150D01*
G03X765768Y1740118I-1968J0D01*
G01X33465D01*
G03X25591Y1732244I0J-7874D01*
G01Y1612317D01*
G02X23284Y1606749I-7875J1D01*
G01X10180Y1593645D01*
G03X7874Y1588077I5568J-5568D01*
G01Y320191D01*
G02X5568Y314623I-7874J0D01*
G01X2306Y311361D01*
G01X0Y1750118D02*
Y1790118D01*
G01X831015Y1780118D02*
X0D01*
G01X7000Y1781618D02*
X0Y1780118D01*
X7000Y1778618D01*
Y1781618D01*
G01X21309Y-227910D02*
X33809D01*
G01X21309Y-200010D02*
X33809D01*
G01X38583Y87795D02*
G02X16535I-11024J0D01*
G02X38583I11024J0D01*
G01X34390Y1533228D02*
G02X19705I-7342J0D01*
G02X34390I7343J0D01*
G01X33809Y-227910D02*
Y-223260D01*
G01Y-200010D02*
Y-204660D01*
G01X27559Y-190635D02*
Y77795D01*
G01X31320Y9298D02*
X34420D01*
Y8378D01*
X34265Y8071D01*
X33903Y7841D01*
X33490Y7764D01*
X33077Y7841D01*
X32767Y8033D01*
X32612Y8378D01*
Y9298D01*
G01X34162Y4588D02*
X34317Y4818D01*
X34420Y5086D01*
Y5393D01*
X34265Y5738D01*
X34007Y6006D01*
X33697Y6198D01*
X33180Y6351D01*
X32715Y6389D01*
X32250Y6313D01*
X31940Y6198D01*
X31630Y5968D01*
X31423Y5699D01*
X31320Y5431D01*
Y5163D01*
X31423Y4894D01*
X31578Y4664D01*
X31785Y4473D01*
G01X32973Y2024D02*
X33128Y1871D01*
X33387Y1756D01*
X33748Y1679D01*
X34058Y1756D01*
X34265Y1909D01*
X34420Y2178D01*
Y3213D01*
X31320D01*
Y1948D01*
X31527Y1679D01*
X31837Y1526D01*
X32198Y1449D01*
X32560Y1526D01*
X32870Y1756D01*
X32973Y2024D01*
Y3213D01*
G01X34420Y-2911D02*
X31320Y-3869D01*
X34420Y-4827D01*
G01X31320Y-7736D02*
Y-6202D01*
X34420D01*
Y-7736D01*
G01X32922Y-7122D02*
Y-6202D01*
G01X31320Y-9187D02*
X34420D01*
X31320Y-10951D01*
X34420D01*
G01X31320Y-12326D02*
X34420D01*
Y-13092D01*
X34265Y-13399D01*
X34058Y-13629D01*
X33748Y-13821D01*
X33387Y-13974D01*
X32870Y-14012D01*
X32353Y-13974D01*
X31992Y-13821D01*
X31682Y-13629D01*
X31475Y-13399D01*
X31320Y-13092D01*
Y-12326D01*
G01Y-16269D02*
X31372Y-15962D01*
X31578Y-15694D01*
X31888Y-15464D01*
X32250Y-15311D01*
X32663Y-15234D01*
X33077D01*
X33490Y-15311D01*
X33852Y-15464D01*
X34162Y-15694D01*
X34368Y-15962D01*
X34420Y-16269D01*
X34368Y-16576D01*
X34162Y-16844D01*
X33852Y-17074D01*
X33490Y-17227D01*
X33077Y-17304D01*
X32663D01*
X32250Y-17227D01*
X31888Y-17074D01*
X31578Y-16844D01*
X31372Y-16576D01*
X31320Y-16269D01*
G01Y-18602D02*
X34420D01*
Y-19561D01*
X34265Y-19867D01*
X34058Y-20059D01*
X33645Y-20136D01*
X33232Y-20059D01*
X32973Y-19829D01*
X32818Y-19561D01*
Y-18602D01*
G01Y-19561D02*
X31320Y-20136D01*
G01X29020Y898D02*
X25920D01*
Y-636D01*
G01Y-2969D02*
X25972Y-2662D01*
X26178Y-2394D01*
X26488Y-2164D01*
X26850Y-2011D01*
X27263Y-1934D01*
X27677D01*
X28090Y-2011D01*
X28452Y-2164D01*
X28762Y-2394D01*
X28968Y-2662D01*
X29020Y-2969D01*
X28968Y-3276D01*
X28762Y-3544D01*
X28452Y-3774D01*
X28090Y-3927D01*
X27677Y-4004D01*
X27263D01*
X26850Y-3927D01*
X26488Y-3774D01*
X26178Y-3544D01*
X25972Y-3276D01*
X25920Y-2969D01*
G01X27470Y-6299D02*
Y-7066D01*
X26540D01*
X26230Y-6836D01*
X26023Y-6567D01*
X25920Y-6184D01*
X26023Y-5801D01*
X26230Y-5532D01*
X26540Y-5302D01*
X26902Y-5149D01*
X27315Y-5072D01*
X27677D01*
X27987Y-5149D01*
X28348Y-5302D01*
X28658Y-5532D01*
X28865Y-5762D01*
X29020Y-6069D01*
Y-6337D01*
X28917Y-6644D01*
X28710Y-6874D01*
G01X25920Y-9169D02*
X25972Y-8862D01*
X26178Y-8594D01*
X26488Y-8364D01*
X26850Y-8211D01*
X27263Y-8134D01*
X27677D01*
X28090Y-8211D01*
X28452Y-8364D01*
X28762Y-8594D01*
X28968Y-8862D01*
X29020Y-9169D01*
X28968Y-9476D01*
X28762Y-9744D01*
X28452Y-9974D01*
X28090Y-10127D01*
X27677Y-10204D01*
X27263D01*
X26850Y-10127D01*
X26488Y-9974D01*
X26178Y-9744D01*
X25972Y-9476D01*
X25920Y-9169D01*
G01X51732Y631890D02*
G02X29685I-11024J0D01*
G02X51732I11023J0D01*
G01Y1368898D02*
G02X29685I-11024J0D01*
G02X51732I11023J0D01*
G01X44030Y-264240D02*
X56530D01*
G01X44030Y-259590D02*
Y-264240D01*
G01Y-199140D02*
X56530D01*
G01X44030Y-203790D02*
Y-199140D01*
G01X38346Y-176840D02*
Y1410331D01*
G01X52600Y-176840D02*
X38346D01*
G01X74950Y-165280D02*
X40708D01*
G01D02*
Y1358908D01*
G01X51180Y-155260D02*
Y1704961D01*
G01X95760Y-155260D02*
X51180D01*
G01X52141Y119148D02*
X56741Y123451D01*
G02X65079Y114538I4169J-4456D01*
G01X60479Y110235D01*
G02X52141Y119148I-4169J4456D01*
G01X40157Y1714961D02*
G02X62205I11024J0D01*
G02X40157I-11024J0D01*
G01X56530Y-264240D02*
Y-259590D01*
G01Y-199140D02*
Y-203790D01*
G01X52296Y-189765D02*
X52600Y-176840D01*
G01X124270Y-144470D02*
X58609D01*
G01D02*
Y106842D01*
G01X67540Y-272340D02*
Y-276990D01*
G01D02*
X80040D01*
G01D02*
Y-272340D01*
G01X67540Y-204140D02*
Y-199490D01*
G01D02*
X80040D01*
G01D02*
Y-204140D01*
G01X74703Y-190115D02*
X74950Y-165280D01*
G01X79590Y-132140D02*
Y1359350D01*
G01X155100Y-132140D02*
X79590D01*
G01X86933Y1369350D02*
G02X72248I-7343J0D01*
G02X86933I7342J0D01*
G01X91050Y-240280D02*
X103550D01*
G01X91050Y-235630D02*
Y-240280D01*
G01Y-199980D02*
X103550D01*
G01X91050Y-204630D02*
Y-199980D01*
G01X96261Y-190605D02*
X95760Y-155260D01*
G01X103550Y-240280D02*
Y-235630D01*
G01Y-199980D02*
Y-204630D01*
G01X137618Y605378D02*
G02X98248I-19685J0D01*
G02X137618I19685J0D01*
G01X116480Y-272720D02*
Y-277370D01*
G01D02*
X128980D01*
G01X116480Y-204520D02*
Y-199870D01*
G01D02*
X128980D01*
G01X123756Y-190495D02*
X124270Y-144470D01*
G01X117933Y-120580D02*
Y595376D01*
G01X178990Y-120580D02*
X117933D01*
G01X128980Y-277370D02*
Y-272720D01*
G01Y-199870D02*
Y-204520D01*
G01X146929Y1482244D02*
G02X129213I-8858J0D01*
G02X146929I8858J0D01*
G01X144626Y1533228D02*
G02X129941I-7343J0D01*
G02X144626I7342J0D01*
G01X148080Y-278140D02*
X160580D01*
G01X148080Y-273490D02*
Y-278140D01*
G01Y-200640D02*
X160580D01*
G01X148080Y-205290D02*
Y-200640D01*
G01X154799Y-191265D02*
X155100Y-132140D01*
G01X142400Y236290D02*
X146103Y242417D01*
G01X148288Y240361D02*
X142400Y236290D01*
G01X154730Y249400D02*
X142400Y236290D01*
G01X146103Y242417D02*
X148288Y240361D01*
G01X172520Y1593661D02*
G02X154803I-8858J0D01*
G02X172520I8859J0D01*
G01X160580Y-278140D02*
Y-273490D01*
G01Y-200640D02*
Y-205290D01*
G01X157728Y294335D02*
G02X197098I19685J0D01*
G01Y260083D01*
G02X157728I-19685J0D01*
G01Y294335D01*
G01X185240Y-278880D02*
Y-274230D01*
G01X172740Y-278880D02*
X185240D01*
G01X172740Y-274230D02*
Y-278880D01*
G01X185240Y-201380D02*
Y-206030D01*
G01X172740Y-201380D02*
X185240D01*
G01X172740Y-206030D02*
Y-201380D01*
G01X178990Y-192005D02*
Y-120580D01*
G01X191000Y-560138D02*
Y-635138D01*
G01Y-610138D02*
X294000D01*
Y-585138D01*
G01X191000D02*
X294000D01*
G01X215418Y-179920D02*
Y648055D01*
G01X229090Y-179920D02*
X215418D01*
G01X222760Y658012D02*
G02X208075I-7342J0D01*
G02X222760I7343J0D01*
G01X223610Y-279650D02*
X236110D01*
G01X223610Y-275000D02*
Y-279650D01*
G01X229179Y-192775D02*
X229090Y-179920D01*
G01X223610Y-202150D02*
X236110D01*
G01X223610Y-206800D02*
Y-202150D01*
G01X226605Y1738112D02*
X290405D01*
Y1640912D01*
X226605D01*
Y1738112D01*
G01X236110Y-279650D02*
Y-275000D01*
G01X244076Y-278880D02*
X256576D01*
G01X244076Y-274230D02*
Y-278880D01*
G01X236110Y-202150D02*
Y-206800D01*
G01X244076Y-201380D02*
X256576D01*
G01X244076Y-206030D02*
Y-201380D01*
G01X247177Y191535D02*
X253476D01*
G02Y178937I0J-6299D01*
G01X247177D01*
G02Y191535I0J6299D01*
G01X256576Y-278880D02*
Y-274230D01*
G01Y-201380D02*
Y-206030D01*
G01X250326Y-192005D02*
Y175236D01*
G01X249900Y1744530D02*
X387080Y1918710D01*
G01X268663Y-279650D02*
X281163D01*
G01X268663Y-275000D02*
Y-279650D01*
G01X274913Y-192775D02*
Y1009214D01*
G01X268663Y-202150D02*
X281163D01*
G01X268663Y-206800D02*
Y-202150D01*
G01X284579Y185236D02*
G02X269618I-7481J0D01*
G02X284579I7481J0D01*
G01X282795Y1019252D02*
G02X267047I-7874J0D01*
G02X282795I7874J0D01*
G01X283783Y1357539D02*
G02X269098I-7342J0D01*
G02X283783I7343J0D01*
G01X281163Y-279650D02*
Y-275000D01*
G01X289890Y-280420D02*
X302390D01*
G01X289890Y-275770D02*
Y-280420D01*
G01Y-207570D02*
Y-202920D01*
G01X281163Y-202150D02*
Y-206800D01*
G01X289890Y-202920D02*
X302390D01*
G01X276440Y-179920D02*
Y1347539D01*
G01X296910Y-179920D02*
X276440D01*
G01X277098Y-167970D02*
Y175236D01*
G01X317330Y-167970D02*
X277098D01*
G01X296000Y-560138D02*
Y-635138D01*
G01X294000Y-560138D02*
Y-635138D01*
G01X301507Y-620138D02*
Y-615138D01*
X302773D01*
X303280Y-615388D01*
X303660Y-615721D01*
X303977Y-616221D01*
X304230Y-616805D01*
X304293Y-617638D01*
X304230Y-618471D01*
X303977Y-619055D01*
X303660Y-619555D01*
X303280Y-619888D01*
X302773Y-620138D01*
X301507D01*
G01X306417D02*
X308000Y-615138D01*
X309583Y-620138D01*
G01X309013Y-618388D02*
X306987D01*
G01X313100Y-615138D02*
Y-620138D01*
G01X311643Y-615138D02*
X314557D01*
G01X319467Y-620138D02*
X316933D01*
Y-615138D01*
X319467D01*
G01X318453Y-617555D02*
X316933D01*
G01X323300Y-620305D02*
X323173Y-620221D01*
Y-620055D01*
X323300Y-619971D01*
X323427Y-620055D01*
Y-620221D01*
X323300Y-620305D01*
G01Y-618055D02*
X323173Y-617971D01*
Y-617805D01*
X323300Y-617721D01*
X323427Y-617805D01*
Y-617971D01*
X323300Y-618055D01*
G01X296000Y-610138D02*
X496000D01*
G01X301633Y-595138D02*
Y-590138D01*
X303153D01*
X303660Y-590388D01*
X304040Y-590971D01*
X304167Y-591638D01*
X304040Y-592305D01*
X303723Y-592805D01*
X303153Y-593055D01*
X301633D01*
G01X306860Y-595305D02*
X309140Y-590138D01*
G01X311643Y-595138D02*
Y-590138D01*
X314557Y-595138D01*
Y-590138D01*
G01X318200Y-595305D02*
X318073Y-595221D01*
Y-595055D01*
X318200Y-594971D01*
X318327Y-595055D01*
Y-595221D01*
X318200Y-595305D01*
G01Y-593055D02*
X318073Y-592971D01*
Y-592805D01*
X318200Y-592721D01*
X318327Y-592805D01*
Y-592971D01*
X318200Y-593055D01*
G01X296000Y-585138D02*
X496000D01*
G01X301633Y-570138D02*
Y-565138D01*
X303153D01*
X303660Y-565388D01*
X304040Y-565971D01*
X304167Y-566638D01*
X304040Y-567305D01*
X303723Y-567805D01*
X303153Y-568055D01*
X301633D01*
G01X306733Y-570138D02*
Y-565138D01*
X308317D01*
X308823Y-565388D01*
X309140Y-565721D01*
X309267Y-566388D01*
X309140Y-567055D01*
X308760Y-567471D01*
X308317Y-567721D01*
X306733D01*
G01X308317D02*
X309267Y-570138D01*
G01X313100D02*
X312593Y-570055D01*
X312150Y-569721D01*
X311770Y-569221D01*
X311517Y-568638D01*
X311390Y-567971D01*
Y-567305D01*
X311517Y-566638D01*
X311770Y-566055D01*
X312150Y-565555D01*
X312593Y-565221D01*
X313100Y-565138D01*
X313607Y-565221D01*
X314050Y-565555D01*
X314430Y-566055D01*
X314683Y-566638D01*
X314810Y-567305D01*
Y-567971D01*
X314683Y-568638D01*
X314430Y-569221D01*
X314050Y-569721D01*
X313607Y-570055D01*
X313100Y-570138D01*
G01X316933Y-569138D02*
X317250Y-569638D01*
X317630Y-569971D01*
X318073Y-570138D01*
X318580Y-569971D01*
X318960Y-569638D01*
X319340Y-569138D01*
X319467Y-568471D01*
Y-565138D01*
G01X324567Y-570138D02*
X322033D01*
Y-565138D01*
X324567D01*
G01X323553Y-567555D02*
X322033D01*
G01X329793Y-565555D02*
X329413Y-565305D01*
X328970Y-565138D01*
X328463D01*
X327893Y-565388D01*
X327450Y-565805D01*
X327133Y-566305D01*
X326880Y-567138D01*
X326817Y-567888D01*
X326943Y-568638D01*
X327133Y-569138D01*
X327513Y-569638D01*
X327957Y-569971D01*
X328400Y-570138D01*
X328843D01*
X329287Y-569971D01*
X329667Y-569721D01*
X329983Y-569388D01*
G01X333500Y-565138D02*
Y-570138D01*
G01X332043Y-565138D02*
X334957D01*
G01X338600Y-570305D02*
X338473Y-570221D01*
Y-570055D01*
X338600Y-569971D01*
X338727Y-570055D01*
Y-570221D01*
X338600Y-570305D01*
G01Y-568055D02*
X338473Y-567971D01*
Y-567805D01*
X338600Y-567721D01*
X338727Y-567805D01*
Y-567971D01*
X338600Y-568055D01*
G01X302390Y-280420D02*
Y-275770D01*
G01Y-202920D02*
Y-207570D01*
G01X296816Y-193545D02*
X296910Y-179920D01*
G01X356685Y1668212D02*
X293635D01*
Y1736912D01*
X356685D01*
Y1668212D01*
G01X312240Y-282350D02*
X324740D01*
G01X312240Y-277700D02*
Y-282350D01*
G01Y-209500D02*
Y-204850D01*
G01X317584Y-195475D02*
X317330Y-167970D01*
G01X312240Y-204850D02*
X324740D01*
G01X328071Y838543D02*
G02X312323I-7874J0D01*
G02X328071I7874J0D01*
G01Y1199961D02*
G02X312323I-7874J0D01*
G02X328071I7874J0D01*
G01X324740Y-282350D02*
Y-277700D01*
G01Y-204850D02*
Y-209500D01*
G01X320189Y-151400D02*
Y1189923D01*
G01X341610Y-151400D02*
X320189D01*
G01X326970Y1746840D02*
X409430Y1911770D01*
G01X347860Y-282730D02*
Y-278080D01*
G01X335360Y-282730D02*
X347860D01*
G01X335360Y-278080D02*
Y-282730D01*
G01X347860Y-205230D02*
Y-209880D01*
G01X335360D02*
Y-205230D01*
G01X341610Y-195855D02*
Y-151400D01*
G01X335360Y-205230D02*
X347860D01*
G01X362187Y-281960D02*
X374687D01*
G01X362187Y-277310D02*
Y-281960D01*
G01Y-209110D02*
Y-204460D01*
G01D02*
X374687D01*
G01X384646Y87795D02*
G02X362598I-11024J0D01*
G02X384646I11024J0D01*
G01X365287Y191535D02*
X371587D01*
G02Y178937I0J-6299D01*
G01X365287D01*
G02Y191535I0J6299D01*
G01X374687Y-281960D02*
Y-277310D01*
G01Y-204460D02*
Y-209110D01*
G01X368437Y-195085D02*
Y175236D01*
G01X373622Y-183770D02*
Y77795D01*
G01X393250Y-183770D02*
X373622D01*
G01X387000Y-269600D02*
X399500D01*
G01X387000Y-264950D02*
Y-269600D01*
G01Y-209150D02*
Y-204500D01*
G01X393250Y-195125D02*
Y-183770D01*
G01X387000Y-204500D02*
X399500D01*
G01X402689Y185236D02*
G02X387728I-7480J0D01*
G02X402689I7481J0D01*
G01X406694Y1714961D02*
G02X384647I-11023J0D01*
G02X406694I11023J0D01*
G01X387080Y1918710D02*
X383927Y1912283D01*
G01X381571Y1914139D02*
X387080Y1918710D01*
G01X383927Y1912283D02*
X381571Y1914139D01*
G01X406650Y-294330D02*
X419150D01*
G01X406650Y-289680D02*
Y-294330D01*
G01X399500Y-269600D02*
Y-264950D01*
G01Y-204500D02*
Y-209150D01*
G01X406650Y-209080D02*
Y-204430D01*
G01D02*
X419150D01*
G01X395208Y-172980D02*
Y175236D01*
G01X412900Y-172980D02*
X395208D01*
G01X395671Y-163160D02*
Y1704960D01*
G01X429470Y-163160D02*
X395671D01*
G01X409430Y1911770D02*
X407641Y1904838D01*
G01X404958Y1906180D02*
X409430Y1911770D01*
G01X407641Y1904838D02*
X404958Y1906180D01*
G01X411000Y-610138D02*
Y-635138D01*
G01X413633Y-612638D02*
Y-617638D01*
X416167D01*
G01X419240Y-612638D02*
X420760D01*
G01X420000D02*
Y-617638D01*
G01X419240D02*
X420760D01*
G01X425607Y-614971D02*
X425860Y-614721D01*
X426050Y-614305D01*
X426177Y-613721D01*
X426050Y-613221D01*
X425797Y-612888D01*
X425353Y-612638D01*
X423643D01*
Y-617638D01*
X425733D01*
X426177Y-617305D01*
X426430Y-616805D01*
X426557Y-616221D01*
X426430Y-615638D01*
X426050Y-615138D01*
X425607Y-614971D01*
X423643D01*
G01X430200Y-617805D02*
X430073Y-617721D01*
Y-617555D01*
X430200Y-617471D01*
X430327Y-617555D01*
Y-617721D01*
X430200Y-617805D01*
G01Y-615555D02*
X430073Y-615471D01*
Y-615305D01*
X430200Y-615221D01*
X430327Y-615305D01*
Y-615471D01*
X430200Y-615555D01*
G01X419150Y-294330D02*
Y-289680D01*
G01X423800Y-288900D02*
X436300D01*
G01X423800Y-284250D02*
Y-288900D01*
G01X419150Y-204430D02*
Y-209080D01*
G01X423800Y-211400D02*
X436300D01*
G01X423800Y-216050D02*
Y-211400D01*
G01X412900Y-195055D02*
Y-172980D01*
G01X420125Y-143700D02*
Y646008D01*
G01X456450Y-143700D02*
X420125D01*
G01X427484Y655965D02*
G02X412799I-7343J0D01*
G02X427484I7343J0D01*
G01X436300Y-288900D02*
Y-284250D01*
G01Y-211400D02*
Y-216050D01*
G01X429635Y-202025D02*
X429470Y-163160D01*
G01X451106Y1339823D02*
G02X436421I-7343J0D01*
G02X451106I7343J0D01*
G01X434793Y1698268D02*
G02X447293I6250J0D01*
G02X434793I-6250J0D01*
G01X431780Y1911770D02*
X436376Y1906281D01*
G01X433724Y1904880D02*
X431780Y1911770D01*
G01X436376Y1906281D02*
X433724Y1904880D01*
G01X518100Y1748380D02*
X431780Y1911770D01*
G01X454000Y-610138D02*
Y-635138D01*
G01Y-585138D02*
Y-610138D01*
G01X450200Y-295100D02*
X462700D01*
G01X450200Y-290450D02*
Y-295100D01*
G01Y-209850D02*
Y-205200D01*
G01D02*
X462700D01*
G01X441043Y-122890D02*
Y1708465D01*
G01X481110Y-122890D02*
X441043D01*
G01X443764Y-112100D02*
Y1329823D01*
G01X508850Y-112100D02*
X443764D01*
G01X447200Y1924870D02*
X452616Y1920189D01*
G01X450222Y1918380D02*
X447200Y1924870D01*
G01X452616Y1920189D02*
X450222Y1918380D01*
G01X582840Y1745300D02*
X447200Y1924870D01*
G01X459013Y-637305D02*
X459120Y-637180D01*
X459200Y-636971D01*
X459253Y-636680D01*
X459200Y-636430D01*
X459093Y-636263D01*
X458907Y-636138D01*
X458187D01*
Y-638638D01*
X459067D01*
X459253Y-638471D01*
X459360Y-638221D01*
X459413Y-637930D01*
X459360Y-637638D01*
X459200Y-637388D01*
X459013Y-637305D01*
X458187D01*
G01X461480Y-638638D02*
Y-636971D01*
G01Y-637263D02*
X461373Y-637096D01*
X461213Y-637013D01*
X461027Y-636971D01*
X460840Y-637055D01*
X460680Y-637221D01*
X460573Y-637471D01*
X460520Y-637805D01*
X460573Y-638138D01*
X460680Y-638388D01*
X460840Y-638555D01*
X461027Y-638638D01*
X461213Y-638596D01*
X461373Y-638471D01*
X461480Y-638305D01*
G01X462800Y-638346D02*
X462933Y-638513D01*
X463120Y-638638D01*
X463280D01*
X463440Y-638555D01*
X463547Y-638430D01*
X463600Y-638263D01*
X463573Y-638013D01*
X463467Y-637888D01*
X462987Y-637638D01*
X462880Y-637346D01*
X462933Y-637138D01*
X463040Y-637013D01*
X463200Y-636971D01*
X463360Y-637013D01*
X463520Y-637138D01*
G01X465000Y-637513D02*
X465853D01*
X465773Y-637221D01*
X465640Y-637055D01*
X465453Y-636971D01*
X465267Y-637013D01*
X465107Y-637138D01*
X465000Y-637430D01*
X464947Y-637680D01*
Y-637930D01*
X465000Y-638180D01*
X465133Y-638430D01*
X465293Y-638596D01*
X465480Y-638638D01*
X465667Y-638555D01*
X465853Y-638305D01*
G01X467120Y-638638D02*
Y-636138D01*
G01Y-637388D02*
X467253Y-637138D01*
X467413Y-637013D01*
X467573Y-636971D01*
X467813Y-637055D01*
X467973Y-637221D01*
X468080Y-637513D01*
Y-637846D01*
X468027Y-638180D01*
X467920Y-638430D01*
X467733Y-638596D01*
X467573Y-638638D01*
X467413Y-638596D01*
X467253Y-638471D01*
X467120Y-638263D01*
G01X469800Y-638638D02*
X469640Y-638596D01*
X469480Y-638430D01*
X469373Y-638138D01*
X469320Y-637805D01*
X469373Y-637471D01*
X469480Y-637180D01*
X469640Y-637013D01*
X469800Y-636971D01*
X469960Y-637013D01*
X470120Y-637180D01*
X470227Y-637471D01*
X470253Y-637805D01*
X470227Y-638138D01*
X470120Y-638430D01*
X469960Y-638596D01*
X469800Y-638638D01*
G01X472480D02*
Y-636971D01*
G01Y-637263D02*
X472373Y-637096D01*
X472213Y-637013D01*
X472027Y-636971D01*
X471840Y-637055D01*
X471680Y-637221D01*
X471573Y-637471D01*
X471520Y-637805D01*
X471573Y-638138D01*
X471680Y-638388D01*
X471840Y-638555D01*
X472027Y-638638D01*
X472213Y-638596D01*
X472373Y-638471D01*
X472480Y-638305D01*
G01X473827Y-638638D02*
Y-636971D01*
G01Y-637305D02*
X473960Y-637138D01*
X474093Y-637013D01*
X474280Y-636971D01*
X474413Y-637013D01*
X474573Y-637138D01*
G01X476880Y-636138D02*
Y-638638D01*
G01Y-638263D02*
X476773Y-638471D01*
X476613Y-638596D01*
X476427Y-638638D01*
X476213Y-638555D01*
X476053Y-638346D01*
X475947Y-638096D01*
X475920Y-637805D01*
X475947Y-637513D01*
X476053Y-637263D01*
X476213Y-637055D01*
X476427Y-636971D01*
X476613Y-637013D01*
X476747Y-637096D01*
X476880Y-637263D01*
G01X480267Y-638638D02*
Y-636138D01*
X480933D01*
X481147Y-636263D01*
X481280Y-636430D01*
X481333Y-636763D01*
X481280Y-637096D01*
X481120Y-637305D01*
X480933Y-637430D01*
X480267D01*
G01X480933D02*
X481333Y-638638D01*
G01X482600Y-637513D02*
X483453D01*
X483373Y-637221D01*
X483240Y-637055D01*
X483053Y-636971D01*
X482867Y-637013D01*
X482707Y-637138D01*
X482600Y-637430D01*
X482547Y-637680D01*
Y-637930D01*
X482600Y-638180D01*
X482733Y-638430D01*
X482893Y-638596D01*
X483080Y-638638D01*
X483267Y-638555D01*
X483453Y-638305D01*
G01X484720Y-636971D02*
X485200Y-638638D01*
X485680Y-636971D01*
G01X487400Y-638721D02*
X487347Y-638680D01*
Y-638596D01*
X487400Y-638555D01*
X487453Y-638596D01*
Y-638680D01*
X487400Y-638721D01*
G01X489147Y-638346D02*
X489333Y-638555D01*
X489547Y-638638D01*
X489760Y-638555D01*
X489947Y-638305D01*
X490080Y-637930D01*
X490133Y-637555D01*
Y-637096D01*
X490080Y-636721D01*
X489947Y-636388D01*
X489787Y-636221D01*
X489600Y-636138D01*
X489387Y-636221D01*
X489227Y-636388D01*
X489120Y-636638D01*
X489067Y-636971D01*
X489120Y-637263D01*
X489253Y-637555D01*
X489413Y-637721D01*
X489600Y-637763D01*
X489813Y-637680D01*
X489973Y-637471D01*
X490133Y-637096D01*
G01X492013Y-637305D02*
X492120Y-637180D01*
X492200Y-636971D01*
X492253Y-636680D01*
X492200Y-636430D01*
X492093Y-636263D01*
X491907Y-636138D01*
X491187D01*
Y-638638D01*
X492067D01*
X492253Y-638471D01*
X492360Y-638221D01*
X492413Y-637930D01*
X492360Y-637638D01*
X492200Y-637388D01*
X492013Y-637305D01*
X491187D01*
G01X457900Y-612638D02*
Y-617638D01*
G01X456443Y-612638D02*
X459357D01*
G01X463000Y-617638D02*
X462620Y-617555D01*
X462240Y-617221D01*
X461987Y-616638D01*
X461860Y-615971D01*
X461987Y-615305D01*
X462240Y-614721D01*
X462620Y-614388D01*
X463000Y-614305D01*
X463380Y-614388D01*
X463760Y-614721D01*
X464013Y-615305D01*
X464077Y-615971D01*
X464013Y-616638D01*
X463760Y-617221D01*
X463380Y-617555D01*
X463000Y-617638D01*
G01X468100D02*
X467720Y-617555D01*
X467340Y-617221D01*
X467087Y-616638D01*
X466960Y-615971D01*
X467087Y-615305D01*
X467340Y-614721D01*
X467720Y-614388D01*
X468100Y-614305D01*
X468480Y-614388D01*
X468860Y-614721D01*
X469113Y-615305D01*
X469177Y-615971D01*
X469113Y-616638D01*
X468860Y-617221D01*
X468480Y-617555D01*
X468100Y-617638D01*
G01X473200D02*
Y-612638D01*
G01X478300Y-617805D02*
X478173Y-617721D01*
Y-617555D01*
X478300Y-617471D01*
X478427Y-617555D01*
Y-617721D01*
X478300Y-617805D01*
G01Y-615555D02*
X478173Y-615471D01*
Y-615305D01*
X478300Y-615221D01*
X478427Y-615305D01*
Y-615471D01*
X478300Y-615555D01*
G01X456633Y-592638D02*
Y-587638D01*
X458217D01*
X458723Y-587888D01*
X459040Y-588221D01*
X459167Y-588888D01*
X459040Y-589555D01*
X458660Y-589971D01*
X458217Y-590221D01*
X456633D01*
G01X458217D02*
X459167Y-592638D01*
G01X464267D02*
X461733D01*
Y-587638D01*
X464267D01*
G01X463253Y-590055D02*
X461733D01*
G01X466517Y-587638D02*
X468100Y-592638D01*
X469683Y-587638D01*
G01X473200Y-592805D02*
X473073Y-592721D01*
Y-592555D01*
X473200Y-592471D01*
X473327Y-592555D01*
Y-592721D01*
X473200Y-592805D01*
G01Y-590555D02*
X473073Y-590471D01*
Y-590305D01*
X473200Y-590221D01*
X473327Y-590305D01*
Y-590471D01*
X473200Y-590555D01*
G01X462700Y-295100D02*
Y-290450D01*
G01Y-205200D02*
Y-209850D01*
G01X456450Y-195825D02*
Y-143700D01*
G01X474090Y-295100D02*
X486590D01*
G01X474090Y-290450D02*
Y-295100D01*
G01Y-209850D02*
Y-205200D01*
G01X480793Y-195825D02*
X481110Y-122890D01*
G01X474090Y-205200D02*
X486590D01*
G01Y-295100D02*
Y-290450D01*
G01Y-205200D02*
Y-209850D01*
G01X553928Y1668212D02*
X490878D01*
Y1736912D01*
X553928D01*
Y1668212D01*
G01X501830Y-293560D02*
X514330D01*
G01X501830Y-288910D02*
Y-293560D01*
G01Y-208310D02*
Y-203660D01*
G01X508511Y-194285D02*
X508850Y-112100D01*
G01X501830Y-203660D02*
X514330D01*
G01Y-293560D02*
Y-288910D01*
G01X526490Y-292020D02*
X538990D01*
G01X526490Y-287370D02*
Y-292020D01*
G01X514330Y-203660D02*
Y-208310D01*
G01X526490Y-202120D02*
X538990D01*
G01X526490Y-206770D02*
Y-202120D01*
G01X523173Y-177610D02*
Y568174D01*
G01X533520Y-177610D02*
X523173D01*
G01X530516Y578130D02*
G02X515831I-7343J0D01*
G02X530516I7342J0D01*
G01X538990Y-292020D02*
Y-287370D01*
G01X533421Y-192745D02*
X533520Y-177610D01*
G01X538990Y-202120D02*
Y-206770D01*
G01X554883Y-294330D02*
X567383D01*
G01X554883Y-289680D02*
Y-294330D01*
G01Y-209080D02*
Y-204430D01*
G01D02*
X567383D01*
G01X569016Y838543D02*
G02X553268I-7874J0D01*
G02X569016I7874J0D01*
G01Y1199961D02*
G02X553268I-7874J0D01*
G02X569016I7874J0D01*
G01X548898Y1432726D02*
X607953D01*
Y1401230D01*
X548898D01*
Y1432726D01*
G01X620858Y1668212D02*
X557808D01*
Y1736912D01*
X620858D01*
Y1668212D01*
G01X567383Y-294330D02*
Y-289680D01*
G01Y-204430D02*
Y-209080D01*
G01X561133Y-195055D02*
Y1189923D01*
G01X600159Y-295870D02*
X612659D01*
G01X600159Y-291220D02*
Y-295870D01*
G01Y-210620D02*
Y-205970D01*
G01D02*
X612659D01*
G01X614291Y1019252D02*
G02X598543I-7874J0D01*
G02X614291I7874J0D01*
G01X612659Y-295870D02*
Y-291220D01*
G01Y-205970D02*
Y-210620D01*
G01X606409Y-196595D02*
Y1009214D01*
G01X654774Y-288130D02*
X667274D01*
G01X654774Y-283480D02*
Y-288130D01*
G01Y-210630D02*
X667274D01*
G01X654774Y-215280D02*
Y-210630D01*
G01X661024Y-201255D02*
Y621890D01*
G01X672047Y631890D02*
G02X650000I-11024J0D01*
G02X672047I11023J0D01*
G01X667274Y-288130D02*
Y-283480D01*
G01Y-210630D02*
Y-215280D01*
G01X688783Y1385138D02*
G02X674098I-7343J0D01*
G02X688783I7343J0D01*
G01X682087Y1593661D02*
G02X664370I-8859J0D01*
G02X682087I8859J0D01*
G01X683720Y-303580D02*
X696220D01*
G01X683720Y-298930D02*
Y-303580D01*
G01Y-213680D02*
X696220D01*
G01X683720Y-218330D02*
Y-213680D01*
G01X689970Y-204305D02*
Y-177610D01*
G01X681440D02*
Y1375138D01*
G01X689970Y-177610D02*
X681440D01*
G01X684500Y294362D02*
G02X723870I19685J0D01*
G01Y260110D01*
G02X684500I-19685J0D01*
G01Y294362D01*
G01X707677Y1482244D02*
G02X689961I-8858J0D01*
G02X707677I8858J0D01*
G01X696220Y-303580D02*
Y-298930D01*
G01Y-213680D02*
Y-218330D01*
G01X704185Y-167590D02*
Y284362D01*
G01X716940Y-167590D02*
X704185D01*
G01X718701Y1714961D02*
G02X696654I-11024J0D01*
G02X718701I11023J0D01*
G01X721650Y-298180D02*
Y-293530D01*
G01X709150Y-298180D02*
X721650D01*
G01X709150Y-293530D02*
Y-298180D01*
G01X721650Y-208280D02*
Y-212930D01*
G01X709150Y-208280D02*
X721650D01*
G01X709150Y-212930D02*
Y-208280D01*
G01X716584Y-198905D02*
X716940Y-167590D01*
G01X707677Y-157570D02*
Y1704961D01*
G01X739290Y-157570D02*
X707677D01*
G01X733040Y-298180D02*
X745540D01*
G01X733040Y-293530D02*
Y-298180D01*
G01Y-208280D02*
X745540D01*
G01X733040Y-212930D02*
Y-208280D01*
G01X738560Y235910D02*
X732729Y240063D01*
G01X734942Y242087D02*
X738560Y235910D01*
G01X726220Y249400D02*
X738560Y235910D01*
G01X732729Y240063D02*
X734942Y242087D01*
G01X745540Y-298180D02*
Y-293530D01*
G01Y-208280D02*
Y-212930D01*
G01X739290Y-198905D02*
Y-157570D01*
G01X783287Y605413D02*
G02X743917I-19685J0D01*
G02X783287I19685J0D01*
G01X757352Y-298180D02*
X769852D01*
G01X757352Y-293530D02*
Y-298180D01*
G01Y-208280D02*
X769852D01*
G01X757352Y-212930D02*
Y-208280D01*
G01X763602Y-198905D02*
Y595413D01*
G01X769852Y-298180D02*
Y-293530D01*
G01Y-208280D02*
Y-212930D01*
G01X785428Y-298950D02*
X797928D01*
G01X785428Y-294300D02*
Y-298950D01*
G01Y-209050D02*
X797928D01*
G01X785428Y-213700D02*
Y-209050D01*
G01X791678Y-199675D02*
Y1375138D01*
G01X811811Y87795D02*
G02X789764I-11023J0D01*
G02X811811I11023J0D01*
G01X816535Y204724D02*
G02X794882I-10826J0D01*
G02X816535I10827J0D01*
G01X799020Y1385138D02*
G02X784335I-7343J0D01*
G02X799020I7342J0D01*
G01X797928Y-298950D02*
Y-294300D01*
G01X807800Y-286590D02*
X820300D01*
G01X807800Y-281940D02*
Y-286590D01*
G01X797928Y-209050D02*
Y-213700D01*
G01X807800Y-209090D02*
X820300D01*
G01X807800Y-213740D02*
Y-209090D01*
G01X800787Y-188400D02*
Y77795D01*
G01X815590Y-188400D02*
X800787D01*
G01X805690Y-178380D02*
Y194724D01*
G01X836400Y-178380D02*
X805690D01*
G01X820300Y-286590D02*
Y-281940D01*
G01Y-209090D02*
Y-213740D01*
G01X815431Y-199715D02*
X815590Y-188400D01*
G01X813680Y1719690D02*
Y1679290D01*
X1043280D01*
Y1719690D01*
X813680D01*
G01X829380Y-299720D02*
X841880D01*
G01X829380Y-295070D02*
Y-299720D01*
G01Y-209820D02*
X841880D01*
G01X829380Y-214470D02*
Y-209820D01*
G01X836266Y-200445D02*
X836400Y-178380D01*
G01X841240Y-162960D02*
Y1410331D01*
G01X857980Y-162960D02*
X841240D01*
G01X849114Y1420331D02*
G02X833366I-7874J0D01*
G02X849114I7874J0D01*
G01X841880Y-299720D02*
Y-295070D01*
G01X853270Y-298180D02*
X865770D01*
G01X853270Y-293530D02*
Y-298180D01*
G01X841880Y-209820D02*
Y-214470D01*
G01X853270Y-208280D02*
X865770D01*
G01X853270Y-212930D02*
Y-208280D01*
G01X854790Y1761368D02*
X850140D01*
Y1773868D01*
X854790D01*
G01X865770Y-298180D02*
Y-293530D01*
G01Y-208280D02*
Y-212930D01*
G01X858375Y-198905D02*
X857980Y-162960D01*
G01X880965Y1145276D02*
G02X866280I-7342J0D01*
G02X880965I7343J0D01*
G01X895789Y1528196D02*
G02X879254I-8267J0D01*
G02X895789I8268J0D01*
G01X893947Y-298180D02*
X906447D01*
G01X893947Y-293530D02*
Y-298180D01*
G01Y-208280D02*
X906447D01*
G01X893947Y-212930D02*
Y-208280D01*
G01X900197Y-198905D02*
Y165177D01*
G01X904134Y175177D02*
G02X896260I-3937J0D01*
G02X904134I3937J0D01*
G01X899980Y1922560D02*
X904155Y1916745D01*
G01X901406Y1915544D02*
X899980Y1922560D01*
G01X979370Y1740680D02*
X899980Y1922560D01*
G01X906447Y-298180D02*
Y-293530D01*
G01Y-208280D02*
Y-212930D01*
G01X936673Y311614D02*
X920807D01*
G02X936673I7933J10039D01*
G01X904155Y1916745D02*
X901406Y1915544D01*
G01X925443Y-297410D02*
X937943D01*
G01X925443Y-292760D02*
Y-297410D01*
G01Y-212160D02*
Y-207510D01*
G01D02*
X937943D01*
G01X942717Y757874D02*
G02X920669I-11024J0D01*
G02X942717I11024J0D01*
G01Y1072835D02*
G02X920669I-11024J0D01*
G02X942717I11024J0D01*
G01Y1387795D02*
G02X920669I-11024J0D01*
G02X942717I11024J0D01*
G01X922990Y1761368D02*
X927640D01*
Y1773868D01*
X922990D01*
G01X937943Y-297410D02*
Y-292760D01*
G01Y-207510D02*
Y-212160D01*
G01X931693Y-198135D02*
Y1377795D01*
G01X944685Y-179920D02*
Y145197D01*
G01X956630Y-179920D02*
X944685D01*
G01X948622Y155197D02*
G02X940748I-3937J0D01*
G02X948622I3937J0D01*
G01X931749Y311557D02*
X945349Y292257D01*
G01X934822Y308906D02*
X931749Y311557D01*
X933213Y307772D01*
X934822Y308906D01*
G01X951150Y-297410D02*
X963650D01*
G01X951150Y-292760D02*
Y-297410D01*
G01Y-212160D02*
Y-207510D01*
G01X956744Y-198135D02*
X956630Y-179920D01*
G01X951150Y-207510D02*
X963650D01*
G01X946465Y1780118D02*
X1857480D01*
G01X963650Y-297410D02*
Y-292760D01*
G01Y-207510D02*
Y-212160D01*
G01X991201Y1145276D02*
G02X976516I-7343J0D01*
G02X991201I7343J0D01*
G01X1009990Y-298920D02*
X1022490D01*
G01X1009990Y-294270D02*
Y-298920D01*
G01Y-209020D02*
X1022490D01*
G01X1009990Y-213670D02*
Y-209020D01*
G01X1016240Y-199645D02*
Y1410331D01*
G01X1024114Y1420331D02*
G02X1008366I-7874J0D01*
G02X1024114I7874J0D01*
G01X1022490Y-298920D02*
Y-294270D01*
G01Y-209020D02*
Y-213670D01*
G01X1056890Y87795D02*
G02X1034843I-11023J0D01*
G02X1056890I11024J0D01*
G01X1039616Y-299690D02*
X1052116D01*
G01X1039616Y-295040D02*
Y-299690D01*
G01Y-209790D02*
X1052116D01*
G01X1039616Y-214440D02*
Y-209790D01*
G01X1045866Y-200415D02*
Y77795D01*
G01X1068504Y204724D02*
G02X1046850I-10827J0D01*
G02X1068504I10827J0D01*
G01X1060303Y1369350D02*
G02X1045618I-7343J0D01*
G02X1060303I7343J0D01*
G01X1052116Y-299690D02*
Y-295040D01*
G01Y-209790D02*
Y-214440D01*
G01X1057659Y-161420D02*
Y194724D01*
G01X1101520Y-161420D02*
X1057659D01*
G01X1113760Y605378D02*
G02X1074390I-19685J0D01*
G02X1113760I19685J0D01*
G01X1094076Y-142160D02*
Y595378D01*
G01X1138520Y-142160D02*
X1094076D01*
G01X1108550Y-301230D02*
Y-296580D01*
G01X1096050Y-301230D02*
X1108550D01*
G01X1096050Y-296580D02*
Y-301230D01*
G01X1108550Y-211330D02*
Y-215980D01*
G01X1096050Y-211330D02*
X1108550D01*
G01X1096050Y-215980D02*
Y-211330D01*
G01X1101729Y-201955D02*
X1101520Y-161420D01*
G01X1132270Y-289640D02*
X1144770D01*
G01X1132270Y-284990D02*
Y-289640D01*
G01Y-212140D02*
X1144770D01*
G01X1132270Y-216790D02*
Y-212140D01*
G01X1138520Y-202765D02*
Y-142160D01*
G01X1133870Y294335D02*
G02X1173240I19685J0D01*
G01Y260083D01*
G02X1133870I-19685J0D01*
G01Y294335D01*
G01X1154803Y1515236D02*
G02X1137087I-8858J0D01*
G02X1154803I8858J0D01*
G01X1144770Y-289640D02*
Y-284990D01*
G01Y-212140D02*
Y-216790D01*
G01X1153555Y-113640D02*
Y284335D01*
G01X1197090Y-113640D02*
X1153555D01*
G01X1166732Y1714961D02*
G02X1144685I-11024J0D01*
G02X1166732I11023J0D01*
G01X1155709Y-101310D02*
Y1704961D01*
G01X1227920Y-101310D02*
X1155709D01*
G01X1180394Y1626654D02*
G02X1162677I-8859J0D01*
G02X1180394I8859J0D01*
G01X1177480Y257100D02*
X1190590Y240530D01*
G01X1192380Y-263360D02*
X1204880D01*
G01X1192380Y-258710D02*
Y-263360D01*
G01Y-210660D02*
X1204880D01*
G01X1192380Y-215310D02*
Y-210660D01*
G01X1197842Y-201285D02*
X1197090Y-113640D01*
G01X1190590Y240530D02*
X1185070Y245089D01*
G01X1187423Y246950D02*
X1190590Y240530D01*
G01X1185070Y245089D02*
X1187423Y246950D01*
G01X1204880Y-263360D02*
Y-258710D01*
G01Y-210660D02*
Y-215310D01*
G01X1221670Y-302000D02*
X1234170D01*
G01X1221670Y-297350D02*
Y-302000D01*
G01Y-212100D02*
X1234170D01*
G01X1221670Y-216750D02*
Y-212100D01*
G01X1227920Y-202725D02*
Y-101310D01*
G01X1234170Y-302000D02*
Y-297350D01*
G01Y-212100D02*
Y-216750D01*
G01X1258937Y1019252D02*
G02X1243189I-7874J0D01*
G02X1258937I7874J0D01*
G01X1257154Y1357539D02*
G02X1242469I-7343J0D01*
G02X1257154I7343J0D01*
G01X1297628Y1668212D02*
X1234578D01*
Y1736912D01*
X1297628D01*
Y1668212D01*
G01X1251063Y-167590D02*
Y1009252D01*
G01X1282640Y-167590D02*
X1251063D01*
G01X1271260Y-151400D02*
Y621890D01*
G01X1307300Y-151400D02*
X1271260D01*
G01X1282283Y631890D02*
G02X1260236I-11023J0D01*
G02X1282283I11023J0D01*
G01X1261450Y1745300D02*
X1410580Y1919480D01*
G01X1277160Y-304310D02*
X1289660D01*
G01X1277160Y-299660D02*
Y-304310D01*
G01Y-214410D02*
X1289660D01*
G01X1277160Y-219060D02*
Y-214410D01*
G01X1282835Y-205035D02*
X1282640Y-167590D01*
G01X1304213Y838543D02*
G02X1288465I-7874J0D01*
G02X1304213I7874J0D01*
G01Y1199961D02*
G02X1288465I-7874J0D01*
G02X1304213I7874J0D01*
G01X1289660Y-304310D02*
Y-299660D01*
G01X1302590Y-291180D02*
X1315090D01*
G01X1302590Y-286530D02*
Y-291180D01*
G01X1289660Y-214410D02*
Y-219060D01*
G01X1302590Y-213680D02*
X1315090D01*
G01X1302590Y-218330D02*
Y-213680D01*
G01X1296339Y-138300D02*
Y1189961D01*
G01X1338130Y-138300D02*
X1296339D01*
G01X1364558Y1668212D02*
X1301508D01*
Y1736912D01*
X1364558D01*
Y1668212D01*
G01X1315090Y-291180D02*
Y-286530D01*
G01Y-213680D02*
Y-218330D01*
G01X1307818Y-204305D02*
X1307300Y-151400D01*
G01X1331880Y-304310D02*
X1344380D01*
G01X1331880Y-299660D02*
Y-304310D01*
G01Y-214410D02*
X1344380D01*
G01X1331880Y-219060D02*
Y-214410D01*
G01X1344380Y-304310D02*
Y-299660D01*
G01Y-214410D02*
Y-219060D01*
G01X1338130Y-205035D02*
Y-138300D01*
G01X1336590Y1743370D02*
X1434080Y1913310D01*
G01X1377626Y582303D02*
G02X1362941I-7343J0D01*
G02X1377626I7342J0D01*
G01X1376533Y-302770D02*
Y-298120D01*
G01X1364033Y-302770D02*
X1376533D01*
G01X1364033Y-298120D02*
Y-302770D01*
G01X1376533Y-212870D02*
Y-217520D01*
G01X1364033Y-212870D02*
X1376533D01*
G01X1364033Y-217520D02*
Y-212870D01*
G01X1370283Y-203495D02*
Y572303D01*
G01X1410580Y1919480D02*
X1407167Y1913187D01*
G01X1404888Y1915138D02*
X1410580Y1919480D01*
G01X1407167Y1913187D02*
X1404888Y1915138D01*
G01X1416437Y-189940D02*
Y1708465D01*
G01X1437550Y-189940D02*
X1416437D01*
G01X1424476Y1339823D02*
G02X1409791I-7343J0D01*
G02X1424476I7342J0D01*
G01X1410187Y1698268D02*
G02X1422687I6250J0D01*
G02X1410187I-6250J0D01*
G01X1433610Y-308170D02*
X1446110D01*
G01X1433610Y-303520D02*
Y-308170D01*
G01Y-222920D02*
Y-218270D01*
G01X1437888Y-208895D02*
X1437550Y-189940D01*
G01X1433610Y-218270D02*
X1446110D01*
G01X1434080Y1913310D02*
X1431898Y1906492D01*
G01X1429296Y1907985D02*
X1434080Y1913310D01*
G01X1431898Y1906492D02*
X1429296Y1907985D01*
G01X1446110Y-308170D02*
Y-303520D01*
G01Y-218270D02*
Y-222920D01*
G01X1472829Y1714961D02*
G02X1450782I-11024J0D01*
G02X1472829I11023J0D01*
G01X1452451Y1908222D02*
X1451040Y1915240D01*
G01X1455203Y1909416D02*
X1452451Y1908222D01*
G01X1451040Y1915240D02*
X1455203Y1909416D01*
G01X1524640Y1745680D02*
X1451040Y1915240D01*
G01X1455556Y-296570D02*
X1468056D01*
G01X1455556Y-291920D02*
Y-296570D01*
G01Y-223720D02*
Y-219070D01*
G01X1461806Y-209695D02*
Y1704961D01*
G01X1455556Y-219070D02*
X1468056D01*
G01Y-296570D02*
Y-291920D01*
G01Y-219070D02*
Y-223720D01*
G01X1586680Y1744140D02*
X1471080Y1926800D01*
G01D02*
X1476091Y1921687D01*
G01X1473556Y1920083D02*
X1471080Y1926800D01*
G01X1476091Y1921687D02*
X1473556Y1920083D01*
G01X1493356Y-295800D02*
X1505856D01*
G01X1493356Y-291150D02*
Y-295800D01*
G01Y-222950D02*
Y-218300D01*
G01D02*
X1505856D01*
G01X1510630Y87795D02*
G02X1488583I-11023J0D01*
G02X1510630I11024J0D01*
G01X1505856Y-295800D02*
Y-291150D01*
G01Y-218300D02*
Y-222950D01*
G01X1499606Y-208925D02*
Y77795D01*
G01X1561802Y1668212D02*
X1498752D01*
Y1736912D01*
X1561802D01*
Y1668212D01*
G01X1527302Y-307400D02*
X1539802D01*
G01X1527302Y-302750D02*
Y-307400D01*
G01Y-217500D02*
X1539802D01*
G01X1527302Y-222150D02*
Y-217500D01*
G01X1540894Y682343D02*
G02X1526209I-7343J0D01*
G02X1540894I7342J0D01*
G01X1539802Y-307400D02*
Y-302750D01*
G01X1533552Y-208125D02*
Y672342D01*
G01X1539802Y-217500D02*
Y-222150D01*
G01X1537275Y-185310D02*
Y1189922D01*
G01X1563950Y-185310D02*
X1537275D01*
G01X1545157Y838543D02*
G02X1529409I-7874J0D01*
G02X1545157I7874J0D01*
G01Y1199961D02*
G02X1529409I-7874J0D01*
G02X1545157I7874J0D01*
G01X1556160Y-305850D02*
X1568660D01*
G01X1556160Y-301200D02*
Y-305850D01*
G01Y-215950D02*
X1568660D01*
G01X1556160Y-220600D02*
Y-215950D01*
G01X1568660Y-305850D02*
Y-301200D01*
G01Y-215950D02*
Y-220600D01*
G01X1563702Y-206575D02*
X1563950Y-185310D01*
G01X1628732Y1668212D02*
X1565682D01*
Y1736912D01*
X1628732D01*
Y1668212D01*
G01X1576301Y-307400D02*
X1588801D01*
G01X1576301Y-302750D02*
Y-307400D01*
G01X1582551Y-208125D02*
Y1009213D01*
G01X1576301Y-217500D02*
X1588801D01*
G01X1576301Y-222150D02*
Y-217500D01*
G01X1590433Y1019252D02*
G02X1574685I-7874J0D01*
G02X1590433I7874J0D01*
G01X1588801Y-307400D02*
Y-302750D01*
G01Y-217500D02*
Y-222150D01*
G01X1623482Y-308170D02*
X1635982D01*
G01X1623482Y-303520D02*
Y-308170D01*
G01Y-222920D02*
Y-218270D01*
G01X1629732Y-208895D02*
Y1373523D01*
G01X1623482Y-218270D02*
X1635982D01*
G01X1637075Y1383524D02*
G02X1622390I-7343J0D01*
G02X1637075I7343J0D01*
G01X1635982Y-308170D02*
Y-303520D01*
G01Y-218270D02*
Y-222920D01*
G01X1658640Y-306630D02*
X1671140D01*
G01X1658640Y-301980D02*
Y-306630D01*
G01Y-216730D02*
X1671140D01*
G01X1658640Y-221380D02*
Y-216730D01*
G01X1660642Y294362D02*
G02X1700012I19685J0D01*
G01Y260110D01*
G02X1660642I-19685J0D01*
G01Y294362D01*
G01X1700012Y277236D02*
X1660642D01*
G01X1672232Y642972D02*
G02X1657547I-7343J0D01*
G02X1672232I7342J0D01*
G01X1671140Y-306630D02*
Y-301980D01*
G01Y-216730D02*
Y-221380D01*
G01X1664890Y-207355D02*
Y632972D01*
G01X1689961Y1626654D02*
G02X1672244I-8859J0D01*
G02X1689961I8859J0D01*
G01X1704080Y258450D02*
X1714680Y239180D01*
G01X1715551Y1515236D02*
G02X1697835I-8858J0D01*
G02X1715551I8858J0D01*
G01X1714680Y239180D02*
X1709992Y244590D01*
G01X1712621Y246036D02*
X1714680Y239180D01*
G01X1709992Y244590D02*
X1712621Y246036D01*
G01X1759429Y605413D02*
G02X1720059I-19685J0D01*
G02X1759429I19685J0D01*
G01X1721673Y1570984D02*
G02X1706988I-7342J0D01*
G02X1721673I7343J0D01*
G01X1731110Y-290440D02*
X1743610D01*
G01X1731110Y-285790D02*
Y-290440D01*
G01Y-200540D02*
X1743610D01*
G01X1731110Y-205190D02*
Y-200540D01*
G01X1747311Y1383524D02*
G02X1732626I-7343J0D01*
G02X1747311I7343J0D01*
G01X1743610Y-290440D02*
Y-285790D01*
G01X1739968Y-194950D02*
Y1373527D01*
G01X1743610Y-200540D02*
Y-205190D01*
G01X1755770Y-290060D02*
X1768270D01*
G01X1755770Y-285410D02*
Y-290060D01*
G01X1761575Y-197650D02*
Y149134D01*
G01X1755770Y-200160D02*
X1768270D01*
G01X1755770Y-204810D02*
Y-200160D01*
G01X1768917Y159134D02*
G02X1754232I-7342J0D01*
G02X1768917I7343J0D01*
G01X1773031Y1714961D02*
G02X1760827I-6102J0D01*
G02X1773031I6102J0D01*
G01X1779660Y-283080D02*
X1792160D01*
G01X1779660Y-278430D02*
Y-283080D01*
G01X1768270Y-290060D02*
Y-285410D01*
G01X1779660Y-210230D02*
Y-205580D01*
G01D02*
X1792160D01*
G01X1768270Y-200160D02*
Y-204810D01*
G01X1766929Y-190710D02*
Y1704960D01*
G01X1783600Y-190710D02*
X1766929D01*
G01X1792160Y-283080D02*
Y-278430D01*
G01Y-205580D02*
Y-210230D01*
G01X1783716Y-196205D02*
X1783600Y-190710D01*
G01X1817323Y1714961D02*
G02X1795276I-11023J0D01*
G02X1817323I11024J0D01*
G01X1801630Y-280770D02*
X1814130D01*
G01X1801630Y-276120D02*
Y-280770D01*
G01Y-207920D02*
Y-203270D01*
G01X1806367Y-193895D02*
X1806298Y-189170D01*
G01X1801630Y-203270D02*
X1814130D01*
G01X1806298Y-189170D02*
Y1704961D01*
G01X1827795Y631890D02*
G02X1805748I-11023J0D01*
G02X1827795I11024J0D01*
G01Y1368898D02*
G02X1805748I-11023J0D01*
G02X1827795I11024J0D01*
G01X1825520Y-289670D02*
X1838020D01*
G01X1825520Y-285020D02*
Y-289670D01*
G01X1814130Y-280770D02*
Y-276120D01*
G01Y-203270D02*
Y-207920D01*
G01X1825520Y-199770D02*
X1838020D01*
G01X1825520Y-204420D02*
Y-199770D01*
G01X1816772Y-186090D02*
Y1358897D01*
G01X1831380Y-186090D02*
X1816772D01*
G01X1840945Y87795D02*
G02X1818898I-11023J0D01*
G02X1840945I11023J0D01*
G01X1823819Y133465D02*
G02X1836024I6103J0D01*
G01Y127165D01*
G02X1823819I-6103J0D01*
G01Y133465D01*
G01X1831909Y1570984D02*
G02X1817224I-7342J0D01*
G02X1831909I7343J0D01*
G01X1838020Y-289670D02*
Y-285020D01*
G01Y-199770D02*
Y-204420D01*
G01X1831395Y-190395D02*
X1831380Y-186090D01*
G01X1829921Y-165280D02*
Y120314D01*
G01X1882250Y-165280D02*
X1829921D01*
G01X1838150Y-156410D02*
Y191929D01*
G01X1907680Y-156410D02*
X1838150D01*
G01X1845492Y201929D02*
G02X1830807I-7342J0D01*
G02X1845492I7343J0D01*
G01X1850480Y1778618D02*
X1857480Y1780118D01*
X1850480Y1781618D01*
Y1778618D01*
G01X1867480Y0D02*
X2127480D01*
G01X1867480Y1740118D02*
X2127480D01*
G01X1857480Y1750118D02*
Y1790118D01*
G01X1874460Y-276340D02*
X1886960D01*
G01X1874460Y-271690D02*
Y-276340D01*
G01Y-198840D02*
X1886960D01*
G01X1874460Y-203490D02*
Y-198840D01*
G01X1881960Y-189465D02*
X1882250Y-165280D01*
G01X1886960Y-276340D02*
Y-271690D01*
G01Y-198840D02*
Y-203490D01*
G01X1914700Y-287940D02*
Y-283290D01*
G01X1902200Y-287940D02*
X1914700D01*
G01X1902200Y-283290D02*
Y-287940D01*
G01X1914700Y-198040D02*
Y-202690D01*
G01X1902200Y-198040D02*
X1914700D01*
G01X1902200Y-202690D02*
Y-198040D01*
G01X1907854Y-188665D02*
X1907680Y-156410D01*
G01X2101574Y10236D02*
Y-48819D01*
X2062204D01*
Y10236D01*
X2101574D01*
G01X2091406Y9488D02*
X2094506D01*
Y8568D01*
X2094351Y8261D01*
X2093989Y8031D01*
X2093576Y7954D01*
X2093163Y8031D01*
X2092853Y8223D01*
X2092698Y8568D01*
Y9488D01*
G01X2094248Y4778D02*
X2094403Y5008D01*
X2094506Y5276D01*
Y5583D01*
X2094351Y5928D01*
X2094093Y6196D01*
X2093783Y6388D01*
X2093266Y6541D01*
X2092801Y6579D01*
X2092336Y6503D01*
X2092026Y6388D01*
X2091716Y6158D01*
X2091509Y5889D01*
X2091406Y5621D01*
Y5353D01*
X2091509Y5084D01*
X2091664Y4854D01*
X2091871Y4663D01*
G01X2093059Y2214D02*
X2093214Y2061D01*
X2093473Y1946D01*
X2093834Y1869D01*
X2094144Y1946D01*
X2094351Y2099D01*
X2094506Y2368D01*
Y3403D01*
X2091406D01*
Y2138D01*
X2091613Y1869D01*
X2091923Y1716D01*
X2092284Y1639D01*
X2092646Y1716D01*
X2092956Y1946D01*
X2093059Y2214D01*
Y3403D01*
G01X2094506Y-2721D02*
X2091406Y-3679D01*
X2094506Y-4637D01*
G01X2091406Y-7546D02*
Y-6012D01*
X2094506D01*
Y-7546D01*
G01X2093008Y-6932D02*
Y-6012D01*
G01X2091406Y-8997D02*
X2094506D01*
X2091406Y-10761D01*
X2094506D01*
G01X2091406Y-12136D02*
X2094506D01*
Y-12902D01*
X2094351Y-13209D01*
X2094144Y-13439D01*
X2093834Y-13631D01*
X2093473Y-13784D01*
X2092956Y-13822D01*
X2092439Y-13784D01*
X2092078Y-13631D01*
X2091768Y-13439D01*
X2091561Y-13209D01*
X2091406Y-12902D01*
Y-12136D01*
G01Y-16079D02*
X2091458Y-15772D01*
X2091664Y-15504D01*
X2091974Y-15274D01*
X2092336Y-15121D01*
X2092749Y-15044D01*
X2093163D01*
X2093576Y-15121D01*
X2093938Y-15274D01*
X2094248Y-15504D01*
X2094454Y-15772D01*
X2094506Y-16079D01*
X2094454Y-16386D01*
X2094248Y-16654D01*
X2093938Y-16884D01*
X2093576Y-17037D01*
X2093163Y-17114D01*
X2092749D01*
X2092336Y-17037D01*
X2091974Y-16884D01*
X2091664Y-16654D01*
X2091458Y-16386D01*
X2091406Y-16079D01*
G01Y-18412D02*
X2094506D01*
Y-19371D01*
X2094351Y-19677D01*
X2094144Y-19869D01*
X2093731Y-19946D01*
X2093318Y-19869D01*
X2093059Y-19639D01*
X2092904Y-19371D01*
Y-18412D01*
G01Y-19371D02*
X2091406Y-19946D01*
G01X2089506Y2188D02*
X2086406D01*
Y654D01*
G01Y-1679D02*
X2086458Y-1372D01*
X2086664Y-1104D01*
X2086974Y-874D01*
X2087336Y-721D01*
X2087749Y-644D01*
X2088163D01*
X2088576Y-721D01*
X2088938Y-874D01*
X2089248Y-1104D01*
X2089454Y-1372D01*
X2089506Y-1679D01*
X2089454Y-1986D01*
X2089248Y-2254D01*
X2088938Y-2484D01*
X2088576Y-2637D01*
X2088163Y-2714D01*
X2087749D01*
X2087336Y-2637D01*
X2086974Y-2484D01*
X2086664Y-2254D01*
X2086458Y-1986D01*
X2086406Y-1679D01*
G01X2087956Y-5009D02*
Y-5776D01*
X2087026D01*
X2086716Y-5546D01*
X2086509Y-5277D01*
X2086406Y-4894D01*
X2086509Y-4511D01*
X2086716Y-4242D01*
X2087026Y-4012D01*
X2087388Y-3859D01*
X2087801Y-3782D01*
X2088163D01*
X2088473Y-3859D01*
X2088834Y-4012D01*
X2089144Y-4242D01*
X2089351Y-4472D01*
X2089506Y-4779D01*
Y-5047D01*
X2089403Y-5354D01*
X2089196Y-5584D01*
G01X2086406Y-7879D02*
X2086458Y-7572D01*
X2086664Y-7304D01*
X2086974Y-7074D01*
X2087336Y-6921D01*
X2087749Y-6844D01*
X2088163D01*
X2088576Y-6921D01*
X2088938Y-7074D01*
X2089248Y-7304D01*
X2089454Y-7572D01*
X2089506Y-7879D01*
X2089454Y-8186D01*
X2089248Y-8454D01*
X2088938Y-8684D01*
X2088576Y-8837D01*
X2088163Y-8914D01*
X2087749D01*
X2087336Y-8837D01*
X2086974Y-8684D01*
X2086664Y-8454D01*
X2086458Y-8186D01*
X2086406Y-7879D01*
G01X2117480Y872334D02*
Y0D01*
G01X2115980Y7000D02*
X2117480Y0D01*
X2118980Y7000D01*
X2115980D01*
G01X2136230Y889909D02*
Y885259D01*
X2123730D01*
Y889909D01*
G01X2136230Y970509D02*
Y975159D01*
X2123730D01*
Y970509D01*
G01X2117480Y987784D02*
Y1740118D01*
G01X2118980Y1733118D02*
X2117480Y1740118D01*
X2115980Y1733118D01*
X2118980D01*
G01X2347870Y-643344D02*
Y1618356D01*
X3246870D01*
Y-643344D01*
X2347870D01*
G01Y-584244D02*
X3246870D01*
G01X2347870Y-525144D02*
X3246870D01*
G01X2347870Y-466044D02*
X3246870D01*
G01X2347870Y-406944D02*
X3246870D01*
G01X2347870Y-347844D02*
X3246870D01*
G01X2347870Y-288744D02*
X3246870D01*
G01X2347870Y-229644D02*
X3246870D01*
G01X2347870Y-170544D02*
X3246870D01*
G01X2347870Y-111444D02*
X3246870D01*
G01X2347870Y-52344D02*
X3246870D01*
G01X2347870Y6756D02*
X3246870D01*
G01X2347870Y65856D02*
X3246870D01*
G01X2347870Y124956D02*
X3246870D01*
G01X2347870Y184056D02*
X3246870D01*
G01X2347870Y243156D02*
X3246870D01*
G01X2347870Y302256D02*
X3246870D01*
G01X2347870Y361356D02*
X3246870D01*
G01X2347870Y420456D02*
X3246870D01*
G01X2347870Y479556D02*
X3246870D01*
G01X2347870Y538656D02*
X3246870D01*
G01X2347870Y597756D02*
X3246870D01*
G01X2347870Y656856D02*
X3246870D01*
G01X2347870Y715956D02*
X3246870D01*
G01X2347870Y775056D02*
X3246870D01*
G01X2347870Y834156D02*
X3246870D01*
G01X2347870Y893256D02*
X3246870D01*
G01X2350826Y946823D02*
Y897253D01*
X4204596D01*
Y946823D01*
X2350826D01*
G01X2347870Y952356D02*
X3246870D01*
G01X2347870Y1011456D02*
X3246870D01*
G01X2347870Y1070556D02*
X3246870D01*
G01X2347870Y1129656D02*
X3246870D01*
G01X2347870Y1188756D02*
X3246870D01*
G01X2352490Y1243920D02*
Y1194350D01*
X4206260D01*
Y1243920D01*
X2352490D01*
G01Y1303020D02*
Y1253450D01*
X4206260D01*
Y1303020D01*
X2352490D01*
G01X2347870Y1247856D02*
X3246870D01*
G01X2347870Y1306956D02*
X3246870D01*
G01X2347870Y1366056D02*
X3246870D01*
G01X2347870Y1425156D02*
X3246870D01*
G01X2347870Y1484256D02*
X3246870D01*
G01X2347870Y1543356D02*
X3246870D01*
G01X2347870Y1568356D02*
X3246870D01*
G01X2347870Y1593356D02*
X3246870D01*
G01X2437770Y1568356D02*
Y-643344D01*
G01X2639270Y1568356D02*
Y-643344D01*
G01X2840770Y1568356D02*
Y-643344D01*
G01X3042270Y1568356D02*
Y-643344D01*
G01X3146319Y2017555D02*
X3133819D01*
X3136319Y2015695D01*
G01X3146319D02*
Y2019415D01*
G01X3133819Y2029955D02*
X3134236Y2028715D01*
X3135277Y2027785D01*
X3136527Y2027165D01*
X3138194Y2026700D01*
X3140069Y2026545D01*
X3141944Y2026700D01*
X3143611Y2027165D01*
X3144861Y2027785D01*
X3145902Y2028715D01*
X3146319Y2029955D01*
X3145902Y2031195D01*
X3144861Y2032125D01*
X3143611Y2032745D01*
X3141944Y2033210D01*
X3140069Y2033365D01*
X3138194Y2033210D01*
X3136527Y2032745D01*
X3135277Y2032125D01*
X3134236Y2031195D01*
X3133819Y2029955D01*
G01X3146319Y2038325D02*
X3133819D01*
X3144236Y2042355D01*
X3133819Y2046385D01*
X3146319D01*
G01Y2050725D02*
X3133819D01*
X3144236Y2054755D01*
X3133819Y2058785D01*
X3146319D01*
G01X3221408Y2022375D02*
X3147304D01*
G01X3220554Y2061745D02*
X3147304D01*
G01X3144548Y2227923D02*
Y2235923D01*
X3143348Y2234323D01*
G01Y2227923D02*
X3145748D01*
G01X3152548D02*
Y2235923D01*
X3151348Y2234323D01*
G01Y2227923D02*
X3153748D01*
G01X3160548Y2227656D02*
X3160348Y2227790D01*
Y2228056D01*
X3160548Y2228190D01*
X3160748Y2228056D01*
Y2227790D01*
X3160548Y2227656D01*
G01X3167348Y2235923D02*
X3169748D01*
G01X3168548D02*
Y2227923D01*
G01X3167348D02*
X3169748D01*
G01X3174848D02*
Y2233256D01*
G01Y2231923D02*
X3175248Y2232590D01*
X3175848Y2233123D01*
X3176648Y2233256D01*
X3177348Y2233123D01*
X3177948Y2232590D01*
X3178248Y2231656D01*
Y2227923D01*
G01X3193348Y2232190D02*
X3193748Y2232590D01*
X3194048Y2233256D01*
X3194248Y2234190D01*
X3194048Y2234990D01*
X3193648Y2235523D01*
X3192948Y2235923D01*
X3190248D01*
Y2227923D01*
X3193548D01*
X3194248Y2228456D01*
X3194648Y2229256D01*
X3194848Y2230190D01*
X3194648Y2231123D01*
X3194048Y2231923D01*
X3193348Y2232190D01*
X3190248D01*
G01X3201148Y2231923D02*
X3203148D01*
Y2229523D01*
X3202548Y2228723D01*
X3201848Y2228190D01*
X3200848Y2227923D01*
X3199848Y2228190D01*
X3199148Y2228723D01*
X3198548Y2229523D01*
X3198148Y2230456D01*
X3197948Y2231523D01*
Y2232456D01*
X3198148Y2233256D01*
X3198548Y2234190D01*
X3199148Y2234990D01*
X3199748Y2235523D01*
X3200548Y2235923D01*
X3201248D01*
X3202048Y2235656D01*
X3202648Y2235123D01*
G01X3206048Y2227923D02*
X3208548Y2235923D01*
X3211048Y2227923D01*
G01X3210148Y2230723D02*
X3206948D01*
G01X3226348Y2227923D02*
Y2233256D01*
G01Y2232323D02*
X3225948Y2232856D01*
X3225348Y2233123D01*
X3224648Y2233256D01*
X3223948Y2232990D01*
X3223348Y2232456D01*
X3222948Y2231656D01*
X3222748Y2230590D01*
X3222948Y2229523D01*
X3223348Y2228723D01*
X3223948Y2228190D01*
X3224648Y2227923D01*
X3225348Y2228056D01*
X3225948Y2228456D01*
X3226348Y2228989D01*
G01X3231148Y2227923D02*
Y2233256D01*
G01Y2232190D02*
X3231648Y2232723D01*
X3232148Y2233123D01*
X3232848Y2233256D01*
X3233348Y2233123D01*
X3233948Y2232723D01*
G01X3239048Y2231523D02*
X3242248D01*
X3241948Y2232456D01*
X3241448Y2232990D01*
X3240748Y2233256D01*
X3240048Y2233123D01*
X3239448Y2232723D01*
X3239048Y2231790D01*
X3238848Y2230989D01*
Y2230190D01*
X3239048Y2229390D01*
X3239548Y2228590D01*
X3240148Y2228056D01*
X3240848Y2227923D01*
X3241548Y2228190D01*
X3242248Y2228989D01*
G01X3250348Y2227923D02*
Y2233256D01*
G01Y2232323D02*
X3249948Y2232856D01*
X3249348Y2233123D01*
X3248648Y2233256D01*
X3247948Y2232990D01*
X3247348Y2232456D01*
X3246948Y2231656D01*
X3246748Y2230590D01*
X3246948Y2229523D01*
X3247348Y2228723D01*
X3247948Y2228190D01*
X3248648Y2227923D01*
X3249348Y2228056D01*
X3249948Y2228456D01*
X3250348Y2228989D01*
G01X3256348Y2226456D02*
X3256748Y2228190D01*
G01X3270748Y2227923D02*
Y2235923D01*
G01Y2231923D02*
X3271248Y2232723D01*
X3271848Y2233123D01*
X3272448Y2233256D01*
X3273348Y2232990D01*
X3273948Y2232456D01*
X3274348Y2231523D01*
Y2230456D01*
X3274148Y2229390D01*
X3273748Y2228590D01*
X3273048Y2228056D01*
X3272448Y2227923D01*
X3271848Y2228056D01*
X3271248Y2228456D01*
X3270748Y2229123D01*
G01X3282348Y2227923D02*
Y2233256D01*
G01Y2232323D02*
X3281948Y2232856D01*
X3281348Y2233123D01*
X3280648Y2233256D01*
X3279948Y2232990D01*
X3279348Y2232456D01*
X3278948Y2231656D01*
X3278748Y2230590D01*
X3278948Y2229523D01*
X3279348Y2228723D01*
X3279948Y2228190D01*
X3280648Y2227923D01*
X3281348Y2228056D01*
X3281948Y2228456D01*
X3282348Y2228989D01*
G01X3290148Y2232590D02*
X3289448Y2233123D01*
X3288848Y2233256D01*
X3288048Y2232990D01*
X3287448Y2232456D01*
X3287048Y2231523D01*
X3286948Y2230590D01*
X3287048Y2229656D01*
X3287448Y2228856D01*
X3288048Y2228190D01*
X3288848Y2227923D01*
X3289548Y2228190D01*
X3290148Y2228723D01*
G01X3294848Y2227923D02*
Y2235923D01*
G01X3298048Y2233256D02*
X3294848Y2230190D01*
G01X3296148Y2231390D02*
X3298248Y2227923D01*
G01X3306348Y2235923D02*
Y2227923D01*
G01Y2229123D02*
X3305948Y2228456D01*
X3305348Y2228056D01*
X3304648Y2227923D01*
X3303848Y2228190D01*
X3303248Y2228856D01*
X3302848Y2229656D01*
X3302748Y2230590D01*
X3302848Y2231523D01*
X3303248Y2232323D01*
X3303848Y2232990D01*
X3304648Y2233256D01*
X3305348Y2233123D01*
X3305848Y2232856D01*
X3306348Y2232323D01*
G01X3311148Y2227923D02*
Y2233256D01*
G01Y2232190D02*
X3311648Y2232723D01*
X3312148Y2233123D01*
X3312848Y2233256D01*
X3313348Y2233123D01*
X3313948Y2232723D01*
G01X3320548Y2233256D02*
Y2227923D01*
G01Y2235390D02*
X3320348Y2235523D01*
Y2235790D01*
X3320548Y2235923D01*
X3320748Y2235790D01*
Y2235523D01*
X3320548Y2235390D01*
G01X3328548Y2227923D02*
Y2235923D01*
G01X3336548Y2227923D02*
Y2235923D01*
G01X3351048Y2228856D02*
X3351548Y2228323D01*
X3352248Y2227923D01*
X3352848D01*
X3353448Y2228190D01*
X3353848Y2228590D01*
X3354048Y2229123D01*
X3353948Y2229923D01*
X3353548Y2230323D01*
X3351748Y2231123D01*
X3351348Y2232056D01*
X3351548Y2232723D01*
X3351948Y2233123D01*
X3352548Y2233256D01*
X3353148Y2233123D01*
X3353748Y2232723D01*
G01X3360548Y2233256D02*
Y2227923D01*
G01Y2235390D02*
X3360348Y2235523D01*
Y2235790D01*
X3360548Y2235923D01*
X3360748Y2235790D01*
Y2235523D01*
X3360548Y2235390D01*
G01X3367048Y2233256D02*
X3370048D01*
X3367048Y2227923D01*
X3370048D01*
G01X3375048Y2231523D02*
X3378248D01*
X3377948Y2232456D01*
X3377448Y2232990D01*
X3376748Y2233256D01*
X3376048Y2233123D01*
X3375448Y2232723D01*
X3375048Y2231790D01*
X3374848Y2230989D01*
Y2230190D01*
X3375048Y2229390D01*
X3375548Y2228590D01*
X3376148Y2228056D01*
X3376848Y2227923D01*
X3377548Y2228190D01*
X3378248Y2228989D01*
G01X3391048Y2228856D02*
X3391548Y2228323D01*
X3392248Y2227923D01*
X3392848D01*
X3393448Y2228190D01*
X3393848Y2228590D01*
X3394048Y2229123D01*
X3393948Y2229923D01*
X3393548Y2230323D01*
X3391748Y2231123D01*
X3391348Y2232056D01*
X3391548Y2232723D01*
X3391948Y2233123D01*
X3392548Y2233256D01*
X3393148Y2233123D01*
X3393748Y2232723D01*
G01X3398848Y2227923D02*
Y2235923D01*
G01Y2232056D02*
X3399348Y2232723D01*
X3399848Y2233123D01*
X3400648Y2233256D01*
X3401248Y2233123D01*
X3401948Y2232590D01*
X3402248Y2231790D01*
Y2227923D01*
G01X3408548D02*
X3407948Y2228056D01*
X3407348Y2228590D01*
X3406948Y2229523D01*
X3406748Y2230590D01*
X3406948Y2231656D01*
X3407348Y2232590D01*
X3407948Y2233123D01*
X3408548Y2233256D01*
X3409148Y2233123D01*
X3409748Y2232590D01*
X3410148Y2231656D01*
X3410248Y2230590D01*
X3410148Y2229523D01*
X3409748Y2228590D01*
X3409148Y2228056D01*
X3408548Y2227923D01*
G01X3414848Y2233256D02*
Y2229523D01*
X3415248Y2228590D01*
X3415848Y2228056D01*
X3416548Y2227923D01*
X3417248Y2228056D01*
X3417848Y2228590D01*
X3418248Y2229523D01*
G01Y2227923D02*
Y2233256D01*
G01X3424548Y2227923D02*
Y2235923D01*
G01X3434348D02*
Y2227923D01*
G01Y2229123D02*
X3433948Y2228456D01*
X3433348Y2228056D01*
X3432648Y2227923D01*
X3431848Y2228190D01*
X3431248Y2228856D01*
X3430848Y2229656D01*
X3430748Y2230590D01*
X3430848Y2231523D01*
X3431248Y2232323D01*
X3431848Y2232990D01*
X3432648Y2233256D01*
X3433348Y2233123D01*
X3433848Y2232856D01*
X3434348Y2232323D01*
G01X3446748Y2227923D02*
Y2235923D01*
G01Y2231923D02*
X3447248Y2232723D01*
X3447848Y2233123D01*
X3448448Y2233256D01*
X3449348Y2232990D01*
X3449948Y2232456D01*
X3450348Y2231523D01*
Y2230456D01*
X3450148Y2229390D01*
X3449748Y2228590D01*
X3449048Y2228056D01*
X3448448Y2227923D01*
X3447848Y2228056D01*
X3447248Y2228456D01*
X3446748Y2229123D01*
G01X3455048Y2231523D02*
X3458248D01*
X3457948Y2232456D01*
X3457448Y2232990D01*
X3456748Y2233256D01*
X3456048Y2233123D01*
X3455448Y2232723D01*
X3455048Y2231790D01*
X3454848Y2230989D01*
Y2230190D01*
X3455048Y2229390D01*
X3455548Y2228590D01*
X3456148Y2228056D01*
X3456848Y2227923D01*
X3457548Y2228190D01*
X3458248Y2228989D01*
G01X3472048Y2225256D02*
X3471048Y2226590D01*
X3470548Y2227923D01*
Y2233256D01*
X3471048Y2234590D01*
X3472048Y2235923D01*
G01X3478348Y2227923D02*
Y2235923D01*
X3480348D01*
X3481148Y2235523D01*
X3481748Y2234990D01*
X3482248Y2234190D01*
X3482648Y2233256D01*
X3482748Y2231923D01*
X3482648Y2230590D01*
X3482248Y2229656D01*
X3481748Y2228856D01*
X3481148Y2228323D01*
X3480348Y2227923D01*
X3478348D01*
G01X3495448Y2230590D02*
X3497848D01*
G01X3496548Y2232323D02*
Y2228856D01*
G01X3512348Y2227923D02*
X3512548Y2229656D01*
X3512848Y2231123D01*
X3513248Y2232456D01*
X3513748Y2233923D01*
X3514548Y2235923D01*
X3510548D01*
G01X3521048Y2225256D02*
X3522048Y2226590D01*
X3522548Y2227923D01*
Y2233256D01*
X3522048Y2234590D01*
X3521048Y2235923D01*
G01X3533548Y2227923D02*
Y2233256D01*
G01Y2231790D02*
X3533848Y2232456D01*
X3534348Y2232990D01*
X3535048Y2233256D01*
X3535748Y2232990D01*
X3536248Y2232456D01*
X3536548Y2231790D01*
Y2227923D01*
G01Y2231790D02*
X3536848Y2232456D01*
X3537348Y2232990D01*
X3538048Y2233256D01*
X3538748Y2232990D01*
X3539248Y2232456D01*
X3539548Y2231656D01*
Y2227923D01*
G01X3544548Y2233256D02*
Y2227923D01*
G01Y2235390D02*
X3544348Y2235523D01*
Y2235790D01*
X3544548Y2235923D01*
X3544748Y2235790D01*
Y2235523D01*
X3544548Y2235390D01*
G01X3552548Y2227923D02*
Y2235923D01*
G01X3559048Y2228856D02*
X3559548Y2228323D01*
X3560248Y2227923D01*
X3560848D01*
X3561448Y2228190D01*
X3561848Y2228590D01*
X3562048Y2229123D01*
X3561948Y2229923D01*
X3561548Y2230323D01*
X3559748Y2231123D01*
X3559348Y2232056D01*
X3559548Y2232723D01*
X3559948Y2233123D01*
X3560548Y2233256D01*
X3561148Y2233123D01*
X3561748Y2232723D01*
G01X3578348Y2227923D02*
Y2233256D01*
G01Y2232323D02*
X3577948Y2232856D01*
X3577348Y2233123D01*
X3576648Y2233256D01*
X3575948Y2232990D01*
X3575348Y2232456D01*
X3574948Y2231656D01*
X3574748Y2230590D01*
X3574948Y2229523D01*
X3575348Y2228723D01*
X3575948Y2228190D01*
X3576648Y2227923D01*
X3577348Y2228056D01*
X3577948Y2228456D01*
X3578348Y2228989D01*
G01X3583148Y2227923D02*
Y2233256D01*
G01Y2232190D02*
X3583648Y2232723D01*
X3584148Y2233123D01*
X3584848Y2233256D01*
X3585348Y2233123D01*
X3585948Y2232723D01*
G01X3592548Y2227923D02*
X3591948Y2228056D01*
X3591348Y2228590D01*
X3590948Y2229523D01*
X3590748Y2230590D01*
X3590948Y2231656D01*
X3591348Y2232590D01*
X3591948Y2233123D01*
X3592548Y2233256D01*
X3593148Y2233123D01*
X3593748Y2232590D01*
X3594148Y2231656D01*
X3594248Y2230590D01*
X3594148Y2229523D01*
X3593748Y2228590D01*
X3593148Y2228056D01*
X3592548Y2227923D01*
G01X3598848Y2233256D02*
Y2229523D01*
X3599248Y2228590D01*
X3599848Y2228056D01*
X3600548Y2227923D01*
X3601248Y2228056D01*
X3601848Y2228590D01*
X3602248Y2229523D01*
G01Y2227923D02*
Y2233256D01*
G01X3606848Y2227923D02*
Y2233256D01*
G01Y2231923D02*
X3607248Y2232590D01*
X3607848Y2233123D01*
X3608648Y2233256D01*
X3609348Y2233123D01*
X3609948Y2232590D01*
X3610248Y2231656D01*
Y2227923D01*
G01X3618348Y2235923D02*
Y2227923D01*
G01Y2229123D02*
X3617948Y2228456D01*
X3617348Y2228056D01*
X3616648Y2227923D01*
X3615848Y2228190D01*
X3615248Y2228856D01*
X3614848Y2229656D01*
X3614748Y2230590D01*
X3614848Y2231523D01*
X3615248Y2232323D01*
X3615848Y2232990D01*
X3616648Y2233256D01*
X3617348Y2233123D01*
X3617848Y2232856D01*
X3618348Y2232323D01*
G01X3632548Y2235923D02*
Y2227923D01*
G01X3631148Y2233256D02*
X3633948D01*
G01X3638848Y2227923D02*
Y2235923D01*
G01Y2232056D02*
X3639348Y2232723D01*
X3639848Y2233123D01*
X3640648Y2233256D01*
X3641248Y2233123D01*
X3641948Y2232590D01*
X3642248Y2231790D01*
Y2227923D01*
G01X3647048Y2231523D02*
X3650248D01*
X3649948Y2232456D01*
X3649448Y2232990D01*
X3648748Y2233256D01*
X3648048Y2233123D01*
X3647448Y2232723D01*
X3647048Y2231790D01*
X3646848Y2230989D01*
Y2230190D01*
X3647048Y2229390D01*
X3647548Y2228590D01*
X3648148Y2228056D01*
X3648848Y2227923D01*
X3649548Y2228190D01*
X3650248Y2228989D01*
G01X3662848Y2227923D02*
Y2233256D01*
G01Y2231923D02*
X3663248Y2232590D01*
X3663848Y2233123D01*
X3664648Y2233256D01*
X3665348Y2233123D01*
X3665948Y2232590D01*
X3666248Y2231656D01*
Y2227923D01*
G01X3671048Y2231523D02*
X3674248D01*
X3673948Y2232456D01*
X3673448Y2232990D01*
X3672748Y2233256D01*
X3672048Y2233123D01*
X3671448Y2232723D01*
X3671048Y2231790D01*
X3670848Y2230989D01*
Y2230190D01*
X3671048Y2229390D01*
X3671548Y2228590D01*
X3672148Y2228056D01*
X3672848Y2227923D01*
X3673548Y2228190D01*
X3674248Y2228989D01*
G01X3682148Y2232590D02*
X3681448Y2233123D01*
X3680848Y2233256D01*
X3680048Y2232990D01*
X3679448Y2232456D01*
X3679048Y2231523D01*
X3678948Y2230590D01*
X3679048Y2229656D01*
X3679448Y2228856D01*
X3680048Y2228190D01*
X3680848Y2227923D01*
X3681548Y2228190D01*
X3682148Y2228723D01*
G01X3686848Y2227923D02*
Y2235923D01*
G01X3690048Y2233256D02*
X3686848Y2230190D01*
G01X3688148Y2231390D02*
X3690248Y2227923D01*
G01X3701548D02*
Y2233256D01*
G01Y2231790D02*
X3701848Y2232456D01*
X3702348Y2232990D01*
X3703048Y2233256D01*
X3703748Y2232990D01*
X3704248Y2232456D01*
X3704548Y2231790D01*
Y2227923D01*
G01Y2231790D02*
X3704848Y2232456D01*
X3705348Y2232990D01*
X3706048Y2233256D01*
X3706748Y2232990D01*
X3707248Y2232456D01*
X3707548Y2231656D01*
Y2227923D01*
G01X3712548D02*
X3711948Y2228056D01*
X3711348Y2228590D01*
X3710948Y2229523D01*
X3710748Y2230590D01*
X3710948Y2231656D01*
X3711348Y2232590D01*
X3711948Y2233123D01*
X3712548Y2233256D01*
X3713148Y2233123D01*
X3713748Y2232590D01*
X3714148Y2231656D01*
X3714248Y2230590D01*
X3714148Y2229523D01*
X3713748Y2228590D01*
X3713148Y2228056D01*
X3712548Y2227923D01*
G01X3722348Y2235923D02*
Y2227923D01*
G01Y2229123D02*
X3721948Y2228456D01*
X3721348Y2228056D01*
X3720648Y2227923D01*
X3719848Y2228190D01*
X3719248Y2228856D01*
X3718848Y2229656D01*
X3718748Y2230590D01*
X3718848Y2231523D01*
X3719248Y2232323D01*
X3719848Y2232990D01*
X3720648Y2233256D01*
X3721348Y2233123D01*
X3721848Y2232856D01*
X3722348Y2232323D01*
G01X3727048Y2231523D02*
X3730248D01*
X3729948Y2232456D01*
X3729448Y2232990D01*
X3728748Y2233256D01*
X3728048Y2233123D01*
X3727448Y2232723D01*
X3727048Y2231790D01*
X3726848Y2230989D01*
Y2230190D01*
X3727048Y2229390D01*
X3727548Y2228590D01*
X3728148Y2228056D01*
X3728848Y2227923D01*
X3729548Y2228190D01*
X3730248Y2228989D01*
G01X3743148Y2227923D02*
Y2233256D01*
G01Y2232190D02*
X3743648Y2232723D01*
X3744148Y2233123D01*
X3744848Y2233256D01*
X3745348Y2233123D01*
X3745948Y2232723D01*
G01X3752548Y2227923D02*
X3751948Y2228056D01*
X3751348Y2228590D01*
X3750948Y2229523D01*
X3750748Y2230590D01*
X3750948Y2231656D01*
X3751348Y2232590D01*
X3751948Y2233123D01*
X3752548Y2233256D01*
X3753148Y2233123D01*
X3753748Y2232590D01*
X3754148Y2231656D01*
X3754248Y2230590D01*
X3754148Y2229523D01*
X3753748Y2228590D01*
X3753148Y2228056D01*
X3752548Y2227923D01*
G01X3758848Y2233256D02*
Y2229523D01*
X3759248Y2228590D01*
X3759848Y2228056D01*
X3760548Y2227923D01*
X3761248Y2228056D01*
X3761848Y2228590D01*
X3762248Y2229523D01*
G01Y2227923D02*
Y2233256D01*
G01X3768548Y2235923D02*
Y2227923D01*
G01X3767148Y2233256D02*
X3769948D01*
G01X3776548D02*
Y2227923D01*
G01Y2235390D02*
X3776348Y2235523D01*
Y2235790D01*
X3776548Y2235923D01*
X3776748Y2235790D01*
Y2235523D01*
X3776548Y2235390D01*
G01X3782848Y2227923D02*
Y2233256D01*
G01Y2231923D02*
X3783248Y2232590D01*
X3783848Y2233123D01*
X3784648Y2233256D01*
X3785348Y2233123D01*
X3785948Y2232590D01*
X3786248Y2231656D01*
Y2227923D01*
G01X3791148Y2225923D02*
X3791848Y2225390D01*
X3792648Y2225256D01*
X3793348Y2225390D01*
X3793948Y2226056D01*
X3794348Y2226990D01*
Y2233256D01*
G01Y2232190D02*
X3793948Y2232723D01*
X3793348Y2233123D01*
X3792648Y2233256D01*
X3791848Y2232990D01*
X3791348Y2232456D01*
X3790948Y2231523D01*
X3790748Y2230590D01*
X3790848Y2229790D01*
X3791248Y2228856D01*
X3791848Y2228190D01*
X3792648Y2227923D01*
X3793248Y2228056D01*
X3793948Y2228590D01*
X3794348Y2229123D01*
G01X3806048Y2233256D02*
X3807248Y2227923D01*
X3808548Y2233256D01*
X3809848Y2227923D01*
X3811048Y2233256D01*
G01X3814848Y2227923D02*
Y2235923D01*
G01Y2232056D02*
X3815348Y2232723D01*
X3815848Y2233123D01*
X3816648Y2233256D01*
X3817248Y2233123D01*
X3817948Y2232590D01*
X3818248Y2231790D01*
Y2227923D01*
G01X3824548Y2233256D02*
Y2227923D01*
G01Y2235390D02*
X3824348Y2235523D01*
Y2235790D01*
X3824548Y2235923D01*
X3824748Y2235790D01*
Y2235523D01*
X3824548Y2235390D01*
G01X3834148Y2232590D02*
X3833448Y2233123D01*
X3832848Y2233256D01*
X3832048Y2232990D01*
X3831448Y2232456D01*
X3831048Y2231523D01*
X3830948Y2230590D01*
X3831048Y2229656D01*
X3831448Y2228856D01*
X3832048Y2228190D01*
X3832848Y2227923D01*
X3833548Y2228190D01*
X3834148Y2228723D01*
G01X3838848Y2227923D02*
Y2235923D01*
G01Y2232056D02*
X3839348Y2232723D01*
X3839848Y2233123D01*
X3840648Y2233256D01*
X3841248Y2233123D01*
X3841948Y2232590D01*
X3842248Y2231790D01*
Y2227923D01*
G01X3856548Y2233256D02*
Y2227923D01*
G01Y2235390D02*
X3856348Y2235523D01*
Y2235790D01*
X3856548Y2235923D01*
X3856748Y2235790D01*
Y2235523D01*
X3856548Y2235390D01*
G01X3863048Y2228856D02*
X3863548Y2228323D01*
X3864248Y2227923D01*
X3864848D01*
X3865448Y2228190D01*
X3865848Y2228590D01*
X3866048Y2229123D01*
X3865948Y2229923D01*
X3865548Y2230323D01*
X3863748Y2231123D01*
X3863348Y2232056D01*
X3863548Y2232723D01*
X3863948Y2233123D01*
X3864548Y2233256D01*
X3865148Y2233123D01*
X3865748Y2232723D01*
G01X3881748Y2227923D02*
Y2235923D01*
X3878048Y2230190D01*
X3883048D01*
G01X3888548Y2227656D02*
X3888348Y2227790D01*
Y2228056D01*
X3888548Y2228190D01*
X3888748Y2228056D01*
Y2227790D01*
X3888548Y2227656D01*
G01X3894348Y2229123D02*
X3894948Y2228456D01*
X3895648Y2228056D01*
X3896548Y2227923D01*
X3897448Y2228190D01*
X3898148Y2228723D01*
X3898648Y2229656D01*
X3898748Y2230723D01*
X3898548Y2231790D01*
X3898048Y2232456D01*
X3897348Y2232990D01*
X3896648Y2233123D01*
X3895948Y2232990D01*
X3895048Y2232456D01*
X3895348Y2235923D01*
X3898048D01*
G01X3910748Y2227656D02*
X3914348Y2235923D01*
G01X3926348Y2229523D02*
X3926948Y2228590D01*
X3927748Y2228056D01*
X3928648Y2227923D01*
X3929448Y2228056D01*
X3930248Y2228723D01*
X3930748Y2229523D01*
X3930848Y2230323D01*
X3930648Y2231256D01*
X3929948Y2231923D01*
X3929248Y2232190D01*
X3928348D01*
G01X3929248D02*
X3929848Y2232590D01*
X3930348Y2233256D01*
X3930548Y2234056D01*
X3930348Y2234856D01*
X3929848Y2235523D01*
X3928948Y2235923D01*
X3928048Y2235790D01*
X3927148Y2235256D01*
G01X3942748Y2227656D02*
X3946348Y2235923D01*
G01X3961748Y2227923D02*
Y2235923D01*
X3958048Y2230190D01*
X3963048D01*
G01X3968548Y2227656D02*
X3968348Y2227790D01*
Y2228056D01*
X3968548Y2228190D01*
X3968748Y2228056D01*
Y2227790D01*
X3968548Y2227656D01*
G01X3974348Y2229123D02*
X3974948Y2228456D01*
X3975648Y2228056D01*
X3976548Y2227923D01*
X3977448Y2228190D01*
X3978148Y2228723D01*
X3978648Y2229656D01*
X3978748Y2230723D01*
X3978548Y2231790D01*
X3978048Y2232456D01*
X3977348Y2232990D01*
X3976648Y2233123D01*
X3975948Y2232990D01*
X3975048Y2232456D01*
X3975348Y2235923D01*
X3978048D01*
G01X3989548Y2227923D02*
Y2233256D01*
G01Y2231790D02*
X3989848Y2232456D01*
X3990348Y2232990D01*
X3991048Y2233256D01*
X3991748Y2232990D01*
X3992248Y2232456D01*
X3992548Y2231790D01*
Y2227923D01*
G01Y2231790D02*
X3992848Y2232456D01*
X3993348Y2232990D01*
X3994048Y2233256D01*
X3994748Y2232990D01*
X3995248Y2232456D01*
X3995548Y2231656D01*
Y2227923D01*
G01X4000548Y2233256D02*
Y2227923D01*
G01Y2235390D02*
X4000348Y2235523D01*
Y2235790D01*
X4000548Y2235923D01*
X4000748Y2235790D01*
Y2235523D01*
X4000548Y2235390D01*
G01X4008548Y2227923D02*
Y2235923D01*
G01X4015048Y2228856D02*
X4015548Y2228323D01*
X4016248Y2227923D01*
X4016848D01*
X4017448Y2228190D01*
X4017848Y2228590D01*
X4018048Y2229123D01*
X4017948Y2229923D01*
X4017548Y2230323D01*
X4015748Y2231123D01*
X4015348Y2232056D01*
X4015548Y2232723D01*
X4015948Y2233123D01*
X4016548Y2233256D01*
X4017148Y2233123D01*
X4017748Y2232723D01*
G01X3144548Y2272923D02*
Y2280923D01*
X3143348Y2279323D01*
G01Y2272923D02*
X3145748D01*
G01X3152548Y2280923D02*
X3151748Y2280656D01*
X3151148Y2279990D01*
X3150748Y2279190D01*
X3150448Y2278123D01*
X3150348Y2276923D01*
X3150448Y2275723D01*
X3150748Y2274656D01*
X3151148Y2273856D01*
X3151748Y2273190D01*
X3152548Y2272923D01*
X3153348Y2273190D01*
X3153948Y2273856D01*
X3154348Y2274656D01*
X3154648Y2275723D01*
X3154748Y2276923D01*
X3154648Y2278123D01*
X3154348Y2279190D01*
X3153948Y2279990D01*
X3153348Y2280656D01*
X3152548Y2280923D01*
G01X3160548Y2272656D02*
X3160348Y2272790D01*
Y2273056D01*
X3160548Y2273190D01*
X3160748Y2273056D01*
Y2272790D01*
X3160548Y2272656D01*
G01X3166648Y2272923D02*
Y2280923D01*
X3170448D01*
G01X3169048Y2277056D02*
X3166648D01*
G01X3176548Y2272923D02*
X3175748Y2273056D01*
X3175048Y2273590D01*
X3174448Y2274390D01*
X3174048Y2275323D01*
X3173848Y2276390D01*
Y2277456D01*
X3174048Y2278523D01*
X3174448Y2279456D01*
X3175048Y2280256D01*
X3175748Y2280790D01*
X3176548Y2280923D01*
X3177348Y2280790D01*
X3178048Y2280256D01*
X3178648Y2279456D01*
X3179048Y2278523D01*
X3179248Y2277456D01*
Y2276390D01*
X3179048Y2275323D01*
X3178648Y2274390D01*
X3178048Y2273590D01*
X3177348Y2273056D01*
X3176548Y2272923D01*
G01X3182548D02*
Y2280923D01*
X3185048D01*
X3185848Y2280523D01*
X3186348Y2279990D01*
X3186548Y2278923D01*
X3186348Y2277856D01*
X3185748Y2277190D01*
X3185048Y2276790D01*
X3182548D01*
G01X3185048D02*
X3186548Y2272923D01*
G01X3200548Y2280923D02*
Y2272923D01*
G01X3198248Y2280923D02*
X3202848D01*
G01X3206448Y2272923D02*
Y2280923D01*
G01X3210648D02*
Y2272923D01*
G01Y2276923D02*
X3206448D01*
G01X3218548Y2272923D02*
X3214548D01*
Y2280923D01*
X3218548D01*
G01X3216948Y2277056D02*
X3214548D01*
G01X3230548Y2272923D02*
Y2280923D01*
X3232948D01*
X3233748Y2280523D01*
X3234348Y2279590D01*
X3234548Y2278523D01*
X3234348Y2277456D01*
X3233848Y2276656D01*
X3232948Y2276256D01*
X3230548D01*
G01X3240548Y2280923D02*
Y2272923D01*
G01X3238248Y2280923D02*
X3242848D01*
G01X3246448Y2272923D02*
Y2280923D01*
G01X3250648D02*
Y2272923D01*
G01Y2276923D02*
X3246448D01*
G01X3264548Y2280923D02*
Y2272923D01*
G01X3262248Y2280923D02*
X3266848D01*
G01X3272548Y2272923D02*
X3271748Y2273056D01*
X3271048Y2273590D01*
X3270448Y2274390D01*
X3270048Y2275323D01*
X3269848Y2276390D01*
Y2277456D01*
X3270048Y2278523D01*
X3270448Y2279456D01*
X3271048Y2280256D01*
X3271748Y2280790D01*
X3272548Y2280923D01*
X3273348Y2280790D01*
X3274048Y2280256D01*
X3274648Y2279456D01*
X3275048Y2278523D01*
X3275248Y2277456D01*
Y2276390D01*
X3275048Y2275323D01*
X3274648Y2274390D01*
X3274048Y2273590D01*
X3273348Y2273056D01*
X3272548Y2272923D01*
G01X3280548D02*
X3279748Y2273056D01*
X3279048Y2273590D01*
X3278448Y2274390D01*
X3278048Y2275323D01*
X3277848Y2276390D01*
Y2277456D01*
X3278048Y2278523D01*
X3278448Y2279456D01*
X3279048Y2280256D01*
X3279748Y2280790D01*
X3280548Y2280923D01*
X3281348Y2280790D01*
X3282048Y2280256D01*
X3282648Y2279456D01*
X3283048Y2278523D01*
X3283248Y2277456D01*
Y2276390D01*
X3283048Y2275323D01*
X3282648Y2274390D01*
X3282048Y2273590D01*
X3281348Y2273056D01*
X3280548Y2272923D01*
G01X3286548Y2280923D02*
Y2272923D01*
X3290548D01*
G01X3295348Y2280923D02*
X3297748D01*
G01X3296548D02*
Y2272923D01*
G01X3295348D02*
X3297748D01*
G01X3302248D02*
Y2280923D01*
X3306848Y2272923D01*
Y2280923D01*
G01X3313148Y2276923D02*
X3315148D01*
Y2274523D01*
X3314548Y2273723D01*
X3313848Y2273190D01*
X3312848Y2272923D01*
X3311848Y2273190D01*
X3311148Y2273723D01*
X3310548Y2274523D01*
X3310148Y2275456D01*
X3309948Y2276523D01*
Y2277456D01*
X3310148Y2278256D01*
X3310548Y2279190D01*
X3311148Y2279990D01*
X3311748Y2280523D01*
X3312548Y2280923D01*
X3313248D01*
X3314048Y2280656D01*
X3314648Y2280123D01*
G01X3326448Y2272923D02*
Y2280923D01*
G01X3330648D02*
Y2272923D01*
G01Y2276923D02*
X3326448D01*
G01X3336548Y2272923D02*
X3335748Y2273056D01*
X3335048Y2273590D01*
X3334448Y2274390D01*
X3334048Y2275323D01*
X3333848Y2276390D01*
Y2277456D01*
X3334048Y2278523D01*
X3334448Y2279456D01*
X3335048Y2280256D01*
X3335748Y2280790D01*
X3336548Y2280923D01*
X3337348Y2280790D01*
X3338048Y2280256D01*
X3338648Y2279456D01*
X3339048Y2278523D01*
X3339248Y2277456D01*
Y2276390D01*
X3339048Y2275323D01*
X3338648Y2274390D01*
X3338048Y2273590D01*
X3337348Y2273056D01*
X3336548Y2272923D01*
G01X3342548Y2280923D02*
Y2272923D01*
X3346548D01*
G01X3354548D02*
X3350548D01*
Y2280923D01*
X3354548D01*
G01X3352948Y2277056D02*
X3350548D01*
G01X3358448Y2273989D02*
X3359248Y2273323D01*
X3360148Y2272923D01*
X3360948D01*
X3361748Y2273323D01*
X3362348Y2273989D01*
X3362648Y2274923D01*
X3362448Y2275856D01*
X3361948Y2276656D01*
X3361048Y2277190D01*
X3359848Y2277456D01*
X3359148Y2277990D01*
X3358848Y2278923D01*
X3359048Y2279856D01*
X3359548Y2280523D01*
X3360248Y2280923D01*
X3360948D01*
X3361648Y2280656D01*
X3362248Y2279990D01*
G01X3373548Y2280923D02*
X3374948Y2272923D01*
X3376548Y2280923D01*
X3378148Y2272923D01*
X3379548Y2280923D01*
G01X3382448Y2272923D02*
Y2280923D01*
G01X3386648D02*
Y2272923D01*
G01Y2276923D02*
X3382448D01*
G01X3391348Y2280923D02*
X3393748D01*
G01X3392548D02*
Y2272923D01*
G01X3391348D02*
X3393748D01*
G01X3402748Y2280256D02*
X3402148Y2280656D01*
X3401448Y2280923D01*
X3400648D01*
X3399748Y2280523D01*
X3399048Y2279856D01*
X3398548Y2279056D01*
X3398148Y2277723D01*
X3398048Y2276523D01*
X3398248Y2275323D01*
X3398548Y2274523D01*
X3399148Y2273723D01*
X3399848Y2273190D01*
X3400548Y2272923D01*
X3401248D01*
X3401948Y2273190D01*
X3402548Y2273590D01*
X3403048Y2274123D01*
G01X3406448Y2272923D02*
Y2280923D01*
G01X3410648D02*
Y2272923D01*
G01Y2276923D02*
X3406448D01*
G01X3422448Y2273989D02*
X3423248Y2273323D01*
X3424148Y2272923D01*
X3424948D01*
X3425748Y2273323D01*
X3426348Y2273989D01*
X3426648Y2274923D01*
X3426448Y2275856D01*
X3425948Y2276656D01*
X3425048Y2277190D01*
X3423848Y2277456D01*
X3423148Y2277990D01*
X3422848Y2278923D01*
X3423048Y2279856D01*
X3423548Y2280523D01*
X3424248Y2280923D01*
X3424948D01*
X3425648Y2280656D01*
X3426248Y2279990D01*
G01X3431348Y2280923D02*
X3433748D01*
G01X3432548D02*
Y2272923D01*
G01X3431348D02*
X3433748D01*
G01X3438648Y2280923D02*
X3442448D01*
X3438648Y2272923D01*
X3442448D01*
G01X3450548D02*
X3446548D01*
Y2280923D01*
X3450548D01*
G01X3448948Y2277056D02*
X3446548D01*
G01X3463348Y2280923D02*
X3465748D01*
G01X3464548D02*
Y2272923D01*
G01X3463348D02*
X3465748D01*
G01X3470448Y2273989D02*
X3471248Y2273323D01*
X3472148Y2272923D01*
X3472948D01*
X3473748Y2273323D01*
X3474348Y2273989D01*
X3474648Y2274923D01*
X3474448Y2275856D01*
X3473948Y2276656D01*
X3473048Y2277190D01*
X3471848Y2277456D01*
X3471148Y2277990D01*
X3470848Y2278923D01*
X3471048Y2279856D01*
X3471548Y2280523D01*
X3472248Y2280923D01*
X3472948D01*
X3473648Y2280656D01*
X3474248Y2279990D01*
G01X3490548Y2272923D02*
X3486548D01*
Y2280923D01*
X3490548D01*
G01X3488948Y2277056D02*
X3486548D01*
G01X3496548Y2272923D02*
X3495748Y2273056D01*
X3495048Y2273590D01*
X3494448Y2274390D01*
X3494048Y2275323D01*
X3493848Y2276390D01*
Y2277456D01*
X3494048Y2278523D01*
X3494448Y2279456D01*
X3495048Y2280256D01*
X3495748Y2280790D01*
X3496548Y2280923D01*
X3497348Y2280790D01*
X3498048Y2280256D01*
X3498648Y2279456D01*
X3499048Y2278523D01*
X3499248Y2277456D01*
Y2276390D01*
X3499048Y2275323D01*
X3498648Y2274390D01*
X3498048Y2273590D01*
X3497348Y2273056D01*
X3496548Y2272923D01*
G01X3497348Y2275056D02*
X3498548Y2272923D01*
G01X3502348Y2280923D02*
Y2275190D01*
X3502748Y2273989D01*
X3503548Y2273190D01*
X3504548Y2272923D01*
X3505548Y2273190D01*
X3506348Y2273989D01*
X3506748Y2275190D01*
Y2280923D01*
G01X3510048Y2272923D02*
X3512548Y2280923D01*
X3515048Y2272923D01*
G01X3514148Y2275723D02*
X3510948D01*
G01X3518548Y2280923D02*
Y2272923D01*
X3522548D01*
G01X3536548Y2280923D02*
Y2272923D01*
G01X3534248Y2280923D02*
X3538848D01*
G01X3544548Y2272923D02*
X3543748Y2273056D01*
X3543048Y2273590D01*
X3542448Y2274390D01*
X3542048Y2275323D01*
X3541848Y2276390D01*
Y2277456D01*
X3542048Y2278523D01*
X3542448Y2279456D01*
X3543048Y2280256D01*
X3543748Y2280790D01*
X3544548Y2280923D01*
X3545348Y2280790D01*
X3546048Y2280256D01*
X3546648Y2279456D01*
X3547048Y2278523D01*
X3547248Y2277456D01*
Y2276390D01*
X3547048Y2275323D01*
X3546648Y2274390D01*
X3546048Y2273590D01*
X3545348Y2273056D01*
X3544548Y2272923D01*
G01X3560548D02*
X3559748Y2273056D01*
X3559048Y2273590D01*
X3558448Y2274390D01*
X3558048Y2275323D01*
X3557848Y2276390D01*
Y2277456D01*
X3558048Y2278523D01*
X3558448Y2279456D01*
X3559048Y2280256D01*
X3559748Y2280790D01*
X3560548Y2280923D01*
X3561348Y2280790D01*
X3562048Y2280256D01*
X3562648Y2279456D01*
X3563048Y2278523D01*
X3563248Y2277456D01*
Y2276390D01*
X3563048Y2275323D01*
X3562648Y2274390D01*
X3562048Y2273590D01*
X3561348Y2273056D01*
X3560548Y2272923D01*
G01X3566548D02*
Y2280923D01*
X3569048D01*
X3569848Y2280523D01*
X3570348Y2279990D01*
X3570548Y2278923D01*
X3570348Y2277856D01*
X3569748Y2277190D01*
X3569048Y2276790D01*
X3566548D01*
G01X3569048D02*
X3570548Y2272923D01*
G01X3581948D02*
Y2280923D01*
X3584548Y2274256D01*
X3587148Y2280923D01*
Y2272923D01*
G01X3592548D02*
X3591748Y2273056D01*
X3591048Y2273590D01*
X3590448Y2274390D01*
X3590048Y2275323D01*
X3589848Y2276390D01*
Y2277456D01*
X3590048Y2278523D01*
X3590448Y2279456D01*
X3591048Y2280256D01*
X3591748Y2280790D01*
X3592548Y2280923D01*
X3593348Y2280790D01*
X3594048Y2280256D01*
X3594648Y2279456D01*
X3595048Y2278523D01*
X3595248Y2277456D01*
Y2276390D01*
X3595048Y2275323D01*
X3594648Y2274390D01*
X3594048Y2273590D01*
X3593348Y2273056D01*
X3592548Y2272923D01*
G01X3598548D02*
Y2280923D01*
X3601048D01*
X3601848Y2280523D01*
X3602348Y2279990D01*
X3602548Y2278923D01*
X3602348Y2277856D01*
X3601748Y2277190D01*
X3601048Y2276790D01*
X3598548D01*
G01X3601048D02*
X3602548Y2272923D01*
G01X3610548D02*
X3606548D01*
Y2280923D01*
X3610548D01*
G01X3608948Y2277056D02*
X3606548D01*
G01X3624548Y2280923D02*
Y2272923D01*
G01X3622248Y2280923D02*
X3626848D01*
G01X3630448Y2272923D02*
Y2280923D01*
G01X3634648D02*
Y2272923D01*
G01Y2276923D02*
X3630448D01*
G01X3638048Y2272923D02*
X3640548Y2280923D01*
X3643048Y2272923D01*
G01X3642148Y2275723D02*
X3638948D01*
G01X3646248Y2272923D02*
Y2280923D01*
X3650848Y2272923D01*
Y2280923D01*
G01X3664348Y2272923D02*
X3664548Y2274656D01*
X3664848Y2276123D01*
X3665248Y2277456D01*
X3665748Y2278923D01*
X3666548Y2280923D01*
X3662548D01*
G01X3672548D02*
X3671748Y2280656D01*
X3671148Y2279990D01*
X3670748Y2279190D01*
X3670448Y2278123D01*
X3670348Y2276923D01*
X3670448Y2275723D01*
X3670748Y2274656D01*
X3671148Y2273856D01*
X3671748Y2273190D01*
X3672548Y2272923D01*
X3673348Y2273190D01*
X3673948Y2273856D01*
X3674348Y2274656D01*
X3674648Y2275723D01*
X3674748Y2276923D01*
X3674648Y2278123D01*
X3674348Y2279190D01*
X3673948Y2279990D01*
X3673348Y2280656D01*
X3672548Y2280923D01*
G01X3685948Y2272923D02*
Y2280923D01*
X3688548Y2274256D01*
X3691148Y2280923D01*
Y2272923D01*
G01X3695348Y2280923D02*
X3697748D01*
G01X3696548D02*
Y2272923D01*
G01X3695348D02*
X3697748D01*
G01X3702548Y2280923D02*
Y2272923D01*
X3706548D01*
G01X3712548Y2272656D02*
X3712348Y2272790D01*
Y2273056D01*
X3712548Y2273190D01*
X3712748Y2273056D01*
Y2272790D01*
X3712548Y2272656D01*
G01X3734248Y2272923D02*
Y2280923D01*
X3738848Y2272923D01*
Y2280923D01*
G01X3744548Y2272923D02*
X3743748Y2273056D01*
X3743048Y2273590D01*
X3742448Y2274390D01*
X3742048Y2275323D01*
X3741848Y2276390D01*
Y2277456D01*
X3742048Y2278523D01*
X3742448Y2279456D01*
X3743048Y2280256D01*
X3743748Y2280790D01*
X3744548Y2280923D01*
X3745348Y2280790D01*
X3746048Y2280256D01*
X3746648Y2279456D01*
X3747048Y2278523D01*
X3747248Y2277456D01*
Y2276390D01*
X3747048Y2275323D01*
X3746648Y2274390D01*
X3746048Y2273590D01*
X3745348Y2273056D01*
X3744548Y2272923D01*
G01X3750248D02*
Y2280923D01*
X3754848Y2272923D01*
Y2280923D01*
G01X3759248Y2275590D02*
X3761848D01*
G01X3766648Y2272923D02*
Y2280923D01*
X3770448D01*
G01X3769048Y2277056D02*
X3766648D01*
G01X3774348Y2280923D02*
Y2275190D01*
X3774748Y2273989D01*
X3775548Y2273190D01*
X3776548Y2272923D01*
X3777548Y2273190D01*
X3778348Y2273989D01*
X3778748Y2275190D01*
Y2280923D01*
G01X3782248Y2272923D02*
Y2280923D01*
X3786848Y2272923D01*
Y2280923D01*
G01X3794748Y2280256D02*
X3794148Y2280656D01*
X3793448Y2280923D01*
X3792648D01*
X3791748Y2280523D01*
X3791048Y2279856D01*
X3790548Y2279056D01*
X3790148Y2277723D01*
X3790048Y2276523D01*
X3790248Y2275323D01*
X3790548Y2274523D01*
X3791148Y2273723D01*
X3791848Y2273190D01*
X3792548Y2272923D01*
X3793248D01*
X3793948Y2273190D01*
X3794548Y2273590D01*
X3795048Y2274123D01*
G01X3800548Y2280923D02*
Y2272923D01*
G01X3798248Y2280923D02*
X3802848D01*
G01X3807348D02*
X3809748D01*
G01X3808548D02*
Y2272923D01*
G01X3807348D02*
X3809748D01*
G01X3816548D02*
X3815748Y2273056D01*
X3815048Y2273590D01*
X3814448Y2274390D01*
X3814048Y2275323D01*
X3813848Y2276390D01*
Y2277456D01*
X3814048Y2278523D01*
X3814448Y2279456D01*
X3815048Y2280256D01*
X3815748Y2280790D01*
X3816548Y2280923D01*
X3817348Y2280790D01*
X3818048Y2280256D01*
X3818648Y2279456D01*
X3819048Y2278523D01*
X3819248Y2277456D01*
Y2276390D01*
X3819048Y2275323D01*
X3818648Y2274390D01*
X3818048Y2273590D01*
X3817348Y2273056D01*
X3816548Y2272923D01*
G01X3822248D02*
Y2280923D01*
X3826848Y2272923D01*
Y2280923D01*
G01X3830048Y2272923D02*
X3832548Y2280923D01*
X3835048Y2272923D01*
G01X3834148Y2275723D02*
X3830948D01*
G01X3838548Y2280923D02*
Y2272923D01*
X3842548D01*
G01X3854548D02*
Y2280923D01*
X3856948D01*
X3857748Y2280523D01*
X3858348Y2279590D01*
X3858548Y2278523D01*
X3858348Y2277456D01*
X3857848Y2276656D01*
X3856948Y2276256D01*
X3854548D01*
G01X3862048Y2272923D02*
X3864548Y2280923D01*
X3867048Y2272923D01*
G01X3866148Y2275723D02*
X3862948D01*
G01X3870348Y2272923D02*
Y2280923D01*
X3872348D01*
X3873148Y2280523D01*
X3873748Y2279990D01*
X3874248Y2279190D01*
X3874648Y2278256D01*
X3874748Y2276923D01*
X3874648Y2275590D01*
X3874248Y2274656D01*
X3873748Y2273856D01*
X3873148Y2273323D01*
X3872348Y2272923D01*
X3870348D01*
G01X3887348Y2280923D02*
X3889748D01*
G01X3888548D02*
Y2272923D01*
G01X3887348D02*
X3889748D01*
G01X3894448Y2273989D02*
X3895248Y2273323D01*
X3896148Y2272923D01*
X3896948D01*
X3897748Y2273323D01*
X3898348Y2273989D01*
X3898648Y2274923D01*
X3898448Y2275856D01*
X3897948Y2276656D01*
X3897048Y2277190D01*
X3895848Y2277456D01*
X3895148Y2277990D01*
X3894848Y2278923D01*
X3895048Y2279856D01*
X3895548Y2280523D01*
X3896248Y2280923D01*
X3896948D01*
X3897648Y2280656D01*
X3898248Y2279990D01*
G01X3910548Y2272923D02*
Y2280923D01*
X3913048D01*
X3913848Y2280523D01*
X3914348Y2279990D01*
X3914548Y2278923D01*
X3914348Y2277856D01*
X3913748Y2277190D01*
X3913048Y2276790D01*
X3910548D01*
G01X3913048D02*
X3914548Y2272923D01*
G01X3922548D02*
X3918548D01*
Y2280923D01*
X3922548D01*
G01X3920948Y2277056D02*
X3918548D01*
G01X3928548Y2272923D02*
X3927748Y2273056D01*
X3927048Y2273590D01*
X3926448Y2274390D01*
X3926048Y2275323D01*
X3925848Y2276390D01*
Y2277456D01*
X3926048Y2278523D01*
X3926448Y2279456D01*
X3927048Y2280256D01*
X3927748Y2280790D01*
X3928548Y2280923D01*
X3929348Y2280790D01*
X3930048Y2280256D01*
X3930648Y2279456D01*
X3931048Y2278523D01*
X3931248Y2277456D01*
Y2276390D01*
X3931048Y2275323D01*
X3930648Y2274390D01*
X3930048Y2273590D01*
X3929348Y2273056D01*
X3928548Y2272923D01*
G01X3929348Y2275056D02*
X3930548Y2272923D01*
G01X3934348Y2280923D02*
Y2275190D01*
X3934748Y2273989D01*
X3935548Y2273190D01*
X3936548Y2272923D01*
X3937548Y2273190D01*
X3938348Y2273989D01*
X3938748Y2275190D01*
Y2280923D01*
G01X3943348D02*
X3945748D01*
G01X3944548D02*
Y2272923D01*
G01X3943348D02*
X3945748D01*
G01X3950548D02*
Y2280923D01*
X3953048D01*
X3953848Y2280523D01*
X3954348Y2279990D01*
X3954548Y2278923D01*
X3954348Y2277856D01*
X3953748Y2277190D01*
X3953048Y2276790D01*
X3950548D01*
G01X3953048D02*
X3954548Y2272923D01*
G01X3962548D02*
X3958548D01*
Y2280923D01*
X3962548D01*
G01X3960948Y2277056D02*
X3958548D01*
G01X3966348Y2272923D02*
Y2280923D01*
X3968348D01*
X3969148Y2280523D01*
X3969748Y2279990D01*
X3970248Y2279190D01*
X3970648Y2278256D01*
X3970748Y2276923D01*
X3970648Y2275590D01*
X3970248Y2274656D01*
X3969748Y2273856D01*
X3969148Y2273323D01*
X3968348Y2272923D01*
X3966348D01*
G01X3984548Y2280923D02*
Y2272923D01*
G01X3982248Y2280923D02*
X3986848D01*
G01X3992548Y2272923D02*
X3991748Y2273056D01*
X3991048Y2273590D01*
X3990448Y2274390D01*
X3990048Y2275323D01*
X3989848Y2276390D01*
Y2277456D01*
X3990048Y2278523D01*
X3990448Y2279456D01*
X3991048Y2280256D01*
X3991748Y2280790D01*
X3992548Y2280923D01*
X3993348Y2280790D01*
X3994048Y2280256D01*
X3994648Y2279456D01*
X3995048Y2278523D01*
X3995248Y2277456D01*
Y2276390D01*
X3995048Y2275323D01*
X3994648Y2274390D01*
X3994048Y2273590D01*
X3993348Y2273056D01*
X3992548Y2272923D01*
G01X4009348Y2277190D02*
X4009748Y2277590D01*
X4010048Y2278256D01*
X4010248Y2279190D01*
X4010048Y2279990D01*
X4009648Y2280523D01*
X4008948Y2280923D01*
X4006248D01*
Y2272923D01*
X4009548D01*
X4010248Y2273456D01*
X4010648Y2274256D01*
X4010848Y2275190D01*
X4010648Y2276123D01*
X4010048Y2276923D01*
X4009348Y2277190D01*
X4006248D01*
G01X4018548Y2272923D02*
X4014548D01*
Y2280923D01*
X4018548D01*
G01X4016948Y2277056D02*
X4014548D01*
G01X4030048Y2272923D02*
X4032548Y2280923D01*
X4035048Y2272923D01*
G01X4034148Y2275723D02*
X4030948D01*
G01X4038348Y2272923D02*
Y2280923D01*
X4040348D01*
X4041148Y2280523D01*
X4041748Y2279990D01*
X4042248Y2279190D01*
X4042648Y2278256D01*
X4042748Y2276923D01*
X4042648Y2275590D01*
X4042248Y2274656D01*
X4041748Y2273856D01*
X4041148Y2273323D01*
X4040348Y2272923D01*
X4038348D01*
G01X4046348D02*
Y2280923D01*
X4048348D01*
X4049148Y2280523D01*
X4049748Y2279990D01*
X4050248Y2279190D01*
X4050648Y2278256D01*
X4050748Y2276923D01*
X4050648Y2275590D01*
X4050248Y2274656D01*
X4049748Y2273856D01*
X4049148Y2273323D01*
X4048348Y2272923D01*
X4046348D01*
G01X4058548D02*
X4054548D01*
Y2280923D01*
X4058548D01*
G01X4056948Y2277056D02*
X4054548D01*
G01X4062348Y2272923D02*
Y2280923D01*
X4064348D01*
X4065148Y2280523D01*
X4065748Y2279990D01*
X4066248Y2279190D01*
X4066648Y2278256D01*
X4066748Y2276923D01*
X4066648Y2275590D01*
X4066248Y2274656D01*
X4065748Y2273856D01*
X4065148Y2273323D01*
X4064348Y2272923D01*
X4062348D01*
G01X4080548Y2280923D02*
Y2272923D01*
G01X4078248Y2280923D02*
X4082848D01*
G01X4088548Y2272923D02*
X4087748Y2273056D01*
X4087048Y2273590D01*
X4086448Y2274390D01*
X4086048Y2275323D01*
X4085848Y2276390D01*
Y2277456D01*
X4086048Y2278523D01*
X4086448Y2279456D01*
X4087048Y2280256D01*
X4087748Y2280790D01*
X4088548Y2280923D01*
X4089348Y2280790D01*
X4090048Y2280256D01*
X4090648Y2279456D01*
X4091048Y2278523D01*
X4091248Y2277456D01*
Y2276390D01*
X4091048Y2275323D01*
X4090648Y2274390D01*
X4090048Y2273590D01*
X4089348Y2273056D01*
X4088548Y2272923D01*
G01X4102548D02*
Y2280923D01*
X4104948D01*
X4105748Y2280523D01*
X4106348Y2279590D01*
X4106548Y2278523D01*
X4106348Y2277456D01*
X4105848Y2276656D01*
X4104948Y2276256D01*
X4102548D01*
G01X4110548Y2272923D02*
Y2280923D01*
X4113048D01*
X4113848Y2280523D01*
X4114348Y2279990D01*
X4114548Y2278923D01*
X4114348Y2277856D01*
X4113748Y2277190D01*
X4113048Y2276790D01*
X4110548D01*
G01X4113048D02*
X4114548Y2272923D01*
G01X4122548D02*
X4118548D01*
Y2280923D01*
X4122548D01*
G01X4120948Y2277056D02*
X4118548D01*
G01X4126048Y2280923D02*
X4128548Y2272923D01*
X4131048Y2280923D01*
G01X4138548Y2272923D02*
X4134548D01*
Y2280923D01*
X4138548D01*
G01X4136948Y2277056D02*
X4134548D01*
G01X4142248Y2272923D02*
Y2280923D01*
X4146848Y2272923D01*
Y2280923D01*
G01X4152548D02*
Y2272923D01*
G01X4150248Y2280923D02*
X4154848D01*
G01X4168548D02*
Y2272923D01*
G01X4166248Y2280923D02*
X4170848D01*
G01X4174448Y2272923D02*
Y2280923D01*
G01X4178648D02*
Y2272923D01*
G01Y2276923D02*
X4174448D01*
G01X4186548Y2272923D02*
X4182548D01*
Y2280923D01*
X4186548D01*
G01X4184948Y2277056D02*
X4182548D01*
G01X4198548Y2272923D02*
Y2280923D01*
X4200948D01*
X4201748Y2280523D01*
X4202348Y2279590D01*
X4202548Y2278523D01*
X4202348Y2277456D01*
X4201848Y2276656D01*
X4200948Y2276256D01*
X4198548D01*
G01X4208548Y2272923D02*
X4207748Y2273056D01*
X4207048Y2273590D01*
X4206448Y2274390D01*
X4206048Y2275323D01*
X4205848Y2276390D01*
Y2277456D01*
X4206048Y2278523D01*
X4206448Y2279456D01*
X4207048Y2280256D01*
X4207748Y2280790D01*
X4208548Y2280923D01*
X4209348Y2280790D01*
X4210048Y2280256D01*
X4210648Y2279456D01*
X4211048Y2278523D01*
X4211248Y2277456D01*
Y2276390D01*
X4211048Y2275323D01*
X4210648Y2274390D01*
X4210048Y2273590D01*
X4209348Y2273056D01*
X4208548Y2272923D01*
G01X4216548Y2280923D02*
Y2272923D01*
G01X4214248Y2280923D02*
X4218848D01*
G01X4226548Y2272923D02*
X4222548D01*
Y2280923D01*
X4226548D01*
G01X4224948Y2277056D02*
X4222548D01*
G01X4230248Y2272923D02*
Y2280923D01*
X4234848Y2272923D01*
Y2280923D01*
G01X4240548D02*
Y2272923D01*
G01X4238248Y2280923D02*
X4242848D01*
G01X4247348D02*
X4249748D01*
G01X4248548D02*
Y2272923D01*
G01X4247348D02*
X4249748D01*
G01X4254048D02*
X4256548Y2280923D01*
X4259048Y2272923D01*
G01X4258148Y2275723D02*
X4254948D01*
G01X4262548Y2280923D02*
Y2272923D01*
X4266548D01*
G01X4278548D02*
Y2280923D01*
X4280948D01*
X4281748Y2280523D01*
X4282348Y2279590D01*
X4282548Y2278523D01*
X4282348Y2277456D01*
X4281848Y2276656D01*
X4280948Y2276256D01*
X4278548D01*
G01X4286348Y2280923D02*
Y2275190D01*
X4286748Y2273989D01*
X4287548Y2273190D01*
X4288548Y2272923D01*
X4289548Y2273190D01*
X4290348Y2273989D01*
X4290748Y2275190D01*
Y2280923D01*
G01X4294548D02*
Y2272923D01*
X4298548D01*
G01X4302548Y2280923D02*
Y2272923D01*
X4306548D01*
G01X4318048D02*
X4320548Y2280923D01*
X4323048Y2272923D01*
G01X4322148Y2275723D02*
X4318948D01*
G01X4325548Y2280923D02*
X4326948Y2272923D01*
X4328548Y2280923D01*
X4330148Y2272923D01*
X4331548Y2280923D01*
G01X4334048Y2272923D02*
X4336548Y2280923D01*
X4339048Y2272923D01*
G01X4338148Y2275723D02*
X4334948D01*
G01X4344548Y2272923D02*
Y2276523D01*
X4342548Y2280923D01*
G01X4346548D02*
X4344548Y2276523D01*
G01X4352548Y2272656D02*
X4352348Y2272790D01*
Y2273056D01*
X4352548Y2273190D01*
X4352748Y2273056D01*
Y2272790D01*
X4352548Y2272656D01*
G01X3142848Y2288856D02*
X3143548Y2288190D01*
X3144348Y2287923D01*
X3145148Y2288190D01*
X3145848Y2288989D01*
X3146348Y2290190D01*
X3146548Y2291390D01*
Y2292856D01*
X3146348Y2294056D01*
X3145848Y2295123D01*
X3145248Y2295656D01*
X3144548Y2295923D01*
X3143748Y2295656D01*
X3143148Y2295123D01*
X3142748Y2294323D01*
X3142548Y2293256D01*
X3142748Y2292323D01*
X3143248Y2291390D01*
X3143848Y2290856D01*
X3144548Y2290723D01*
X3145348Y2290989D01*
X3145948Y2291656D01*
X3146548Y2292856D01*
G01X3152548Y2287656D02*
X3152348Y2287790D01*
Y2288056D01*
X3152548Y2288190D01*
X3152748Y2288056D01*
Y2287790D01*
X3152548Y2287656D01*
G01X3158048Y2287923D02*
X3160548Y2295923D01*
X3163048Y2287923D01*
G01X3162148Y2290723D02*
X3158948D01*
G01X3166248Y2287923D02*
Y2295923D01*
X3170848Y2287923D01*
Y2295923D01*
G01X3176548Y2287923D02*
Y2291523D01*
X3174548Y2295923D01*
G01X3178548D02*
X3176548Y2291523D01*
G01X3190448Y2288989D02*
X3191248Y2288323D01*
X3192148Y2287923D01*
X3192948D01*
X3193748Y2288323D01*
X3194348Y2288989D01*
X3194648Y2289923D01*
X3194448Y2290856D01*
X3193948Y2291656D01*
X3193048Y2292190D01*
X3191848Y2292456D01*
X3191148Y2292990D01*
X3190848Y2293923D01*
X3191048Y2294856D01*
X3191548Y2295523D01*
X3192248Y2295923D01*
X3192948D01*
X3193648Y2295656D01*
X3194248Y2294990D01*
G01X3198548Y2287923D02*
Y2295923D01*
X3200948D01*
X3201748Y2295523D01*
X3202348Y2294590D01*
X3202548Y2293523D01*
X3202348Y2292456D01*
X3201848Y2291656D01*
X3200948Y2291256D01*
X3198548D01*
G01X3210548Y2287923D02*
X3206548D01*
Y2295923D01*
X3210548D01*
G01X3208948Y2292056D02*
X3206548D01*
G01X3218748Y2295256D02*
X3218148Y2295656D01*
X3217448Y2295923D01*
X3216648D01*
X3215748Y2295523D01*
X3215048Y2294856D01*
X3214548Y2294056D01*
X3214148Y2292723D01*
X3214048Y2291523D01*
X3214248Y2290323D01*
X3214548Y2289523D01*
X3215148Y2288723D01*
X3215848Y2288190D01*
X3216548Y2287923D01*
X3217248D01*
X3217948Y2288190D01*
X3218548Y2288590D01*
X3219048Y2289123D01*
G01X3223348Y2295923D02*
X3225748D01*
G01X3224548D02*
Y2287923D01*
G01X3223348D02*
X3225748D01*
G01X3230048D02*
X3232548Y2295923D01*
X3235048Y2287923D01*
G01X3234148Y2290723D02*
X3230948D01*
G01X3238548Y2295923D02*
Y2287923D01*
X3242548D01*
G01X3254348D02*
Y2295923D01*
X3256348D01*
X3257148Y2295523D01*
X3257748Y2294990D01*
X3258248Y2294190D01*
X3258648Y2293256D01*
X3258748Y2291923D01*
X3258648Y2290590D01*
X3258248Y2289656D01*
X3257748Y2288856D01*
X3257148Y2288323D01*
X3256348Y2287923D01*
X3254348D01*
G01X3262548D02*
Y2295923D01*
X3265048D01*
X3265848Y2295523D01*
X3266348Y2294990D01*
X3266548Y2293923D01*
X3266348Y2292856D01*
X3265748Y2292190D01*
X3265048Y2291790D01*
X3262548D01*
G01X3265048D02*
X3266548Y2287923D01*
G01X3271348Y2295923D02*
X3273748D01*
G01X3272548D02*
Y2287923D01*
G01X3271348D02*
X3273748D01*
G01X3278548Y2295923D02*
Y2287923D01*
X3282548D01*
G01X3286548Y2295923D02*
Y2287923D01*
X3290548D01*
G01X3302048D02*
X3304548Y2295923D01*
X3307048Y2287923D01*
G01X3306148Y2290723D02*
X3302948D01*
G01X3310248Y2287923D02*
Y2295923D01*
X3314848Y2287923D01*
Y2295923D01*
G01X3318348Y2287923D02*
Y2295923D01*
X3320348D01*
X3321148Y2295523D01*
X3321748Y2294990D01*
X3322248Y2294190D01*
X3322648Y2293256D01*
X3322748Y2291923D01*
X3322648Y2290590D01*
X3322248Y2289656D01*
X3321748Y2288856D01*
X3321148Y2288323D01*
X3320348Y2287923D01*
X3318348D01*
G01X3334448Y2288989D02*
X3335248Y2288323D01*
X3336148Y2287923D01*
X3336948D01*
X3337748Y2288323D01*
X3338348Y2288989D01*
X3338648Y2289923D01*
X3338448Y2290856D01*
X3337948Y2291656D01*
X3337048Y2292190D01*
X3335848Y2292456D01*
X3335148Y2292990D01*
X3334848Y2293923D01*
X3335048Y2294856D01*
X3335548Y2295523D01*
X3336248Y2295923D01*
X3336948D01*
X3337648Y2295656D01*
X3338248Y2294990D01*
G01X3344548Y2295923D02*
Y2287923D01*
G01X3342248Y2295923D02*
X3346848D01*
G01X3350048Y2287923D02*
X3352548Y2295923D01*
X3355048Y2287923D01*
G01X3354148Y2290723D02*
X3350948D01*
G01X3362748Y2295256D02*
X3362148Y2295656D01*
X3361448Y2295923D01*
X3360648D01*
X3359748Y2295523D01*
X3359048Y2294856D01*
X3358548Y2294056D01*
X3358148Y2292723D01*
X3358048Y2291523D01*
X3358248Y2290323D01*
X3358548Y2289523D01*
X3359148Y2288723D01*
X3359848Y2288190D01*
X3360548Y2287923D01*
X3361248D01*
X3361948Y2288190D01*
X3362548Y2288590D01*
X3363048Y2289123D01*
G01X3366348Y2287923D02*
Y2295923D01*
G01X3370148D02*
X3366348Y2290989D01*
G01X3370748Y2287923D02*
X3368048Y2293256D01*
G01X3378548Y2287923D02*
X3374548D01*
Y2295923D01*
X3378548D01*
G01X3376948Y2292056D02*
X3374548D01*
G01X3382348Y2287923D02*
Y2295923D01*
X3384348D01*
X3385148Y2295523D01*
X3385748Y2294990D01*
X3386248Y2294190D01*
X3386648Y2293256D01*
X3386748Y2291923D01*
X3386648Y2290590D01*
X3386248Y2289656D01*
X3385748Y2288856D01*
X3385148Y2288323D01*
X3384348Y2287923D01*
X3382348D01*
G01X3398448D02*
Y2295923D01*
G01X3402648D02*
Y2287923D01*
G01Y2291923D02*
X3398448D01*
G01X3408548Y2287923D02*
X3407748Y2288056D01*
X3407048Y2288590D01*
X3406448Y2289390D01*
X3406048Y2290323D01*
X3405848Y2291390D01*
Y2292456D01*
X3406048Y2293523D01*
X3406448Y2294456D01*
X3407048Y2295256D01*
X3407748Y2295790D01*
X3408548Y2295923D01*
X3409348Y2295790D01*
X3410048Y2295256D01*
X3410648Y2294456D01*
X3411048Y2293523D01*
X3411248Y2292456D01*
Y2291390D01*
X3411048Y2290323D01*
X3410648Y2289390D01*
X3410048Y2288590D01*
X3409348Y2288056D01*
X3408548Y2287923D01*
G01X3414548Y2295923D02*
Y2287923D01*
X3418548D01*
G01X3426548D02*
X3422548D01*
Y2295923D01*
X3426548D01*
G01X3424948Y2292056D02*
X3422548D01*
G01X3438548Y2287923D02*
Y2295923D01*
X3440948D01*
X3441748Y2295523D01*
X3442348Y2294590D01*
X3442548Y2293523D01*
X3442348Y2292456D01*
X3441848Y2291656D01*
X3440948Y2291256D01*
X3438548D01*
G01X3446548Y2295923D02*
Y2287923D01*
X3450548D01*
G01X3458548D02*
X3454548D01*
Y2295923D01*
X3458548D01*
G01X3456948Y2292056D02*
X3454548D01*
G01X3462048Y2287923D02*
X3464548Y2295923D01*
X3467048Y2287923D01*
G01X3466148Y2290723D02*
X3462948D01*
G01X3470448Y2288989D02*
X3471248Y2288323D01*
X3472148Y2287923D01*
X3472948D01*
X3473748Y2288323D01*
X3474348Y2288989D01*
X3474648Y2289923D01*
X3474448Y2290856D01*
X3473948Y2291656D01*
X3473048Y2292190D01*
X3471848Y2292456D01*
X3471148Y2292990D01*
X3470848Y2293923D01*
X3471048Y2294856D01*
X3471548Y2295523D01*
X3472248Y2295923D01*
X3472948D01*
X3473648Y2295656D01*
X3474248Y2294990D01*
G01X3482548Y2287923D02*
X3478548D01*
Y2295923D01*
X3482548D01*
G01X3480948Y2292056D02*
X3478548D01*
G01X3494648Y2287923D02*
Y2295923D01*
X3498448D01*
G01X3497048Y2292056D02*
X3494648D01*
G01X3504548Y2287923D02*
X3503748Y2288056D01*
X3503048Y2288590D01*
X3502448Y2289390D01*
X3502048Y2290323D01*
X3501848Y2291390D01*
Y2292456D01*
X3502048Y2293523D01*
X3502448Y2294456D01*
X3503048Y2295256D01*
X3503748Y2295790D01*
X3504548Y2295923D01*
X3505348Y2295790D01*
X3506048Y2295256D01*
X3506648Y2294456D01*
X3507048Y2293523D01*
X3507248Y2292456D01*
Y2291390D01*
X3507048Y2290323D01*
X3506648Y2289390D01*
X3506048Y2288590D01*
X3505348Y2288056D01*
X3504548Y2287923D01*
G01X3510548Y2295923D02*
Y2287923D01*
X3514548D01*
G01X3518548Y2295923D02*
Y2287923D01*
X3522548D01*
G01X3528548D02*
X3527748Y2288056D01*
X3527048Y2288590D01*
X3526448Y2289390D01*
X3526048Y2290323D01*
X3525848Y2291390D01*
Y2292456D01*
X3526048Y2293523D01*
X3526448Y2294456D01*
X3527048Y2295256D01*
X3527748Y2295790D01*
X3528548Y2295923D01*
X3529348Y2295790D01*
X3530048Y2295256D01*
X3530648Y2294456D01*
X3531048Y2293523D01*
X3531248Y2292456D01*
Y2291390D01*
X3531048Y2290323D01*
X3530648Y2289390D01*
X3530048Y2288590D01*
X3529348Y2288056D01*
X3528548Y2287923D01*
G01X3533548Y2295923D02*
X3534948Y2287923D01*
X3536548Y2295923D01*
X3538148Y2287923D01*
X3539548Y2295923D01*
G01X3552548Y2287923D02*
X3551748Y2288056D01*
X3551048Y2288590D01*
X3550448Y2289390D01*
X3550048Y2290323D01*
X3549848Y2291390D01*
Y2292456D01*
X3550048Y2293523D01*
X3550448Y2294456D01*
X3551048Y2295256D01*
X3551748Y2295790D01*
X3552548Y2295923D01*
X3553348Y2295790D01*
X3554048Y2295256D01*
X3554648Y2294456D01*
X3555048Y2293523D01*
X3555248Y2292456D01*
Y2291390D01*
X3555048Y2290323D01*
X3554648Y2289390D01*
X3554048Y2288590D01*
X3553348Y2288056D01*
X3552548Y2287923D01*
G01X3558348Y2295923D02*
Y2290190D01*
X3558748Y2288989D01*
X3559548Y2288190D01*
X3560548Y2287923D01*
X3561548Y2288190D01*
X3562348Y2288989D01*
X3562748Y2290190D01*
Y2295923D01*
G01X3568548D02*
Y2287923D01*
G01X3566248Y2295923D02*
X3570848D01*
G01X3574548D02*
Y2287923D01*
X3578548D01*
G01X3583348Y2295923D02*
X3585748D01*
G01X3584548D02*
Y2287923D01*
G01X3583348D02*
X3585748D01*
G01X3590248D02*
Y2295923D01*
X3594848Y2287923D01*
Y2295923D01*
G01X3602548Y2287923D02*
X3598548D01*
Y2295923D01*
X3602548D01*
G01X3600948Y2292056D02*
X3598548D01*
G01X3608548Y2287656D02*
X3608348Y2287790D01*
Y2288056D01*
X3608548Y2288190D01*
X3608748Y2288056D01*
Y2287790D01*
X3608548Y2287656D01*
G01X3622548Y2287923D02*
Y2295923D01*
X3624948D01*
X3625748Y2295523D01*
X3626348Y2294590D01*
X3626548Y2293523D01*
X3626348Y2292456D01*
X3625848Y2291656D01*
X3624948Y2291256D01*
X3622548D01*
G01X3632548Y2295923D02*
Y2287923D01*
G01X3630248Y2295923D02*
X3634848D01*
G01X3638448Y2287923D02*
Y2295923D01*
G01X3642648D02*
Y2287923D01*
G01Y2291923D02*
X3638448D01*
G01X3656548Y2295923D02*
Y2287923D01*
G01X3654248Y2295923D02*
X3658848D01*
G01X3664548Y2287923D02*
X3663748Y2288056D01*
X3663048Y2288590D01*
X3662448Y2289390D01*
X3662048Y2290323D01*
X3661848Y2291390D01*
Y2292456D01*
X3662048Y2293523D01*
X3662448Y2294456D01*
X3663048Y2295256D01*
X3663748Y2295790D01*
X3664548Y2295923D01*
X3665348Y2295790D01*
X3666048Y2295256D01*
X3666648Y2294456D01*
X3667048Y2293523D01*
X3667248Y2292456D01*
Y2291390D01*
X3667048Y2290323D01*
X3666648Y2289390D01*
X3666048Y2288590D01*
X3665348Y2288056D01*
X3664548Y2287923D01*
G01X3670548Y2295923D02*
Y2287923D01*
X3674548D01*
G01X3682548D02*
X3678548D01*
Y2295923D01*
X3682548D01*
G01X3680948Y2292056D02*
X3678548D01*
G01X3686548Y2287923D02*
Y2295923D01*
X3689048D01*
X3689848Y2295523D01*
X3690348Y2294990D01*
X3690548Y2293923D01*
X3690348Y2292856D01*
X3689748Y2292190D01*
X3689048Y2291790D01*
X3686548D01*
G01X3689048D02*
X3690548Y2287923D01*
G01X3694048D02*
X3696548Y2295923D01*
X3699048Y2287923D01*
G01X3698148Y2290723D02*
X3694948D01*
G01X3702248Y2287923D02*
Y2295923D01*
X3706848Y2287923D01*
Y2295923D01*
G01X3714748Y2295256D02*
X3714148Y2295656D01*
X3713448Y2295923D01*
X3712648D01*
X3711748Y2295523D01*
X3711048Y2294856D01*
X3710548Y2294056D01*
X3710148Y2292723D01*
X3710048Y2291523D01*
X3710248Y2290323D01*
X3710548Y2289523D01*
X3711148Y2288723D01*
X3711848Y2288190D01*
X3712548Y2287923D01*
X3713248D01*
X3713948Y2288190D01*
X3714548Y2288590D01*
X3715048Y2289123D01*
G01X3722548Y2287923D02*
X3718548D01*
Y2295923D01*
X3722548D01*
G01X3720948Y2292056D02*
X3718548D01*
G01X3736548Y2287656D02*
X3736348Y2287790D01*
Y2288056D01*
X3736548Y2288190D01*
X3736748Y2288056D01*
Y2287790D01*
X3736548Y2287656D01*
G01Y2291256D02*
X3736348Y2291390D01*
Y2291656D01*
X3736548Y2291790D01*
X3736748Y2291656D01*
Y2291390D01*
X3736548Y2291256D01*
G01X3751448Y2290590D02*
X3753848D01*
G01X3752548Y2292323D02*
Y2288856D01*
G01X3758748Y2287656D02*
X3762348Y2295923D01*
G01X3767248Y2290590D02*
X3769848D01*
G01X3774348Y2289123D02*
X3774948Y2288456D01*
X3775648Y2288056D01*
X3776548Y2287923D01*
X3777448Y2288190D01*
X3778148Y2288723D01*
X3778648Y2289656D01*
X3778748Y2290723D01*
X3778548Y2291790D01*
X3778048Y2292456D01*
X3777348Y2292990D01*
X3776648Y2293123D01*
X3775948Y2292990D01*
X3775048Y2292456D01*
X3775348Y2295923D01*
X3778048D01*
G01X3784048Y2285256D02*
X3783048Y2286590D01*
X3782548Y2287923D01*
Y2293256D01*
X3783048Y2294590D01*
X3784048Y2295923D01*
G01X3789948Y2287923D02*
Y2295923D01*
X3792548Y2289256D01*
X3795148Y2295923D01*
Y2287923D01*
G01X3799348Y2295923D02*
X3801748D01*
G01X3800548D02*
Y2287923D01*
G01X3799348D02*
X3801748D01*
G01X3806548Y2295923D02*
Y2287923D01*
X3810548D01*
G01X3817048Y2285256D02*
X3818048Y2286590D01*
X3818548Y2287923D01*
Y2293256D01*
X3818048Y2294590D01*
X3817048Y2295923D01*
G01X3824348Y2286456D02*
X3824748Y2288190D01*
G01X3838248Y2287923D02*
Y2295923D01*
X3842848Y2287923D01*
Y2295923D01*
G01X3846548Y2287923D02*
Y2295923D01*
X3848948D01*
X3849748Y2295523D01*
X3850348Y2294590D01*
X3850548Y2293523D01*
X3850348Y2292456D01*
X3849848Y2291656D01*
X3848948Y2291256D01*
X3846548D01*
G01X3856548Y2295923D02*
Y2287923D01*
G01X3854248Y2295923D02*
X3858848D01*
G01X3862448Y2287923D02*
Y2295923D01*
G01X3866648D02*
Y2287923D01*
G01Y2291923D02*
X3862448D01*
G01X3880548Y2295923D02*
Y2287923D01*
G01X3878248Y2295923D02*
X3882848D01*
G01X3888548Y2287923D02*
X3887748Y2288056D01*
X3887048Y2288590D01*
X3886448Y2289390D01*
X3886048Y2290323D01*
X3885848Y2291390D01*
Y2292456D01*
X3886048Y2293523D01*
X3886448Y2294456D01*
X3887048Y2295256D01*
X3887748Y2295790D01*
X3888548Y2295923D01*
X3889348Y2295790D01*
X3890048Y2295256D01*
X3890648Y2294456D01*
X3891048Y2293523D01*
X3891248Y2292456D01*
Y2291390D01*
X3891048Y2290323D01*
X3890648Y2289390D01*
X3890048Y2288590D01*
X3889348Y2288056D01*
X3888548Y2287923D01*
G01X3894548Y2295923D02*
Y2287923D01*
X3898548D01*
G01X3906548D02*
X3902548D01*
Y2295923D01*
X3906548D01*
G01X3904948Y2292056D02*
X3902548D01*
G01X3910548Y2287923D02*
Y2295923D01*
X3913048D01*
X3913848Y2295523D01*
X3914348Y2294990D01*
X3914548Y2293923D01*
X3914348Y2292856D01*
X3913748Y2292190D01*
X3913048Y2291790D01*
X3910548D01*
G01X3913048D02*
X3914548Y2287923D01*
G01X3918048D02*
X3920548Y2295923D01*
X3923048Y2287923D01*
G01X3922148Y2290723D02*
X3918948D01*
G01X3926248Y2287923D02*
Y2295923D01*
X3930848Y2287923D01*
Y2295923D01*
G01X3938748Y2295256D02*
X3938148Y2295656D01*
X3937448Y2295923D01*
X3936648D01*
X3935748Y2295523D01*
X3935048Y2294856D01*
X3934548Y2294056D01*
X3934148Y2292723D01*
X3934048Y2291523D01*
X3934248Y2290323D01*
X3934548Y2289523D01*
X3935148Y2288723D01*
X3935848Y2288190D01*
X3936548Y2287923D01*
X3937248D01*
X3937948Y2288190D01*
X3938548Y2288590D01*
X3939048Y2289123D01*
G01X3946548Y2287923D02*
X3942548D01*
Y2295923D01*
X3946548D01*
G01X3944948Y2292056D02*
X3942548D01*
G01X3952548Y2287656D02*
X3952348Y2287790D01*
Y2288056D01*
X3952548Y2288190D01*
X3952748Y2288056D01*
Y2287790D01*
X3952548Y2287656D01*
G01Y2291256D02*
X3952348Y2291390D01*
Y2291656D01*
X3952548Y2291790D01*
X3952748Y2291656D01*
Y2291390D01*
X3952548Y2291256D01*
G01X3967448Y2290590D02*
X3969848D01*
G01X3968548Y2292323D02*
Y2288856D01*
G01X3974748Y2287656D02*
X3978348Y2295923D01*
G01X3983248Y2290590D02*
X3985848D01*
G01X3993748Y2287923D02*
Y2295923D01*
X3990048Y2290190D01*
X3995048D01*
G01X4000048Y2285256D02*
X3999048Y2286590D01*
X3998548Y2287923D01*
Y2293256D01*
X3999048Y2294590D01*
X4000048Y2295923D01*
G01X4005948Y2287923D02*
Y2295923D01*
X4008548Y2289256D01*
X4011148Y2295923D01*
Y2287923D01*
G01X4015348Y2295923D02*
X4017748D01*
G01X4016548D02*
Y2287923D01*
G01X4015348D02*
X4017748D01*
G01X4022548Y2295923D02*
Y2287923D01*
X4026548D01*
G01X4033048Y2285256D02*
X4034048Y2286590D01*
X4034548Y2287923D01*
Y2293256D01*
X4034048Y2294590D01*
X4033048Y2295923D01*
G01X4040548Y2287656D02*
X4040348Y2287790D01*
Y2288056D01*
X4040548Y2288190D01*
X4040748Y2288056D01*
Y2287790D01*
X4040548Y2287656D01*
G01X3144548Y2302923D02*
X3145248Y2303056D01*
X3146048Y2303456D01*
X3146548Y2304123D01*
X3146748Y2305056D01*
X3146548Y2305989D01*
X3145948Y2306790D01*
X3145048Y2307190D01*
X3144048D01*
X3143448Y2307456D01*
X3142948Y2308123D01*
X3142748Y2309056D01*
X3143048Y2309990D01*
X3143748Y2310656D01*
X3144548Y2310923D01*
X3145348Y2310656D01*
X3146048Y2309990D01*
X3146348Y2309056D01*
X3146148Y2308123D01*
X3145648Y2307456D01*
X3145048Y2307190D01*
X3144048D01*
X3143148Y2306790D01*
X3142548Y2305989D01*
X3142348Y2305056D01*
X3142548Y2304123D01*
X3143048Y2303456D01*
X3143848Y2303056D01*
X3144548Y2302923D01*
G01X3152548Y2302656D02*
X3152348Y2302790D01*
Y2303056D01*
X3152548Y2303190D01*
X3152748Y2303056D01*
Y2302790D01*
X3152548Y2302656D01*
G01X3158248Y2302923D02*
Y2310923D01*
X3162848Y2302923D01*
Y2310923D01*
G01X3168548Y2302923D02*
X3167748Y2303056D01*
X3167048Y2303590D01*
X3166448Y2304390D01*
X3166048Y2305323D01*
X3165848Y2306390D01*
Y2307456D01*
X3166048Y2308523D01*
X3166448Y2309456D01*
X3167048Y2310256D01*
X3167748Y2310790D01*
X3168548Y2310923D01*
X3169348Y2310790D01*
X3170048Y2310256D01*
X3170648Y2309456D01*
X3171048Y2308523D01*
X3171248Y2307456D01*
Y2306390D01*
X3171048Y2305323D01*
X3170648Y2304390D01*
X3170048Y2303590D01*
X3169348Y2303056D01*
X3168548Y2302923D01*
G01X3176548Y2310923D02*
Y2302923D01*
G01X3174248Y2310923D02*
X3178848D01*
G01X3190048Y2302923D02*
X3192548Y2310923D01*
X3195048Y2302923D01*
G01X3194148Y2305723D02*
X3190948D01*
G01X3198548Y2310923D02*
Y2302923D01*
X3202548D01*
G01X3206548Y2310923D02*
Y2302923D01*
X3210548D01*
G01X3216548D02*
X3215748Y2303056D01*
X3215048Y2303590D01*
X3214448Y2304390D01*
X3214048Y2305323D01*
X3213848Y2306390D01*
Y2307456D01*
X3214048Y2308523D01*
X3214448Y2309456D01*
X3215048Y2310256D01*
X3215748Y2310790D01*
X3216548Y2310923D01*
X3217348Y2310790D01*
X3218048Y2310256D01*
X3218648Y2309456D01*
X3219048Y2308523D01*
X3219248Y2307456D01*
Y2306390D01*
X3219048Y2305323D01*
X3218648Y2304390D01*
X3218048Y2303590D01*
X3217348Y2303056D01*
X3216548Y2302923D01*
G01X3221548Y2310923D02*
X3222948Y2302923D01*
X3224548Y2310923D01*
X3226148Y2302923D01*
X3227548Y2310923D01*
G01X3241348Y2307190D02*
X3241748Y2307590D01*
X3242048Y2308256D01*
X3242248Y2309190D01*
X3242048Y2309990D01*
X3241648Y2310523D01*
X3240948Y2310923D01*
X3238248D01*
Y2302923D01*
X3241548D01*
X3242248Y2303456D01*
X3242648Y2304256D01*
X3242848Y2305190D01*
X3242648Y2306123D01*
X3242048Y2306923D01*
X3241348Y2307190D01*
X3238248D01*
G01X3246548Y2302923D02*
Y2310923D01*
X3249048D01*
X3249848Y2310523D01*
X3250348Y2309990D01*
X3250548Y2308923D01*
X3250348Y2307856D01*
X3249748Y2307190D01*
X3249048Y2306790D01*
X3246548D01*
G01X3249048D02*
X3250548Y2302923D01*
G01X3258548D02*
X3254548D01*
Y2310923D01*
X3258548D01*
G01X3256948Y2307056D02*
X3254548D01*
G01X3262048Y2302923D02*
X3264548Y2310923D01*
X3267048Y2302923D01*
G01X3266148Y2305723D02*
X3262948D01*
G01X3270348Y2302923D02*
Y2310923D01*
G01X3274148D02*
X3270348Y2305989D01*
G01X3274748Y2302923D02*
X3272048Y2308256D01*
G01X3280548Y2302923D02*
X3279748Y2303056D01*
X3279048Y2303590D01*
X3278448Y2304390D01*
X3278048Y2305323D01*
X3277848Y2306390D01*
Y2307456D01*
X3278048Y2308523D01*
X3278448Y2309456D01*
X3279048Y2310256D01*
X3279748Y2310790D01*
X3280548Y2310923D01*
X3281348Y2310790D01*
X3282048Y2310256D01*
X3282648Y2309456D01*
X3283048Y2308523D01*
X3283248Y2307456D01*
Y2306390D01*
X3283048Y2305323D01*
X3282648Y2304390D01*
X3282048Y2303590D01*
X3281348Y2303056D01*
X3280548Y2302923D01*
G01X3286348Y2310923D02*
Y2305190D01*
X3286748Y2303989D01*
X3287548Y2303190D01*
X3288548Y2302923D01*
X3289548Y2303190D01*
X3290348Y2303989D01*
X3290748Y2305190D01*
Y2310923D01*
G01X3296548D02*
Y2302923D01*
G01X3294248Y2310923D02*
X3298848D01*
G01X3310648Y2302923D02*
Y2310923D01*
X3314448D01*
G01X3313048Y2307056D02*
X3310648D01*
G01X3320548Y2302923D02*
X3319748Y2303056D01*
X3319048Y2303590D01*
X3318448Y2304390D01*
X3318048Y2305323D01*
X3317848Y2306390D01*
Y2307456D01*
X3318048Y2308523D01*
X3318448Y2309456D01*
X3319048Y2310256D01*
X3319748Y2310790D01*
X3320548Y2310923D01*
X3321348Y2310790D01*
X3322048Y2310256D01*
X3322648Y2309456D01*
X3323048Y2308523D01*
X3323248Y2307456D01*
Y2306390D01*
X3323048Y2305323D01*
X3322648Y2304390D01*
X3322048Y2303590D01*
X3321348Y2303056D01*
X3320548Y2302923D01*
G01X3326548D02*
Y2310923D01*
X3329048D01*
X3329848Y2310523D01*
X3330348Y2309990D01*
X3330548Y2308923D01*
X3330348Y2307856D01*
X3329748Y2307190D01*
X3329048Y2306790D01*
X3326548D01*
G01X3329048D02*
X3330548Y2302923D01*
G01X3342548Y2310923D02*
Y2302923D01*
X3346548D01*
G01X3350048D02*
X3352548Y2310923D01*
X3355048Y2302923D01*
G01X3354148Y2305723D02*
X3350948D01*
G01X3358448Y2303989D02*
X3359248Y2303323D01*
X3360148Y2302923D01*
X3360948D01*
X3361748Y2303323D01*
X3362348Y2303989D01*
X3362648Y2304923D01*
X3362448Y2305856D01*
X3361948Y2306656D01*
X3361048Y2307190D01*
X3359848Y2307456D01*
X3359148Y2307990D01*
X3358848Y2308923D01*
X3359048Y2309856D01*
X3359548Y2310523D01*
X3360248Y2310923D01*
X3360948D01*
X3361648Y2310656D01*
X3362248Y2309990D01*
G01X3370548Y2302923D02*
X3366548D01*
Y2310923D01*
X3370548D01*
G01X3368948Y2307056D02*
X3366548D01*
G01X3374548Y2302923D02*
Y2310923D01*
X3377048D01*
X3377848Y2310523D01*
X3378348Y2309990D01*
X3378548Y2308923D01*
X3378348Y2307856D01*
X3377748Y2307190D01*
X3377048Y2306790D01*
X3374548D01*
G01X3377048D02*
X3378548Y2302923D01*
G01X3390048Y2310923D02*
X3392548Y2302923D01*
X3395048Y2310923D01*
G01X3399348D02*
X3401748D01*
G01X3400548D02*
Y2302923D01*
G01X3399348D02*
X3401748D01*
G01X3406048D02*
X3408548Y2310923D01*
X3411048Y2302923D01*
G01X3410148Y2305723D02*
X3406948D01*
G01X3422448Y2302923D02*
Y2310923D01*
G01X3426648D02*
Y2302923D01*
G01Y2306923D02*
X3422448D01*
G01X3432548Y2302923D02*
X3431748Y2303056D01*
X3431048Y2303590D01*
X3430448Y2304390D01*
X3430048Y2305323D01*
X3429848Y2306390D01*
Y2307456D01*
X3430048Y2308523D01*
X3430448Y2309456D01*
X3431048Y2310256D01*
X3431748Y2310790D01*
X3432548Y2310923D01*
X3433348Y2310790D01*
X3434048Y2310256D01*
X3434648Y2309456D01*
X3435048Y2308523D01*
X3435248Y2307456D01*
Y2306390D01*
X3435048Y2305323D01*
X3434648Y2304390D01*
X3434048Y2303590D01*
X3433348Y2303056D01*
X3432548Y2302923D01*
G01X3438548Y2310923D02*
Y2302923D01*
X3442548D01*
G01X3450548D02*
X3446548D01*
Y2310923D01*
X3450548D01*
G01X3448948Y2307056D02*
X3446548D01*
G01X3456548Y2302656D02*
X3456348Y2302790D01*
Y2303056D01*
X3456548Y2303190D01*
X3456748Y2303056D01*
Y2302790D01*
X3456548Y2302656D01*
G01X3144348Y2317923D02*
X3144548Y2319656D01*
X3144848Y2321123D01*
X3145248Y2322456D01*
X3145748Y2323923D01*
X3146548Y2325923D01*
X3142548D01*
G01X3152548Y2317656D02*
X3152348Y2317790D01*
Y2318056D01*
X3152548Y2318190D01*
X3152748Y2318056D01*
Y2317790D01*
X3152548Y2317656D01*
G01X3158648Y2317923D02*
Y2325923D01*
X3162448D01*
G01X3161048Y2322056D02*
X3158648D01*
G01X3168548Y2317923D02*
X3167748Y2318056D01*
X3167048Y2318590D01*
X3166448Y2319390D01*
X3166048Y2320323D01*
X3165848Y2321390D01*
Y2322456D01*
X3166048Y2323523D01*
X3166448Y2324456D01*
X3167048Y2325256D01*
X3167748Y2325790D01*
X3168548Y2325923D01*
X3169348Y2325790D01*
X3170048Y2325256D01*
X3170648Y2324456D01*
X3171048Y2323523D01*
X3171248Y2322456D01*
Y2321390D01*
X3171048Y2320323D01*
X3170648Y2319390D01*
X3170048Y2318590D01*
X3169348Y2318056D01*
X3168548Y2317923D01*
G01X3174548D02*
Y2325923D01*
X3177048D01*
X3177848Y2325523D01*
X3178348Y2324990D01*
X3178548Y2323923D01*
X3178348Y2322856D01*
X3177748Y2322190D01*
X3177048Y2321790D01*
X3174548D01*
G01X3177048D02*
X3178548Y2317923D01*
G01X3192548D02*
Y2325923D01*
X3191348Y2324323D01*
G01Y2317923D02*
X3193748D01*
G01X3200548Y2325923D02*
X3199748Y2325656D01*
X3199148Y2324990D01*
X3198748Y2324190D01*
X3198448Y2323123D01*
X3198348Y2321923D01*
X3198448Y2320723D01*
X3198748Y2319656D01*
X3199148Y2318856D01*
X3199748Y2318190D01*
X3200548Y2317923D01*
X3201348Y2318190D01*
X3201948Y2318856D01*
X3202348Y2319656D01*
X3202648Y2320723D01*
X3202748Y2321923D01*
X3202648Y2323123D01*
X3202348Y2324190D01*
X3201948Y2324990D01*
X3201348Y2325656D01*
X3200548Y2325923D01*
G01X3205948Y2317923D02*
Y2325923D01*
X3208548Y2319256D01*
X3211148Y2325923D01*
Y2317923D01*
G01X3215348Y2325923D02*
X3217748D01*
G01X3216548D02*
Y2317923D01*
G01X3215348D02*
X3217748D01*
G01X3222548Y2325923D02*
Y2317923D01*
X3226548D01*
G01X3230448Y2318989D02*
X3231248Y2318323D01*
X3232148Y2317923D01*
X3232948D01*
X3233748Y2318323D01*
X3234348Y2318989D01*
X3234648Y2319923D01*
X3234448Y2320856D01*
X3233948Y2321656D01*
X3233048Y2322190D01*
X3231848Y2322456D01*
X3231148Y2322990D01*
X3230848Y2323923D01*
X3231048Y2324856D01*
X3231548Y2325523D01*
X3232248Y2325923D01*
X3232948D01*
X3233648Y2325656D01*
X3234248Y2324990D01*
G01X3246048Y2325923D02*
X3248548Y2317923D01*
X3251048Y2325923D01*
G01X3255348D02*
X3257748D01*
G01X3256548D02*
Y2317923D01*
G01X3255348D02*
X3257748D01*
G01X3262048D02*
X3264548Y2325923D01*
X3267048Y2317923D01*
G01X3266148Y2320723D02*
X3262948D01*
G01X3270448Y2318989D02*
X3271248Y2318323D01*
X3272148Y2317923D01*
X3272948D01*
X3273748Y2318323D01*
X3274348Y2318989D01*
X3274648Y2319923D01*
X3274448Y2320856D01*
X3273948Y2321656D01*
X3273048Y2322190D01*
X3271848Y2322456D01*
X3271148Y2322990D01*
X3270848Y2323923D01*
X3271048Y2324856D01*
X3271548Y2325523D01*
X3272248Y2325923D01*
X3272948D01*
X3273648Y2325656D01*
X3274248Y2324990D01*
G01X3286348Y2325923D02*
Y2320190D01*
X3286748Y2318989D01*
X3287548Y2318190D01*
X3288548Y2317923D01*
X3289548Y2318190D01*
X3290348Y2318989D01*
X3290748Y2320190D01*
Y2325923D01*
G01X3294448Y2318989D02*
X3295248Y2318323D01*
X3296148Y2317923D01*
X3296948D01*
X3297748Y2318323D01*
X3298348Y2318989D01*
X3298648Y2319923D01*
X3298448Y2320856D01*
X3297948Y2321656D01*
X3297048Y2322190D01*
X3295848Y2322456D01*
X3295148Y2322990D01*
X3294848Y2323923D01*
X3295048Y2324856D01*
X3295548Y2325523D01*
X3296248Y2325923D01*
X3296948D01*
X3297648Y2325656D01*
X3298248Y2324990D01*
G01X3306548Y2317923D02*
X3302548D01*
Y2325923D01*
X3306548D01*
G01X3304948Y2322056D02*
X3302548D01*
G01X3318848Y2318856D02*
X3319548Y2318190D01*
X3320348Y2317923D01*
X3321148Y2318190D01*
X3321848Y2318989D01*
X3322348Y2320190D01*
X3322548Y2321390D01*
Y2322856D01*
X3322348Y2324056D01*
X3321848Y2325123D01*
X3321248Y2325656D01*
X3320548Y2325923D01*
X3319748Y2325656D01*
X3319148Y2325123D01*
X3318748Y2324323D01*
X3318548Y2323256D01*
X3318748Y2322323D01*
X3319248Y2321390D01*
X3319848Y2320856D01*
X3320548Y2320723D01*
X3321348Y2320989D01*
X3321948Y2321656D01*
X3322548Y2322856D01*
G01X3328548Y2317656D02*
X3328348Y2317790D01*
Y2318056D01*
X3328548Y2318190D01*
X3328748Y2318056D01*
Y2317790D01*
X3328548Y2317656D01*
G01X3336548Y2317923D02*
X3337248Y2318056D01*
X3338048Y2318456D01*
X3338548Y2319123D01*
X3338748Y2320056D01*
X3338548Y2320989D01*
X3337948Y2321790D01*
X3337048Y2322190D01*
X3336048D01*
X3335448Y2322456D01*
X3334948Y2323123D01*
X3334748Y2324056D01*
X3335048Y2324990D01*
X3335748Y2325656D01*
X3336548Y2325923D01*
X3337348Y2325656D01*
X3338048Y2324990D01*
X3338348Y2324056D01*
X3338148Y2323123D01*
X3337648Y2322456D01*
X3337048Y2322190D01*
X3336048D01*
X3335148Y2321790D01*
X3334548Y2320989D01*
X3334348Y2320056D01*
X3334548Y2319123D01*
X3335048Y2318456D01*
X3335848Y2318056D01*
X3336548Y2317923D01*
G01X3341948D02*
Y2325923D01*
X3344548Y2319256D01*
X3347148Y2325923D01*
Y2317923D01*
G01X3351348Y2325923D02*
X3353748D01*
G01X3352548D02*
Y2317923D01*
G01X3351348D02*
X3353748D01*
G01X3358548Y2325923D02*
Y2317923D01*
X3362548D01*
G01X3366448Y2318989D02*
X3367248Y2318323D01*
X3368148Y2317923D01*
X3368948D01*
X3369748Y2318323D01*
X3370348Y2318989D01*
X3370648Y2319923D01*
X3370448Y2320856D01*
X3369948Y2321656D01*
X3369048Y2322190D01*
X3367848Y2322456D01*
X3367148Y2322990D01*
X3366848Y2323923D01*
X3367048Y2324856D01*
X3367548Y2325523D01*
X3368248Y2325923D01*
X3368948D01*
X3369648Y2325656D01*
X3370248Y2324990D01*
G01X3382348Y2317923D02*
Y2325923D01*
X3384348D01*
X3385148Y2325523D01*
X3385748Y2324990D01*
X3386248Y2324190D01*
X3386648Y2323256D01*
X3386748Y2321923D01*
X3386648Y2320590D01*
X3386248Y2319656D01*
X3385748Y2318856D01*
X3385148Y2318323D01*
X3384348Y2317923D01*
X3382348D01*
G01X3390548D02*
Y2325923D01*
X3393048D01*
X3393848Y2325523D01*
X3394348Y2324990D01*
X3394548Y2323923D01*
X3394348Y2322856D01*
X3393748Y2322190D01*
X3393048Y2321790D01*
X3390548D01*
G01X3393048D02*
X3394548Y2317923D01*
G01X3399348Y2325923D02*
X3401748D01*
G01X3400548D02*
Y2317923D01*
G01X3399348D02*
X3401748D01*
G01X3406548Y2325923D02*
Y2317923D01*
X3410548D01*
G01X3414548Y2325923D02*
Y2317923D01*
X3418548D01*
G01X3433348Y2322190D02*
X3433748Y2322590D01*
X3434048Y2323256D01*
X3434248Y2324190D01*
X3434048Y2324990D01*
X3433648Y2325523D01*
X3432948Y2325923D01*
X3430248D01*
Y2317923D01*
X3433548D01*
X3434248Y2318456D01*
X3434648Y2319256D01*
X3434848Y2320190D01*
X3434648Y2321123D01*
X3434048Y2321923D01*
X3433348Y2322190D01*
X3430248D01*
G01X3439348Y2325923D02*
X3441748D01*
G01X3440548D02*
Y2317923D01*
G01X3439348D02*
X3441748D01*
G01X3448548Y2325923D02*
Y2317923D01*
G01X3446248Y2325923D02*
X3450848D01*
G01X3456548Y2317656D02*
X3456348Y2317790D01*
Y2318056D01*
X3456548Y2318190D01*
X3456748Y2318056D01*
Y2317790D01*
X3456548Y2317656D01*
G01X3470648Y2317923D02*
Y2325923D01*
X3474448D01*
G01X3473048Y2322056D02*
X3470648D01*
G01X3480548Y2317923D02*
X3479748Y2318056D01*
X3479048Y2318590D01*
X3478448Y2319390D01*
X3478048Y2320323D01*
X3477848Y2321390D01*
Y2322456D01*
X3478048Y2323523D01*
X3478448Y2324456D01*
X3479048Y2325256D01*
X3479748Y2325790D01*
X3480548Y2325923D01*
X3481348Y2325790D01*
X3482048Y2325256D01*
X3482648Y2324456D01*
X3483048Y2323523D01*
X3483248Y2322456D01*
Y2321390D01*
X3483048Y2320323D01*
X3482648Y2319390D01*
X3482048Y2318590D01*
X3481348Y2318056D01*
X3480548Y2317923D01*
G01X3486548D02*
Y2325923D01*
X3489048D01*
X3489848Y2325523D01*
X3490348Y2324990D01*
X3490548Y2323923D01*
X3490348Y2322856D01*
X3489748Y2322190D01*
X3489048Y2321790D01*
X3486548D01*
G01X3489048D02*
X3490548Y2317923D01*
G01X3504548D02*
X3505248Y2318056D01*
X3506048Y2318456D01*
X3506548Y2319123D01*
X3506748Y2320056D01*
X3506548Y2320989D01*
X3505948Y2321790D01*
X3505048Y2322190D01*
X3504048D01*
X3503448Y2322456D01*
X3502948Y2323123D01*
X3502748Y2324056D01*
X3503048Y2324990D01*
X3503748Y2325656D01*
X3504548Y2325923D01*
X3505348Y2325656D01*
X3506048Y2324990D01*
X3506348Y2324056D01*
X3506148Y2323123D01*
X3505648Y2322456D01*
X3505048Y2322190D01*
X3504048D01*
X3503148Y2321790D01*
X3502548Y2320989D01*
X3502348Y2320056D01*
X3502548Y2319123D01*
X3503048Y2318456D01*
X3503848Y2318056D01*
X3504548Y2317923D01*
G01X3509948D02*
Y2325923D01*
X3512548Y2319256D01*
X3515148Y2325923D01*
Y2317923D01*
G01X3519348Y2325923D02*
X3521748D01*
G01X3520548D02*
Y2317923D01*
G01X3519348D02*
X3521748D01*
G01X3526548Y2325923D02*
Y2317923D01*
X3530548D01*
G01X3534448Y2318989D02*
X3535248Y2318323D01*
X3536148Y2317923D01*
X3536948D01*
X3537748Y2318323D01*
X3538348Y2318989D01*
X3538648Y2319923D01*
X3538448Y2320856D01*
X3537948Y2321656D01*
X3537048Y2322190D01*
X3535848Y2322456D01*
X3535148Y2322990D01*
X3534848Y2323923D01*
X3535048Y2324856D01*
X3535548Y2325523D01*
X3536248Y2325923D01*
X3536948D01*
X3537648Y2325656D01*
X3538248Y2324990D01*
G01X3550048Y2325923D02*
X3552548Y2317923D01*
X3555048Y2325923D01*
G01X3559348D02*
X3561748D01*
G01X3560548D02*
Y2317923D01*
G01X3559348D02*
X3561748D01*
G01X3566048D02*
X3568548Y2325923D01*
X3571048Y2317923D01*
G01X3570148Y2320723D02*
X3566948D01*
G01X3574448Y2318989D02*
X3575248Y2318323D01*
X3576148Y2317923D01*
X3576948D01*
X3577748Y2318323D01*
X3578348Y2318989D01*
X3578648Y2319923D01*
X3578448Y2320856D01*
X3577948Y2321656D01*
X3577048Y2322190D01*
X3575848Y2322456D01*
X3575148Y2322990D01*
X3574848Y2323923D01*
X3575048Y2324856D01*
X3575548Y2325523D01*
X3576248Y2325923D01*
X3576948D01*
X3577648Y2325656D01*
X3578248Y2324990D01*
G01X3590348Y2325923D02*
Y2320190D01*
X3590748Y2318989D01*
X3591548Y2318190D01*
X3592548Y2317923D01*
X3593548Y2318190D01*
X3594348Y2318989D01*
X3594748Y2320190D01*
Y2325923D01*
G01X3598448Y2318989D02*
X3599248Y2318323D01*
X3600148Y2317923D01*
X3600948D01*
X3601748Y2318323D01*
X3602348Y2318989D01*
X3602648Y2319923D01*
X3602448Y2320856D01*
X3601948Y2321656D01*
X3601048Y2322190D01*
X3599848Y2322456D01*
X3599148Y2322990D01*
X3598848Y2323923D01*
X3599048Y2324856D01*
X3599548Y2325523D01*
X3600248Y2325923D01*
X3600948D01*
X3601648Y2325656D01*
X3602248Y2324990D01*
G01X3610548Y2317923D02*
X3606548D01*
Y2325923D01*
X3610548D01*
G01X3608948Y2322056D02*
X3606548D01*
G01X3624348Y2317923D02*
X3624548Y2319656D01*
X3624848Y2321123D01*
X3625248Y2322456D01*
X3625748Y2323923D01*
X3626548Y2325923D01*
X3622548D01*
G01X3632548Y2317656D02*
X3632348Y2317790D01*
Y2318056D01*
X3632548Y2318190D01*
X3632748Y2318056D01*
Y2317790D01*
X3632548Y2317656D01*
G01X3638848Y2318856D02*
X3639548Y2318190D01*
X3640348Y2317923D01*
X3641148Y2318190D01*
X3641848Y2318989D01*
X3642348Y2320190D01*
X3642548Y2321390D01*
Y2322856D01*
X3642348Y2324056D01*
X3641848Y2325123D01*
X3641248Y2325656D01*
X3640548Y2325923D01*
X3639748Y2325656D01*
X3639148Y2325123D01*
X3638748Y2324323D01*
X3638548Y2323256D01*
X3638748Y2322323D01*
X3639248Y2321390D01*
X3639848Y2320856D01*
X3640548Y2320723D01*
X3641348Y2320989D01*
X3641948Y2321656D01*
X3642548Y2322856D01*
G01X3645948Y2317923D02*
Y2325923D01*
X3648548Y2319256D01*
X3651148Y2325923D01*
Y2317923D01*
G01X3655348Y2325923D02*
X3657748D01*
G01X3656548D02*
Y2317923D01*
G01X3655348D02*
X3657748D01*
G01X3662548Y2325923D02*
Y2317923D01*
X3666548D01*
G01X3670448Y2318989D02*
X3671248Y2318323D01*
X3672148Y2317923D01*
X3672948D01*
X3673748Y2318323D01*
X3674348Y2318989D01*
X3674648Y2319923D01*
X3674448Y2320856D01*
X3673948Y2321656D01*
X3673048Y2322190D01*
X3671848Y2322456D01*
X3671148Y2322990D01*
X3670848Y2323923D01*
X3671048Y2324856D01*
X3671548Y2325523D01*
X3672248Y2325923D01*
X3672948D01*
X3673648Y2325656D01*
X3674248Y2324990D01*
G01X3686348Y2317923D02*
Y2325923D01*
X3688348D01*
X3689148Y2325523D01*
X3689748Y2324990D01*
X3690248Y2324190D01*
X3690648Y2323256D01*
X3690748Y2321923D01*
X3690648Y2320590D01*
X3690248Y2319656D01*
X3689748Y2318856D01*
X3689148Y2318323D01*
X3688348Y2317923D01*
X3686348D01*
G01X3694548D02*
Y2325923D01*
X3697048D01*
X3697848Y2325523D01*
X3698348Y2324990D01*
X3698548Y2323923D01*
X3698348Y2322856D01*
X3697748Y2322190D01*
X3697048Y2321790D01*
X3694548D01*
G01X3697048D02*
X3698548Y2317923D01*
G01X3703348Y2325923D02*
X3705748D01*
G01X3704548D02*
Y2317923D01*
G01X3703348D02*
X3705748D01*
G01X3710548Y2325923D02*
Y2317923D01*
X3714548D01*
G01X3718548Y2325923D02*
Y2317923D01*
X3722548D01*
G01X3737348Y2322190D02*
X3737748Y2322590D01*
X3738048Y2323256D01*
X3738248Y2324190D01*
X3738048Y2324990D01*
X3737648Y2325523D01*
X3736948Y2325923D01*
X3734248D01*
Y2317923D01*
X3737548D01*
X3738248Y2318456D01*
X3738648Y2319256D01*
X3738848Y2320190D01*
X3738648Y2321123D01*
X3738048Y2321923D01*
X3737348Y2322190D01*
X3734248D01*
G01X3743348Y2325923D02*
X3745748D01*
G01X3744548D02*
Y2317923D01*
G01X3743348D02*
X3745748D01*
G01X3752548Y2325923D02*
Y2317923D01*
G01X3750248Y2325923D02*
X3754848D01*
G01X3760548Y2317656D02*
X3760348Y2317790D01*
Y2318056D01*
X3760548Y2318190D01*
X3760748Y2318056D01*
Y2317790D01*
X3760548Y2317656D01*
G01X3766648Y2317923D02*
Y2325923D01*
X3770448D01*
G01X3769048Y2322056D02*
X3766648D01*
G01X3776548Y2317923D02*
X3775748Y2318056D01*
X3775048Y2318590D01*
X3774448Y2319390D01*
X3774048Y2320323D01*
X3773848Y2321390D01*
Y2322456D01*
X3774048Y2323523D01*
X3774448Y2324456D01*
X3775048Y2325256D01*
X3775748Y2325790D01*
X3776548Y2325923D01*
X3777348Y2325790D01*
X3778048Y2325256D01*
X3778648Y2324456D01*
X3779048Y2323523D01*
X3779248Y2322456D01*
Y2321390D01*
X3779048Y2320323D01*
X3778648Y2319390D01*
X3778048Y2318590D01*
X3777348Y2318056D01*
X3776548Y2317923D01*
G01X3782548D02*
Y2325923D01*
X3785048D01*
X3785848Y2325523D01*
X3786348Y2324990D01*
X3786548Y2323923D01*
X3786348Y2322856D01*
X3785748Y2322190D01*
X3785048Y2321790D01*
X3782548D01*
G01X3785048D02*
X3786548Y2317923D01*
G01X3798648Y2324590D02*
X3799248Y2325390D01*
X3799948Y2325790D01*
X3800748Y2325923D01*
X3801748Y2325656D01*
X3802448Y2324990D01*
X3802648Y2324190D01*
X3802548Y2323389D01*
X3802148Y2322723D01*
X3800148Y2321390D01*
X3799248Y2320456D01*
X3798648Y2319123D01*
X3798448Y2317923D01*
X3802648D01*
G01X3808548Y2325923D02*
X3807748Y2325656D01*
X3807148Y2324990D01*
X3806748Y2324190D01*
X3806448Y2323123D01*
X3806348Y2321923D01*
X3806448Y2320723D01*
X3806748Y2319656D01*
X3807148Y2318856D01*
X3807748Y2318190D01*
X3808548Y2317923D01*
X3809348Y2318190D01*
X3809948Y2318856D01*
X3810348Y2319656D01*
X3810648Y2320723D01*
X3810748Y2321923D01*
X3810648Y2323123D01*
X3810348Y2324190D01*
X3809948Y2324990D01*
X3809348Y2325656D01*
X3808548Y2325923D01*
G01X3813948Y2317923D02*
Y2325923D01*
X3816548Y2319256D01*
X3819148Y2325923D01*
Y2317923D01*
G01X3823348Y2325923D02*
X3825748D01*
G01X3824548D02*
Y2317923D01*
G01X3823348D02*
X3825748D01*
G01X3830548Y2325923D02*
Y2317923D01*
X3834548D01*
G01X3838448Y2318989D02*
X3839248Y2318323D01*
X3840148Y2317923D01*
X3840948D01*
X3841748Y2318323D01*
X3842348Y2318989D01*
X3842648Y2319923D01*
X3842448Y2320856D01*
X3841948Y2321656D01*
X3841048Y2322190D01*
X3839848Y2322456D01*
X3839148Y2322990D01*
X3838848Y2323923D01*
X3839048Y2324856D01*
X3839548Y2325523D01*
X3840248Y2325923D01*
X3840948D01*
X3841648Y2325656D01*
X3842248Y2324990D01*
G01X3854048Y2325923D02*
X3856548Y2317923D01*
X3859048Y2325923D01*
G01X3863348D02*
X3865748D01*
G01X3864548D02*
Y2317923D01*
G01X3863348D02*
X3865748D01*
G01X3870048D02*
X3872548Y2325923D01*
X3875048Y2317923D01*
G01X3874148Y2320723D02*
X3870948D01*
G01X3878448Y2318989D02*
X3879248Y2318323D01*
X3880148Y2317923D01*
X3880948D01*
X3881748Y2318323D01*
X3882348Y2318989D01*
X3882648Y2319923D01*
X3882448Y2320856D01*
X3881948Y2321656D01*
X3881048Y2322190D01*
X3879848Y2322456D01*
X3879148Y2322990D01*
X3878848Y2323923D01*
X3879048Y2324856D01*
X3879548Y2325523D01*
X3880248Y2325923D01*
X3880948D01*
X3881648Y2325656D01*
X3882248Y2324990D01*
G01X3894348Y2325923D02*
Y2320190D01*
X3894748Y2318989D01*
X3895548Y2318190D01*
X3896548Y2317923D01*
X3897548Y2318190D01*
X3898348Y2318989D01*
X3898748Y2320190D01*
Y2325923D01*
G01X3902448Y2318989D02*
X3903248Y2318323D01*
X3904148Y2317923D01*
X3904948D01*
X3905748Y2318323D01*
X3906348Y2318989D01*
X3906648Y2319923D01*
X3906448Y2320856D01*
X3905948Y2321656D01*
X3905048Y2322190D01*
X3903848Y2322456D01*
X3903148Y2322990D01*
X3902848Y2323923D01*
X3903048Y2324856D01*
X3903548Y2325523D01*
X3904248Y2325923D01*
X3904948D01*
X3905648Y2325656D01*
X3906248Y2324990D01*
G01X3914548Y2317923D02*
X3910548D01*
Y2325923D01*
X3914548D01*
G01X3912948Y2322056D02*
X3910548D01*
G01X3928548Y2317923D02*
Y2325923D01*
X3927348Y2324323D01*
G01Y2317923D02*
X3929748D01*
G01X3934848Y2318856D02*
X3935548Y2318190D01*
X3936348Y2317923D01*
X3937148Y2318190D01*
X3937848Y2318989D01*
X3938348Y2320190D01*
X3938548Y2321390D01*
Y2322856D01*
X3938348Y2324056D01*
X3937848Y2325123D01*
X3937248Y2325656D01*
X3936548Y2325923D01*
X3935748Y2325656D01*
X3935148Y2325123D01*
X3934748Y2324323D01*
X3934548Y2323256D01*
X3934748Y2322323D01*
X3935248Y2321390D01*
X3935848Y2320856D01*
X3936548Y2320723D01*
X3937348Y2320989D01*
X3937948Y2321656D01*
X3938548Y2322856D01*
G01X3944548Y2317656D02*
X3944348Y2317790D01*
Y2318056D01*
X3944548Y2318190D01*
X3944748Y2318056D01*
Y2317790D01*
X3944548Y2317656D01*
G01X3952348Y2317923D02*
X3952548Y2319656D01*
X3952848Y2321123D01*
X3953248Y2322456D01*
X3953748Y2323923D01*
X3954548Y2325923D01*
X3950548D01*
G01X3957948Y2317923D02*
Y2325923D01*
X3960548Y2319256D01*
X3963148Y2325923D01*
Y2317923D01*
G01X3967348Y2325923D02*
X3969748D01*
G01X3968548D02*
Y2317923D01*
G01X3967348D02*
X3969748D01*
G01X3974548Y2325923D02*
Y2317923D01*
X3978548D01*
G01X3982448Y2318989D02*
X3983248Y2318323D01*
X3984148Y2317923D01*
X3984948D01*
X3985748Y2318323D01*
X3986348Y2318989D01*
X3986648Y2319923D01*
X3986448Y2320856D01*
X3985948Y2321656D01*
X3985048Y2322190D01*
X3983848Y2322456D01*
X3983148Y2322990D01*
X3982848Y2323923D01*
X3983048Y2324856D01*
X3983548Y2325523D01*
X3984248Y2325923D01*
X3984948D01*
X3985648Y2325656D01*
X3986248Y2324990D01*
G01X3998348Y2317923D02*
Y2325923D01*
X4000348D01*
X4001148Y2325523D01*
X4001748Y2324990D01*
X4002248Y2324190D01*
X4002648Y2323256D01*
X4002748Y2321923D01*
X4002648Y2320590D01*
X4002248Y2319656D01*
X4001748Y2318856D01*
X4001148Y2318323D01*
X4000348Y2317923D01*
X3998348D01*
G01X4006548D02*
Y2325923D01*
X4009048D01*
X4009848Y2325523D01*
X4010348Y2324990D01*
X4010548Y2323923D01*
X4010348Y2322856D01*
X4009748Y2322190D01*
X4009048Y2321790D01*
X4006548D01*
G01X4009048D02*
X4010548Y2317923D01*
G01X4015348Y2325923D02*
X4017748D01*
G01X4016548D02*
Y2317923D01*
G01X4015348D02*
X4017748D01*
G01X4022548Y2325923D02*
Y2317923D01*
X4026548D01*
G01X4030548Y2325923D02*
Y2317923D01*
X4034548D01*
G01X4049348Y2322190D02*
X4049748Y2322590D01*
X4050048Y2323256D01*
X4050248Y2324190D01*
X4050048Y2324990D01*
X4049648Y2325523D01*
X4048948Y2325923D01*
X4046248D01*
Y2317923D01*
X4049548D01*
X4050248Y2318456D01*
X4050648Y2319256D01*
X4050848Y2320190D01*
X4050648Y2321123D01*
X4050048Y2321923D01*
X4049348Y2322190D01*
X4046248D01*
G01X4055348Y2325923D02*
X4057748D01*
G01X4056548D02*
Y2317923D01*
G01X4055348D02*
X4057748D01*
G01X4064548Y2325923D02*
Y2317923D01*
G01X4062248Y2325923D02*
X4066848D01*
G01X4072548Y2317656D02*
X4072348Y2317790D01*
Y2318056D01*
X4072548Y2318190D01*
X4072748Y2318056D01*
Y2317790D01*
X4072548Y2317656D01*
G01X3142648Y2336256D02*
X3143348Y2337190D01*
X3143948Y2337723D01*
X3144748Y2337990D01*
X3145448Y2337723D01*
X3145948Y2337190D01*
X3146348Y2336390D01*
X3146448Y2335456D01*
X3146348Y2334656D01*
X3145948Y2333856D01*
X3145348Y2333190D01*
X3144648Y2332923D01*
X3143848Y2333190D01*
X3143148Y2333989D01*
X3142748Y2335190D01*
X3142648Y2336523D01*
X3142848Y2338256D01*
X3143148Y2339190D01*
X3143648Y2340123D01*
X3144348Y2340790D01*
X3145048Y2340923D01*
X3145748Y2340656D01*
X3146248Y2339990D01*
G01X3152548Y2332656D02*
X3152348Y2332790D01*
Y2333056D01*
X3152548Y2333190D01*
X3152748Y2333056D01*
Y2332790D01*
X3152548Y2332656D01*
G01X3158648Y2339590D02*
X3159248Y2340390D01*
X3159948Y2340790D01*
X3160748Y2340923D01*
X3161748Y2340656D01*
X3162448Y2339990D01*
X3162648Y2339190D01*
X3162548Y2338389D01*
X3162148Y2337723D01*
X3160148Y2336390D01*
X3159248Y2335456D01*
X3158648Y2334123D01*
X3158448Y2332923D01*
X3162648D01*
G01X3176548D02*
X3175748Y2333056D01*
X3175048Y2333590D01*
X3174448Y2334390D01*
X3174048Y2335323D01*
X3173848Y2336390D01*
Y2337456D01*
X3174048Y2338523D01*
X3174448Y2339456D01*
X3175048Y2340256D01*
X3175748Y2340790D01*
X3176548Y2340923D01*
X3177348Y2340790D01*
X3178048Y2340256D01*
X3178648Y2339456D01*
X3179048Y2338523D01*
X3179248Y2337456D01*
Y2336390D01*
X3179048Y2335323D01*
X3178648Y2334390D01*
X3178048Y2333590D01*
X3177348Y2333056D01*
X3176548Y2332923D01*
G01X3182348Y2340923D02*
Y2335190D01*
X3182748Y2333989D01*
X3183548Y2333190D01*
X3184548Y2332923D01*
X3185548Y2333190D01*
X3186348Y2333989D01*
X3186748Y2335190D01*
Y2340923D01*
G01X3192548D02*
Y2332923D01*
G01X3190248Y2340923D02*
X3194848D01*
G01X3198448Y2333989D02*
X3199248Y2333323D01*
X3200148Y2332923D01*
X3200948D01*
X3201748Y2333323D01*
X3202348Y2333989D01*
X3202648Y2334923D01*
X3202448Y2335856D01*
X3201948Y2336656D01*
X3201048Y2337190D01*
X3199848Y2337456D01*
X3199148Y2337990D01*
X3198848Y2338923D01*
X3199048Y2339856D01*
X3199548Y2340523D01*
X3200248Y2340923D01*
X3200948D01*
X3201648Y2340656D01*
X3202248Y2339990D01*
G01X3207348Y2340923D02*
X3209748D01*
G01X3208548D02*
Y2332923D01*
G01X3207348D02*
X3209748D01*
G01X3214348D02*
Y2340923D01*
X3216348D01*
X3217148Y2340523D01*
X3217748Y2339990D01*
X3218248Y2339190D01*
X3218648Y2338256D01*
X3218748Y2336923D01*
X3218648Y2335590D01*
X3218248Y2334656D01*
X3217748Y2333856D01*
X3217148Y2333323D01*
X3216348Y2332923D01*
X3214348D01*
G01X3226548D02*
X3222548D01*
Y2340923D01*
X3226548D01*
G01X3224948Y2337056D02*
X3222548D01*
G01X3241348Y2337190D02*
X3241748Y2337590D01*
X3242048Y2338256D01*
X3242248Y2339190D01*
X3242048Y2339990D01*
X3241648Y2340523D01*
X3240948Y2340923D01*
X3238248D01*
Y2332923D01*
X3241548D01*
X3242248Y2333456D01*
X3242648Y2334256D01*
X3242848Y2335190D01*
X3242648Y2336123D01*
X3242048Y2336923D01*
X3241348Y2337190D01*
X3238248D01*
G01X3248548Y2332923D02*
X3247748Y2333056D01*
X3247048Y2333590D01*
X3246448Y2334390D01*
X3246048Y2335323D01*
X3245848Y2336390D01*
Y2337456D01*
X3246048Y2338523D01*
X3246448Y2339456D01*
X3247048Y2340256D01*
X3247748Y2340790D01*
X3248548Y2340923D01*
X3249348Y2340790D01*
X3250048Y2340256D01*
X3250648Y2339456D01*
X3251048Y2338523D01*
X3251248Y2337456D01*
Y2336390D01*
X3251048Y2335323D01*
X3250648Y2334390D01*
X3250048Y2333590D01*
X3249348Y2333056D01*
X3248548Y2332923D01*
G01X3254048D02*
X3256548Y2340923D01*
X3259048Y2332923D01*
G01X3258148Y2335723D02*
X3254948D01*
G01X3262548Y2332923D02*
Y2340923D01*
X3265048D01*
X3265848Y2340523D01*
X3266348Y2339990D01*
X3266548Y2338923D01*
X3266348Y2337856D01*
X3265748Y2337190D01*
X3265048Y2336790D01*
X3262548D01*
G01X3265048D02*
X3266548Y2332923D01*
G01X3270348D02*
Y2340923D01*
X3272348D01*
X3273148Y2340523D01*
X3273748Y2339990D01*
X3274248Y2339190D01*
X3274648Y2338256D01*
X3274748Y2336923D01*
X3274648Y2335590D01*
X3274248Y2334656D01*
X3273748Y2333856D01*
X3273148Y2333323D01*
X3272348Y2332923D01*
X3270348D01*
G01X3288548D02*
X3287748Y2333056D01*
X3287048Y2333590D01*
X3286448Y2334390D01*
X3286048Y2335323D01*
X3285848Y2336390D01*
Y2337456D01*
X3286048Y2338523D01*
X3286448Y2339456D01*
X3287048Y2340256D01*
X3287748Y2340790D01*
X3288548Y2340923D01*
X3289348Y2340790D01*
X3290048Y2340256D01*
X3290648Y2339456D01*
X3291048Y2338523D01*
X3291248Y2337456D01*
Y2336390D01*
X3291048Y2335323D01*
X3290648Y2334390D01*
X3290048Y2333590D01*
X3289348Y2333056D01*
X3288548Y2332923D01*
G01X3294348Y2340923D02*
Y2335190D01*
X3294748Y2333989D01*
X3295548Y2333190D01*
X3296548Y2332923D01*
X3297548Y2333190D01*
X3298348Y2333989D01*
X3298748Y2335190D01*
Y2340923D01*
G01X3304548D02*
Y2332923D01*
G01X3302248Y2340923D02*
X3306848D01*
G01X3310548D02*
Y2332923D01*
X3314548D01*
G01X3319348Y2340923D02*
X3321748D01*
G01X3320548D02*
Y2332923D01*
G01X3319348D02*
X3321748D01*
G01X3326248D02*
Y2340923D01*
X3330848Y2332923D01*
Y2340923D01*
G01X3338548Y2332923D02*
X3334548D01*
Y2340923D01*
X3338548D01*
G01X3336948Y2337056D02*
X3334548D01*
G01X3350648Y2332923D02*
Y2340923D01*
X3354448D01*
G01X3353048Y2337056D02*
X3350648D01*
G01X3360548Y2332923D02*
X3359748Y2333056D01*
X3359048Y2333590D01*
X3358448Y2334390D01*
X3358048Y2335323D01*
X3357848Y2336390D01*
Y2337456D01*
X3358048Y2338523D01*
X3358448Y2339456D01*
X3359048Y2340256D01*
X3359748Y2340790D01*
X3360548Y2340923D01*
X3361348Y2340790D01*
X3362048Y2340256D01*
X3362648Y2339456D01*
X3363048Y2338523D01*
X3363248Y2337456D01*
Y2336390D01*
X3363048Y2335323D01*
X3362648Y2334390D01*
X3362048Y2333590D01*
X3361348Y2333056D01*
X3360548Y2332923D01*
G01X3366548Y2340923D02*
Y2332923D01*
X3370548D01*
G01X3374548Y2340923D02*
Y2332923D01*
X3378548D01*
G01X3384548D02*
X3383748Y2333056D01*
X3383048Y2333590D01*
X3382448Y2334390D01*
X3382048Y2335323D01*
X3381848Y2336390D01*
Y2337456D01*
X3382048Y2338523D01*
X3382448Y2339456D01*
X3383048Y2340256D01*
X3383748Y2340790D01*
X3384548Y2340923D01*
X3385348Y2340790D01*
X3386048Y2340256D01*
X3386648Y2339456D01*
X3387048Y2338523D01*
X3387248Y2337456D01*
Y2336390D01*
X3387048Y2335323D01*
X3386648Y2334390D01*
X3386048Y2333590D01*
X3385348Y2333056D01*
X3384548Y2332923D01*
G01X3389548Y2340923D02*
X3390948Y2332923D01*
X3392548Y2340923D01*
X3394148Y2332923D01*
X3395548Y2340923D01*
G01X3406548Y2332923D02*
Y2340923D01*
X3408948D01*
X3409748Y2340523D01*
X3410348Y2339590D01*
X3410548Y2338523D01*
X3410348Y2337456D01*
X3409848Y2336656D01*
X3408948Y2336256D01*
X3406548D01*
G01X3418748Y2340256D02*
X3418148Y2340656D01*
X3417448Y2340923D01*
X3416648D01*
X3415748Y2340523D01*
X3415048Y2339856D01*
X3414548Y2339056D01*
X3414148Y2337723D01*
X3414048Y2336523D01*
X3414248Y2335323D01*
X3414548Y2334523D01*
X3415148Y2333723D01*
X3415848Y2333190D01*
X3416548Y2332923D01*
X3417248D01*
X3417948Y2333190D01*
X3418548Y2333590D01*
X3419048Y2334123D01*
G01X3425348Y2337190D02*
X3425748Y2337590D01*
X3426048Y2338256D01*
X3426248Y2339190D01*
X3426048Y2339990D01*
X3425648Y2340523D01*
X3424948Y2340923D01*
X3422248D01*
Y2332923D01*
X3425548D01*
X3426248Y2333456D01*
X3426648Y2334256D01*
X3426848Y2335190D01*
X3426648Y2336123D01*
X3426048Y2336923D01*
X3425348Y2337190D01*
X3422248D01*
G01X3438448Y2333989D02*
X3439248Y2333323D01*
X3440148Y2332923D01*
X3440948D01*
X3441748Y2333323D01*
X3442348Y2333989D01*
X3442648Y2334923D01*
X3442448Y2335856D01*
X3441948Y2336656D01*
X3441048Y2337190D01*
X3439848Y2337456D01*
X3439148Y2337990D01*
X3438848Y2338923D01*
X3439048Y2339856D01*
X3439548Y2340523D01*
X3440248Y2340923D01*
X3440948D01*
X3441648Y2340656D01*
X3442248Y2339990D01*
G01X3446448Y2332923D02*
Y2340923D01*
G01X3450648D02*
Y2332923D01*
G01Y2336923D02*
X3446448D01*
G01X3456548Y2332923D02*
X3455748Y2333056D01*
X3455048Y2333590D01*
X3454448Y2334390D01*
X3454048Y2335323D01*
X3453848Y2336390D01*
Y2337456D01*
X3454048Y2338523D01*
X3454448Y2339456D01*
X3455048Y2340256D01*
X3455748Y2340790D01*
X3456548Y2340923D01*
X3457348Y2340790D01*
X3458048Y2340256D01*
X3458648Y2339456D01*
X3459048Y2338523D01*
X3459248Y2337456D01*
Y2336390D01*
X3459048Y2335323D01*
X3458648Y2334390D01*
X3458048Y2333590D01*
X3457348Y2333056D01*
X3456548Y2332923D01*
G01X3462548D02*
Y2340923D01*
X3464948D01*
X3465748Y2340523D01*
X3466348Y2339590D01*
X3466548Y2338523D01*
X3466348Y2337456D01*
X3465848Y2336656D01*
X3464948Y2336256D01*
X3462548D01*
G01X3478548Y2332923D02*
Y2340923D01*
X3480948D01*
X3481748Y2340523D01*
X3482348Y2339590D01*
X3482548Y2338523D01*
X3482348Y2337456D01*
X3481848Y2336656D01*
X3480948Y2336256D01*
X3478548D01*
G01X3486548Y2332923D02*
Y2340923D01*
X3489048D01*
X3489848Y2340523D01*
X3490348Y2339990D01*
X3490548Y2338923D01*
X3490348Y2337856D01*
X3489748Y2337190D01*
X3489048Y2336790D01*
X3486548D01*
G01X3489048D02*
X3490548Y2332923D01*
G01X3498548D02*
X3494548D01*
Y2340923D01*
X3498548D01*
G01X3496948Y2337056D02*
X3494548D01*
G01X3502648Y2332923D02*
Y2340923D01*
X3506448D01*
G01X3505048Y2337056D02*
X3502648D01*
G01X3514548Y2332923D02*
X3510548D01*
Y2340923D01*
X3514548D01*
G01X3512948Y2337056D02*
X3510548D01*
G01X3518548Y2332923D02*
Y2340923D01*
X3521048D01*
X3521848Y2340523D01*
X3522348Y2339990D01*
X3522548Y2338923D01*
X3522348Y2337856D01*
X3521748Y2337190D01*
X3521048Y2336790D01*
X3518548D01*
G01X3521048D02*
X3522548Y2332923D01*
G01X3530548D02*
X3526548D01*
Y2340923D01*
X3530548D01*
G01X3528948Y2337056D02*
X3526548D01*
G01X3534248Y2332923D02*
Y2340923D01*
X3538848Y2332923D01*
Y2340923D01*
G01X3546748Y2340256D02*
X3546148Y2340656D01*
X3545448Y2340923D01*
X3544648D01*
X3543748Y2340523D01*
X3543048Y2339856D01*
X3542548Y2339056D01*
X3542148Y2337723D01*
X3542048Y2336523D01*
X3542248Y2335323D01*
X3542548Y2334523D01*
X3543148Y2333723D01*
X3543848Y2333190D01*
X3544548Y2332923D01*
X3545248D01*
X3545948Y2333190D01*
X3546548Y2333590D01*
X3547048Y2334123D01*
G01X3554548Y2332923D02*
X3550548D01*
Y2340923D01*
X3554548D01*
G01X3552948Y2337056D02*
X3550548D01*
G01X3569348Y2337190D02*
X3569748Y2337590D01*
X3570048Y2338256D01*
X3570248Y2339190D01*
X3570048Y2339990D01*
X3569648Y2340523D01*
X3568948Y2340923D01*
X3566248D01*
Y2332923D01*
X3569548D01*
X3570248Y2333456D01*
X3570648Y2334256D01*
X3570848Y2335190D01*
X3570648Y2336123D01*
X3570048Y2336923D01*
X3569348Y2337190D01*
X3566248D01*
G01X3574348Y2340923D02*
Y2335190D01*
X3574748Y2333989D01*
X3575548Y2333190D01*
X3576548Y2332923D01*
X3577548Y2333190D01*
X3578348Y2333989D01*
X3578748Y2335190D01*
Y2340923D01*
G01X3584548D02*
Y2332923D01*
G01X3582248Y2340923D02*
X3586848D01*
G01X3602748Y2340256D02*
X3602148Y2340656D01*
X3601448Y2340923D01*
X3600648D01*
X3599748Y2340523D01*
X3599048Y2339856D01*
X3598548Y2339056D01*
X3598148Y2337723D01*
X3598048Y2336523D01*
X3598248Y2335323D01*
X3598548Y2334523D01*
X3599148Y2333723D01*
X3599848Y2333190D01*
X3600548Y2332923D01*
X3601248D01*
X3601948Y2333190D01*
X3602548Y2333590D01*
X3603048Y2334123D01*
G01X3608548Y2332923D02*
X3607748Y2333056D01*
X3607048Y2333590D01*
X3606448Y2334390D01*
X3606048Y2335323D01*
X3605848Y2336390D01*
Y2337456D01*
X3606048Y2338523D01*
X3606448Y2339456D01*
X3607048Y2340256D01*
X3607748Y2340790D01*
X3608548Y2340923D01*
X3609348Y2340790D01*
X3610048Y2340256D01*
X3610648Y2339456D01*
X3611048Y2338523D01*
X3611248Y2337456D01*
Y2336390D01*
X3611048Y2335323D01*
X3610648Y2334390D01*
X3610048Y2333590D01*
X3609348Y2333056D01*
X3608548Y2332923D01*
G01X3614348Y2340923D02*
Y2335190D01*
X3614748Y2333989D01*
X3615548Y2333190D01*
X3616548Y2332923D01*
X3617548Y2333190D01*
X3618348Y2333989D01*
X3618748Y2335190D01*
Y2340923D01*
G01X3622548Y2332923D02*
Y2340923D01*
X3624948D01*
X3625748Y2340523D01*
X3626348Y2339590D01*
X3626548Y2338523D01*
X3626348Y2337456D01*
X3625848Y2336656D01*
X3624948Y2336256D01*
X3622548D01*
G01X3632548Y2332923D02*
X3631748Y2333056D01*
X3631048Y2333590D01*
X3630448Y2334390D01*
X3630048Y2335323D01*
X3629848Y2336390D01*
Y2337456D01*
X3630048Y2338523D01*
X3630448Y2339456D01*
X3631048Y2340256D01*
X3631748Y2340790D01*
X3632548Y2340923D01*
X3633348Y2340790D01*
X3634048Y2340256D01*
X3634648Y2339456D01*
X3635048Y2338523D01*
X3635248Y2337456D01*
Y2336390D01*
X3635048Y2335323D01*
X3634648Y2334390D01*
X3634048Y2333590D01*
X3633348Y2333056D01*
X3632548Y2332923D01*
G01X3638248D02*
Y2340923D01*
X3642848Y2332923D01*
Y2340923D01*
G01X3646748Y2332656D02*
X3650348Y2340923D01*
G01X3654648Y2332923D02*
Y2340923D01*
X3658448D01*
G01X3657048Y2337056D02*
X3654648D01*
G01X3663348Y2340923D02*
X3665748D01*
G01X3664548D02*
Y2332923D01*
G01X3663348D02*
X3665748D01*
G01X3670348D02*
Y2340923D01*
X3672348D01*
X3673148Y2340523D01*
X3673748Y2339990D01*
X3674248Y2339190D01*
X3674648Y2338256D01*
X3674748Y2336923D01*
X3674648Y2335590D01*
X3674248Y2334656D01*
X3673748Y2333856D01*
X3673148Y2333323D01*
X3672348Y2332923D01*
X3670348D01*
G01X3678348Y2340923D02*
Y2335190D01*
X3678748Y2333989D01*
X3679548Y2333190D01*
X3680548Y2332923D01*
X3681548Y2333190D01*
X3682348Y2333989D01*
X3682748Y2335190D01*
Y2340923D01*
G01X3690748Y2340256D02*
X3690148Y2340656D01*
X3689448Y2340923D01*
X3688648D01*
X3687748Y2340523D01*
X3687048Y2339856D01*
X3686548Y2339056D01*
X3686148Y2337723D01*
X3686048Y2336523D01*
X3686248Y2335323D01*
X3686548Y2334523D01*
X3687148Y2333723D01*
X3687848Y2333190D01*
X3688548Y2332923D01*
X3689248D01*
X3689948Y2333190D01*
X3690548Y2333590D01*
X3691048Y2334123D01*
G01X3695348Y2340923D02*
X3697748D01*
G01X3696548D02*
Y2332923D01*
G01X3695348D02*
X3697748D01*
G01X3702048D02*
X3704548Y2340923D01*
X3707048Y2332923D01*
G01X3706148Y2335723D02*
X3702948D01*
G01X3710548Y2340923D02*
Y2332923D01*
X3714548D01*
G01X3725948D02*
Y2340923D01*
X3728548Y2334256D01*
X3731148Y2340923D01*
Y2332923D01*
G01X3734048D02*
X3736548Y2340923D01*
X3739048Y2332923D01*
G01X3738148Y2335723D02*
X3734948D01*
G01X3742548Y2332923D02*
Y2340923D01*
X3745048D01*
X3745848Y2340523D01*
X3746348Y2339990D01*
X3746548Y2338923D01*
X3746348Y2337856D01*
X3745748Y2337190D01*
X3745048Y2336790D01*
X3742548D01*
G01X3745048D02*
X3746548Y2332923D01*
G01X3750348D02*
Y2340923D01*
G01X3754148D02*
X3750348Y2335989D01*
G01X3754748Y2332923D02*
X3752048Y2338256D01*
G01X3758748Y2332656D02*
X3762348Y2340923D01*
G01X3768548D02*
Y2332923D01*
G01X3766248Y2340923D02*
X3770848D01*
G01X3776548Y2332923D02*
X3775748Y2333056D01*
X3775048Y2333590D01*
X3774448Y2334390D01*
X3774048Y2335323D01*
X3773848Y2336390D01*
Y2337456D01*
X3774048Y2338523D01*
X3774448Y2339456D01*
X3775048Y2340256D01*
X3775748Y2340790D01*
X3776548Y2340923D01*
X3777348Y2340790D01*
X3778048Y2340256D01*
X3778648Y2339456D01*
X3779048Y2338523D01*
X3779248Y2337456D01*
Y2336390D01*
X3779048Y2335323D01*
X3778648Y2334390D01*
X3778048Y2333590D01*
X3777348Y2333056D01*
X3776548Y2332923D01*
G01X3784548D02*
X3783748Y2333056D01*
X3783048Y2333590D01*
X3782448Y2334390D01*
X3782048Y2335323D01*
X3781848Y2336390D01*
Y2337456D01*
X3782048Y2338523D01*
X3782448Y2339456D01*
X3783048Y2340256D01*
X3783748Y2340790D01*
X3784548Y2340923D01*
X3785348Y2340790D01*
X3786048Y2340256D01*
X3786648Y2339456D01*
X3787048Y2338523D01*
X3787248Y2337456D01*
Y2336390D01*
X3787048Y2335323D01*
X3786648Y2334390D01*
X3786048Y2333590D01*
X3785348Y2333056D01*
X3784548Y2332923D01*
G01X3790548Y2340923D02*
Y2332923D01*
X3794548D01*
G01X3799348Y2340923D02*
X3801748D01*
G01X3800548D02*
Y2332923D01*
G01X3799348D02*
X3801748D01*
G01X3806248D02*
Y2340923D01*
X3810848Y2332923D01*
Y2340923D01*
G01X3817148Y2336923D02*
X3819148D01*
Y2334523D01*
X3818548Y2333723D01*
X3817848Y2333190D01*
X3816848Y2332923D01*
X3815848Y2333190D01*
X3815148Y2333723D01*
X3814548Y2334523D01*
X3814148Y2335456D01*
X3813948Y2336523D01*
Y2337456D01*
X3814148Y2338256D01*
X3814548Y2339190D01*
X3815148Y2339990D01*
X3815748Y2340523D01*
X3816548Y2340923D01*
X3817248D01*
X3818048Y2340656D01*
X3818648Y2340123D01*
G01X3830448Y2332923D02*
Y2340923D01*
G01X3834648D02*
Y2332923D01*
G01Y2336923D02*
X3830448D01*
G01X3840548Y2332923D02*
X3839748Y2333056D01*
X3839048Y2333590D01*
X3838448Y2334390D01*
X3838048Y2335323D01*
X3837848Y2336390D01*
Y2337456D01*
X3838048Y2338523D01*
X3838448Y2339456D01*
X3839048Y2340256D01*
X3839748Y2340790D01*
X3840548Y2340923D01*
X3841348Y2340790D01*
X3842048Y2340256D01*
X3842648Y2339456D01*
X3843048Y2338523D01*
X3843248Y2337456D01*
Y2336390D01*
X3843048Y2335323D01*
X3842648Y2334390D01*
X3842048Y2333590D01*
X3841348Y2333056D01*
X3840548Y2332923D01*
G01X3846548Y2340923D02*
Y2332923D01*
X3850548D01*
G01X3858548D02*
X3854548D01*
Y2340923D01*
X3858548D01*
G01X3856948Y2337056D02*
X3854548D01*
G01X3870448Y2333989D02*
X3871248Y2333323D01*
X3872148Y2332923D01*
X3872948D01*
X3873748Y2333323D01*
X3874348Y2333989D01*
X3874648Y2334923D01*
X3874448Y2335856D01*
X3873948Y2336656D01*
X3873048Y2337190D01*
X3871848Y2337456D01*
X3871148Y2337990D01*
X3870848Y2338923D01*
X3871048Y2339856D01*
X3871548Y2340523D01*
X3872248Y2340923D01*
X3872948D01*
X3873648Y2340656D01*
X3874248Y2339990D01*
G01X3878548Y2332923D02*
Y2340923D01*
X3880948D01*
X3881748Y2340523D01*
X3882348Y2339590D01*
X3882548Y2338523D01*
X3882348Y2337456D01*
X3881848Y2336656D01*
X3880948Y2336256D01*
X3878548D01*
G01X3886048Y2332923D02*
X3888548Y2340923D01*
X3891048Y2332923D01*
G01X3890148Y2335723D02*
X3886948D01*
G01X3898748Y2340256D02*
X3898148Y2340656D01*
X3897448Y2340923D01*
X3896648D01*
X3895748Y2340523D01*
X3895048Y2339856D01*
X3894548Y2339056D01*
X3894148Y2337723D01*
X3894048Y2336523D01*
X3894248Y2335323D01*
X3894548Y2334523D01*
X3895148Y2333723D01*
X3895848Y2333190D01*
X3896548Y2332923D01*
X3897248D01*
X3897948Y2333190D01*
X3898548Y2333590D01*
X3899048Y2334123D01*
G01X3903348Y2340923D02*
X3905748D01*
G01X3904548D02*
Y2332923D01*
G01X3903348D02*
X3905748D01*
G01X3910248D02*
Y2340923D01*
X3914848Y2332923D01*
Y2340923D01*
G01X3921148Y2336923D02*
X3923148D01*
Y2334523D01*
X3922548Y2333723D01*
X3921848Y2333190D01*
X3920848Y2332923D01*
X3919848Y2333190D01*
X3919148Y2333723D01*
X3918548Y2334523D01*
X3918148Y2335456D01*
X3917948Y2336523D01*
Y2337456D01*
X3918148Y2338256D01*
X3918548Y2339190D01*
X3919148Y2339990D01*
X3919748Y2340523D01*
X3920548Y2340923D01*
X3921248D01*
X3922048Y2340656D01*
X3922648Y2340123D01*
G01X3934048Y2332923D02*
X3936548Y2340923D01*
X3939048Y2332923D01*
G01X3938148Y2335723D02*
X3934948D01*
G01X3942548Y2340923D02*
Y2332923D01*
X3946548D01*
G01X3950548Y2340923D02*
Y2332923D01*
X3954548D01*
G01X3966348Y2340923D02*
Y2335190D01*
X3966748Y2333989D01*
X3967548Y2333190D01*
X3968548Y2332923D01*
X3969548Y2333190D01*
X3970348Y2333989D01*
X3970748Y2335190D01*
Y2340923D01*
G01X3974448Y2333989D02*
X3975248Y2333323D01*
X3976148Y2332923D01*
X3976948D01*
X3977748Y2333323D01*
X3978348Y2333989D01*
X3978648Y2334923D01*
X3978448Y2335856D01*
X3977948Y2336656D01*
X3977048Y2337190D01*
X3975848Y2337456D01*
X3975148Y2337990D01*
X3974848Y2338923D01*
X3975048Y2339856D01*
X3975548Y2340523D01*
X3976248Y2340923D01*
X3976948D01*
X3977648Y2340656D01*
X3978248Y2339990D01*
G01X3983348Y2340923D02*
X3985748D01*
G01X3984548D02*
Y2332923D01*
G01X3983348D02*
X3985748D01*
G01X3990248D02*
Y2340923D01*
X3994848Y2332923D01*
Y2340923D01*
G01X4001148Y2336923D02*
X4003148D01*
Y2334523D01*
X4002548Y2333723D01*
X4001848Y2333190D01*
X4000848Y2332923D01*
X3999848Y2333190D01*
X3999148Y2333723D01*
X3998548Y2334523D01*
X3998148Y2335456D01*
X3997948Y2336523D01*
Y2337456D01*
X3998148Y2338256D01*
X3998548Y2339190D01*
X3999148Y2339990D01*
X3999748Y2340523D01*
X4000548Y2340923D01*
X4001248D01*
X4002048Y2340656D01*
X4002648Y2340123D01*
G01X4014348Y2334123D02*
X4014948Y2333456D01*
X4015648Y2333056D01*
X4016548Y2332923D01*
X4017448Y2333190D01*
X4018148Y2333723D01*
X4018648Y2334656D01*
X4018748Y2335723D01*
X4018548Y2336790D01*
X4018048Y2337456D01*
X4017348Y2337990D01*
X4016648Y2338123D01*
X4015948Y2337990D01*
X4015048Y2337456D01*
X4015348Y2340923D01*
X4018048D01*
G01X4024548D02*
X4023748Y2340656D01*
X4023148Y2339990D01*
X4022748Y2339190D01*
X4022448Y2338123D01*
X4022348Y2336923D01*
X4022448Y2335723D01*
X4022748Y2334656D01*
X4023148Y2333856D01*
X4023748Y2333190D01*
X4024548Y2332923D01*
X4025348Y2333190D01*
X4025948Y2333856D01*
X4026348Y2334656D01*
X4026648Y2335723D01*
X4026748Y2336923D01*
X4026648Y2338123D01*
X4026348Y2339190D01*
X4025948Y2339990D01*
X4025348Y2340656D01*
X4024548Y2340923D01*
G01X4029948Y2332923D02*
Y2340923D01*
X4032548Y2334256D01*
X4035148Y2340923D01*
Y2332923D01*
G01X4039348Y2340923D02*
X4041748D01*
G01X4040548D02*
Y2332923D01*
G01X4039348D02*
X4041748D01*
G01X4046548Y2340923D02*
Y2332923D01*
X4050548D01*
G01X4054448Y2333989D02*
X4055248Y2333323D01*
X4056148Y2332923D01*
X4056948D01*
X4057748Y2333323D01*
X4058348Y2333989D01*
X4058648Y2334923D01*
X4058448Y2335856D01*
X4057948Y2336656D01*
X4057048Y2337190D01*
X4055848Y2337456D01*
X4055148Y2337990D01*
X4054848Y2338923D01*
X4055048Y2339856D01*
X4055548Y2340523D01*
X4056248Y2340923D01*
X4056948D01*
X4057648Y2340656D01*
X4058248Y2339990D01*
G01X4064548Y2332656D02*
X4064348Y2332790D01*
Y2333056D01*
X4064548Y2333190D01*
X4064748Y2333056D01*
Y2332790D01*
X4064548Y2332656D01*
G01X3142648Y2351256D02*
X3143348Y2352190D01*
X3143948Y2352723D01*
X3144748Y2352990D01*
X3145448Y2352723D01*
X3145948Y2352190D01*
X3146348Y2351390D01*
X3146448Y2350456D01*
X3146348Y2349656D01*
X3145948Y2348856D01*
X3145348Y2348190D01*
X3144648Y2347923D01*
X3143848Y2348190D01*
X3143148Y2348989D01*
X3142748Y2350190D01*
X3142648Y2351523D01*
X3142848Y2353256D01*
X3143148Y2354190D01*
X3143648Y2355123D01*
X3144348Y2355790D01*
X3145048Y2355923D01*
X3145748Y2355656D01*
X3146248Y2354990D01*
G01X3152548Y2347656D02*
X3152348Y2347790D01*
Y2348056D01*
X3152548Y2348190D01*
X3152748Y2348056D01*
Y2347790D01*
X3152548Y2347656D01*
G01X3160548Y2347923D02*
Y2355923D01*
X3159348Y2354323D01*
G01Y2347923D02*
X3161748D01*
G01X3175348Y2355923D02*
X3177748D01*
G01X3176548D02*
Y2347923D01*
G01X3175348D02*
X3177748D01*
G01X3182248D02*
Y2355923D01*
X3186848Y2347923D01*
Y2355923D01*
G01X3190448Y2348989D02*
X3191248Y2348323D01*
X3192148Y2347923D01*
X3192948D01*
X3193748Y2348323D01*
X3194348Y2348989D01*
X3194648Y2349923D01*
X3194448Y2350856D01*
X3193948Y2351656D01*
X3193048Y2352190D01*
X3191848Y2352456D01*
X3191148Y2352990D01*
X3190848Y2353923D01*
X3191048Y2354856D01*
X3191548Y2355523D01*
X3192248Y2355923D01*
X3192948D01*
X3193648Y2355656D01*
X3194248Y2354990D01*
G01X3199348Y2355923D02*
X3201748D01*
G01X3200548D02*
Y2347923D01*
G01X3199348D02*
X3201748D01*
G01X3206348D02*
Y2355923D01*
X3208348D01*
X3209148Y2355523D01*
X3209748Y2354990D01*
X3210248Y2354190D01*
X3210648Y2353256D01*
X3210748Y2351923D01*
X3210648Y2350590D01*
X3210248Y2349656D01*
X3209748Y2348856D01*
X3209148Y2348323D01*
X3208348Y2347923D01*
X3206348D01*
G01X3218548D02*
X3214548D01*
Y2355923D01*
X3218548D01*
G01X3216948Y2352056D02*
X3214548D01*
G01X3233348Y2352190D02*
X3233748Y2352590D01*
X3234048Y2353256D01*
X3234248Y2354190D01*
X3234048Y2354990D01*
X3233648Y2355523D01*
X3232948Y2355923D01*
X3230248D01*
Y2347923D01*
X3233548D01*
X3234248Y2348456D01*
X3234648Y2349256D01*
X3234848Y2350190D01*
X3234648Y2351123D01*
X3234048Y2351923D01*
X3233348Y2352190D01*
X3230248D01*
G01X3240548Y2347923D02*
X3239748Y2348056D01*
X3239048Y2348590D01*
X3238448Y2349390D01*
X3238048Y2350323D01*
X3237848Y2351390D01*
Y2352456D01*
X3238048Y2353523D01*
X3238448Y2354456D01*
X3239048Y2355256D01*
X3239748Y2355790D01*
X3240548Y2355923D01*
X3241348Y2355790D01*
X3242048Y2355256D01*
X3242648Y2354456D01*
X3243048Y2353523D01*
X3243248Y2352456D01*
Y2351390D01*
X3243048Y2350323D01*
X3242648Y2349390D01*
X3242048Y2348590D01*
X3241348Y2348056D01*
X3240548Y2347923D01*
G01X3246048D02*
X3248548Y2355923D01*
X3251048Y2347923D01*
G01X3250148Y2350723D02*
X3246948D01*
G01X3254548Y2347923D02*
Y2355923D01*
X3257048D01*
X3257848Y2355523D01*
X3258348Y2354990D01*
X3258548Y2353923D01*
X3258348Y2352856D01*
X3257748Y2352190D01*
X3257048Y2351790D01*
X3254548D01*
G01X3257048D02*
X3258548Y2347923D01*
G01X3262348D02*
Y2355923D01*
X3264348D01*
X3265148Y2355523D01*
X3265748Y2354990D01*
X3266248Y2354190D01*
X3266648Y2353256D01*
X3266748Y2351923D01*
X3266648Y2350590D01*
X3266248Y2349656D01*
X3265748Y2348856D01*
X3265148Y2348323D01*
X3264348Y2347923D01*
X3262348D01*
G01X3280548D02*
X3279748Y2348056D01*
X3279048Y2348590D01*
X3278448Y2349390D01*
X3278048Y2350323D01*
X3277848Y2351390D01*
Y2352456D01*
X3278048Y2353523D01*
X3278448Y2354456D01*
X3279048Y2355256D01*
X3279748Y2355790D01*
X3280548Y2355923D01*
X3281348Y2355790D01*
X3282048Y2355256D01*
X3282648Y2354456D01*
X3283048Y2353523D01*
X3283248Y2352456D01*
Y2351390D01*
X3283048Y2350323D01*
X3282648Y2349390D01*
X3282048Y2348590D01*
X3281348Y2348056D01*
X3280548Y2347923D01*
G01X3286348Y2355923D02*
Y2350190D01*
X3286748Y2348989D01*
X3287548Y2348190D01*
X3288548Y2347923D01*
X3289548Y2348190D01*
X3290348Y2348989D01*
X3290748Y2350190D01*
Y2355923D01*
G01X3296548D02*
Y2347923D01*
G01X3294248Y2355923D02*
X3298848D01*
G01X3302548D02*
Y2347923D01*
X3306548D01*
G01X3311348Y2355923D02*
X3313748D01*
G01X3312548D02*
Y2347923D01*
G01X3311348D02*
X3313748D01*
G01X3318248D02*
Y2355923D01*
X3322848Y2347923D01*
Y2355923D01*
G01X3330548Y2347923D02*
X3326548D01*
Y2355923D01*
X3330548D01*
G01X3328948Y2352056D02*
X3326548D01*
G01X3342348Y2347923D02*
Y2355923D01*
X3344348D01*
X3345148Y2355523D01*
X3345748Y2354990D01*
X3346248Y2354190D01*
X3346648Y2353256D01*
X3346748Y2351923D01*
X3346648Y2350590D01*
X3346248Y2349656D01*
X3345748Y2348856D01*
X3345148Y2348323D01*
X3344348Y2347923D01*
X3342348D01*
G01X3350348Y2355923D02*
Y2350190D01*
X3350748Y2348989D01*
X3351548Y2348190D01*
X3352548Y2347923D01*
X3353548Y2348190D01*
X3354348Y2348989D01*
X3354748Y2350190D01*
Y2355923D01*
G01X3357948Y2347923D02*
Y2355923D01*
X3360548Y2349256D01*
X3363148Y2355923D01*
Y2347923D01*
G01X3365948D02*
Y2355923D01*
X3368548Y2349256D01*
X3371148Y2355923D01*
Y2347923D01*
G01X3376548D02*
Y2351523D01*
X3374548Y2355923D01*
G01X3378548D02*
X3376548Y2351523D01*
G01X3390548Y2347923D02*
Y2355923D01*
X3392948D01*
X3393748Y2355523D01*
X3394348Y2354590D01*
X3394548Y2353523D01*
X3394348Y2352456D01*
X3393848Y2351656D01*
X3392948Y2351256D01*
X3390548D01*
G01X3398048Y2347923D02*
X3400548Y2355923D01*
X3403048Y2347923D01*
G01X3402148Y2350723D02*
X3398948D01*
G01X3406348Y2347923D02*
Y2355923D01*
X3408348D01*
X3409148Y2355523D01*
X3409748Y2354990D01*
X3410248Y2354190D01*
X3410648Y2353256D01*
X3410748Y2351923D01*
X3410648Y2350590D01*
X3410248Y2349656D01*
X3409748Y2348856D01*
X3409148Y2348323D01*
X3408348Y2347923D01*
X3406348D01*
G01X3422348D02*
Y2355923D01*
X3424348D01*
X3425148Y2355523D01*
X3425748Y2354990D01*
X3426248Y2354190D01*
X3426648Y2353256D01*
X3426748Y2351923D01*
X3426648Y2350590D01*
X3426248Y2349656D01*
X3425748Y2348856D01*
X3425148Y2348323D01*
X3424348Y2347923D01*
X3422348D01*
G01X3434548D02*
X3430548D01*
Y2355923D01*
X3434548D01*
G01X3432948Y2352056D02*
X3430548D01*
G01X3438448Y2348989D02*
X3439248Y2348323D01*
X3440148Y2347923D01*
X3440948D01*
X3441748Y2348323D01*
X3442348Y2348989D01*
X3442648Y2349923D01*
X3442448Y2350856D01*
X3441948Y2351656D01*
X3441048Y2352190D01*
X3439848Y2352456D01*
X3439148Y2352990D01*
X3438848Y2353923D01*
X3439048Y2354856D01*
X3439548Y2355523D01*
X3440248Y2355923D01*
X3440948D01*
X3441648Y2355656D01*
X3442248Y2354990D01*
G01X3447348Y2355923D02*
X3449748D01*
G01X3448548D02*
Y2347923D01*
G01X3447348D02*
X3449748D01*
G01X3457148Y2351923D02*
X3459148D01*
Y2349523D01*
X3458548Y2348723D01*
X3457848Y2348190D01*
X3456848Y2347923D01*
X3455848Y2348190D01*
X3455148Y2348723D01*
X3454548Y2349523D01*
X3454148Y2350456D01*
X3453948Y2351523D01*
Y2352456D01*
X3454148Y2353256D01*
X3454548Y2354190D01*
X3455148Y2354990D01*
X3455748Y2355523D01*
X3456548Y2355923D01*
X3457248D01*
X3458048Y2355656D01*
X3458648Y2355123D01*
G01X3462248Y2347923D02*
Y2355923D01*
X3466848Y2347923D01*
Y2355923D01*
G01X3479348D02*
X3481748D01*
G01X3480548D02*
Y2347923D01*
G01X3479348D02*
X3481748D01*
G01X3486248D02*
Y2355923D01*
X3490848Y2347923D01*
Y2355923D01*
G01X3502448Y2348989D02*
X3503248Y2348323D01*
X3504148Y2347923D01*
X3504948D01*
X3505748Y2348323D01*
X3506348Y2348989D01*
X3506648Y2349923D01*
X3506448Y2350856D01*
X3505948Y2351656D01*
X3505048Y2352190D01*
X3503848Y2352456D01*
X3503148Y2352990D01*
X3502848Y2353923D01*
X3503048Y2354856D01*
X3503548Y2355523D01*
X3504248Y2355923D01*
X3504948D01*
X3505648Y2355656D01*
X3506248Y2354990D01*
G01X3512548Y2347923D02*
X3511748Y2348056D01*
X3511048Y2348590D01*
X3510448Y2349390D01*
X3510048Y2350323D01*
X3509848Y2351390D01*
Y2352456D01*
X3510048Y2353523D01*
X3510448Y2354456D01*
X3511048Y2355256D01*
X3511748Y2355790D01*
X3512548Y2355923D01*
X3513348Y2355790D01*
X3514048Y2355256D01*
X3514648Y2354456D01*
X3515048Y2353523D01*
X3515248Y2352456D01*
Y2351390D01*
X3515048Y2350323D01*
X3514648Y2349390D01*
X3514048Y2348590D01*
X3513348Y2348056D01*
X3512548Y2347923D01*
G01X3513348Y2350056D02*
X3514548Y2347923D01*
G01X3518348Y2355923D02*
Y2350190D01*
X3518748Y2348989D01*
X3519548Y2348190D01*
X3520548Y2347923D01*
X3521548Y2348190D01*
X3522348Y2348989D01*
X3522748Y2350190D01*
Y2355923D01*
G01X3526048Y2347923D02*
X3528548Y2355923D01*
X3531048Y2347923D01*
G01X3530148Y2350723D02*
X3526948D01*
G01X3534548Y2347923D02*
Y2355923D01*
X3537048D01*
X3537848Y2355523D01*
X3538348Y2354990D01*
X3538548Y2353923D01*
X3538348Y2352856D01*
X3537748Y2352190D01*
X3537048Y2351790D01*
X3534548D01*
G01X3537048D02*
X3538548Y2347923D01*
G01X3546548D02*
X3542548D01*
Y2355923D01*
X3546548D01*
G01X3544948Y2352056D02*
X3542548D01*
G01X3558448Y2348989D02*
X3559248Y2348323D01*
X3560148Y2347923D01*
X3560948D01*
X3561748Y2348323D01*
X3562348Y2348989D01*
X3562648Y2349923D01*
X3562448Y2350856D01*
X3561948Y2351656D01*
X3561048Y2352190D01*
X3559848Y2352456D01*
X3559148Y2352990D01*
X3558848Y2353923D01*
X3559048Y2354856D01*
X3559548Y2355523D01*
X3560248Y2355923D01*
X3560948D01*
X3561648Y2355656D01*
X3562248Y2354990D01*
G01X3566448Y2347923D02*
Y2355923D01*
G01X3570648D02*
Y2347923D01*
G01Y2351923D02*
X3566448D01*
G01X3574048Y2347923D02*
X3576548Y2355923D01*
X3579048Y2347923D01*
G01X3578148Y2350723D02*
X3574948D01*
G01X3582548Y2347923D02*
Y2355923D01*
X3584948D01*
X3585748Y2355523D01*
X3586348Y2354590D01*
X3586548Y2353523D01*
X3586348Y2352456D01*
X3585848Y2351656D01*
X3584948Y2351256D01*
X3582548D01*
G01X3594548Y2347923D02*
X3590548D01*
Y2355923D01*
X3594548D01*
G01X3592948Y2352056D02*
X3590548D01*
G01X3599248Y2350590D02*
X3601848D01*
G01X3614448Y2348989D02*
X3615248Y2348323D01*
X3616148Y2347923D01*
X3616948D01*
X3617748Y2348323D01*
X3618348Y2348989D01*
X3618648Y2349923D01*
X3618448Y2350856D01*
X3617948Y2351656D01*
X3617048Y2352190D01*
X3615848Y2352456D01*
X3615148Y2352990D01*
X3614848Y2353923D01*
X3615048Y2354856D01*
X3615548Y2355523D01*
X3616248Y2355923D01*
X3616948D01*
X3617648Y2355656D01*
X3618248Y2354990D01*
G01X3622448Y2347923D02*
Y2355923D01*
G01X3626648D02*
Y2347923D01*
G01Y2351923D02*
X3622448D01*
G01X3630048Y2347923D02*
X3632548Y2355923D01*
X3635048Y2347923D01*
G01X3634148Y2350723D02*
X3630948D01*
G01X3638548Y2347923D02*
Y2355923D01*
X3640948D01*
X3641748Y2355523D01*
X3642348Y2354590D01*
X3642548Y2353523D01*
X3642348Y2352456D01*
X3641848Y2351656D01*
X3640948Y2351256D01*
X3638548D01*
G01X3650548Y2347923D02*
X3646548D01*
Y2355923D01*
X3650548D01*
G01X3648948Y2352056D02*
X3646548D01*
G01X3662448Y2348989D02*
X3663248Y2348323D01*
X3664148Y2347923D01*
X3664948D01*
X3665748Y2348323D01*
X3666348Y2348989D01*
X3666648Y2349923D01*
X3666448Y2350856D01*
X3665948Y2351656D01*
X3665048Y2352190D01*
X3663848Y2352456D01*
X3663148Y2352990D01*
X3662848Y2353923D01*
X3663048Y2354856D01*
X3663548Y2355523D01*
X3664248Y2355923D01*
X3664948D01*
X3665648Y2355656D01*
X3666248Y2354990D01*
G01X3671348Y2355923D02*
X3673748D01*
G01X3672548D02*
Y2347923D01*
G01X3671348D02*
X3673748D01*
G01X3678648Y2355923D02*
X3682448D01*
X3678648Y2347923D01*
X3682448D01*
G01X3690548D02*
X3686548D01*
Y2355923D01*
X3690548D01*
G01X3688948Y2352056D02*
X3686548D01*
G01X3702348Y2349123D02*
X3702948Y2348456D01*
X3703648Y2348056D01*
X3704548Y2347923D01*
X3705448Y2348190D01*
X3706148Y2348723D01*
X3706648Y2349656D01*
X3706748Y2350723D01*
X3706548Y2351790D01*
X3706048Y2352456D01*
X3705348Y2352990D01*
X3704648Y2353123D01*
X3703948Y2352990D01*
X3703048Y2352456D01*
X3703348Y2355923D01*
X3706048D01*
G01X3712548D02*
X3711748Y2355656D01*
X3711148Y2354990D01*
X3710748Y2354190D01*
X3710448Y2353123D01*
X3710348Y2351923D01*
X3710448Y2350723D01*
X3710748Y2349656D01*
X3711148Y2348856D01*
X3711748Y2348190D01*
X3712548Y2347923D01*
X3713348Y2348190D01*
X3713948Y2348856D01*
X3714348Y2349656D01*
X3714648Y2350723D01*
X3714748Y2351923D01*
X3714648Y2353123D01*
X3714348Y2354190D01*
X3713948Y2354990D01*
X3713348Y2355656D01*
X3712548Y2355923D01*
G01X3717948Y2347923D02*
Y2355923D01*
X3720548Y2349256D01*
X3723148Y2355923D01*
Y2347923D01*
G01X3727348Y2355923D02*
X3729748D01*
G01X3728548D02*
Y2347923D01*
G01X3727348D02*
X3729748D01*
G01X3734548Y2355923D02*
Y2347923D01*
X3738548D01*
G01X3742448Y2348989D02*
X3743248Y2348323D01*
X3744148Y2347923D01*
X3744948D01*
X3745748Y2348323D01*
X3746348Y2348989D01*
X3746648Y2349923D01*
X3746448Y2350856D01*
X3745948Y2351656D01*
X3745048Y2352190D01*
X3743848Y2352456D01*
X3743148Y2352990D01*
X3742848Y2353923D01*
X3743048Y2354856D01*
X3743548Y2355523D01*
X3744248Y2355923D01*
X3744948D01*
X3745648Y2355656D01*
X3746248Y2354990D01*
G01X3752348Y2346456D02*
X3752748Y2348190D01*
G01X3766548Y2347923D02*
Y2355923D01*
X3768948D01*
X3769748Y2355523D01*
X3770348Y2354590D01*
X3770548Y2353523D01*
X3770348Y2352456D01*
X3769848Y2351656D01*
X3768948Y2351256D01*
X3766548D01*
G01X3775348Y2355923D02*
X3777748D01*
G01X3776548D02*
Y2347923D01*
G01X3775348D02*
X3777748D01*
G01X3784548Y2355923D02*
Y2347923D01*
G01X3782248Y2355923D02*
X3786848D01*
G01X3794748Y2355256D02*
X3794148Y2355656D01*
X3793448Y2355923D01*
X3792648D01*
X3791748Y2355523D01*
X3791048Y2354856D01*
X3790548Y2354056D01*
X3790148Y2352723D01*
X3790048Y2351523D01*
X3790248Y2350323D01*
X3790548Y2349523D01*
X3791148Y2348723D01*
X3791848Y2348190D01*
X3792548Y2347923D01*
X3793248D01*
X3793948Y2348190D01*
X3794548Y2348590D01*
X3795048Y2349123D01*
G01X3798448Y2347923D02*
Y2355923D01*
G01X3802648D02*
Y2347923D01*
G01Y2351923D02*
X3798448D01*
G01X3816048Y2345256D02*
X3815048Y2346590D01*
X3814548Y2347923D01*
Y2353256D01*
X3815048Y2354590D01*
X3816048Y2355923D01*
G01X3822448Y2348989D02*
X3823248Y2348323D01*
X3824148Y2347923D01*
X3824948D01*
X3825748Y2348323D01*
X3826348Y2348989D01*
X3826648Y2349923D01*
X3826448Y2350856D01*
X3825948Y2351656D01*
X3825048Y2352190D01*
X3823848Y2352456D01*
X3823148Y2352990D01*
X3822848Y2353923D01*
X3823048Y2354856D01*
X3823548Y2355523D01*
X3824248Y2355923D01*
X3824948D01*
X3825648Y2355656D01*
X3826248Y2354990D01*
G01X3830448Y2347923D02*
Y2355923D01*
G01X3834648D02*
Y2347923D01*
G01Y2351923D02*
X3830448D01*
G01X3838048Y2347923D02*
X3840548Y2355923D01*
X3843048Y2347923D01*
G01X3842148Y2350723D02*
X3838948D01*
G01X3846548Y2347923D02*
Y2355923D01*
X3848948D01*
X3849748Y2355523D01*
X3850348Y2354590D01*
X3850548Y2353523D01*
X3850348Y2352456D01*
X3849848Y2351656D01*
X3848948Y2351256D01*
X3846548D01*
G01X3858548Y2347923D02*
X3854548D01*
Y2355923D01*
X3858548D01*
G01X3856948Y2352056D02*
X3854548D01*
G01X3874748Y2355256D02*
X3874148Y2355656D01*
X3873448Y2355923D01*
X3872648D01*
X3871748Y2355523D01*
X3871048Y2354856D01*
X3870548Y2354056D01*
X3870148Y2352723D01*
X3870048Y2351523D01*
X3870248Y2350323D01*
X3870548Y2349523D01*
X3871148Y2348723D01*
X3871848Y2348190D01*
X3872548Y2347923D01*
X3873248D01*
X3873948Y2348190D01*
X3874548Y2348590D01*
X3875048Y2349123D01*
G01X3882548Y2347923D02*
X3878548D01*
Y2355923D01*
X3882548D01*
G01X3880948Y2352056D02*
X3878548D01*
G01X3886248Y2347923D02*
Y2355923D01*
X3890848Y2347923D01*
Y2355923D01*
G01X3896548D02*
Y2347923D01*
G01X3894248Y2355923D02*
X3898848D01*
G01X3906548Y2347923D02*
X3902548D01*
Y2355923D01*
X3906548D01*
G01X3904948Y2352056D02*
X3902548D01*
G01X3910548Y2347923D02*
Y2355923D01*
X3913048D01*
X3913848Y2355523D01*
X3914348Y2354990D01*
X3914548Y2353923D01*
X3914348Y2352856D01*
X3913748Y2352190D01*
X3913048Y2351790D01*
X3910548D01*
G01X3913048D02*
X3914548Y2347923D01*
G01X3928548Y2355923D02*
Y2347923D01*
G01X3926248Y2355923D02*
X3930848D01*
G01X3936548Y2347923D02*
X3935748Y2348056D01*
X3935048Y2348590D01*
X3934448Y2349390D01*
X3934048Y2350323D01*
X3933848Y2351390D01*
Y2352456D01*
X3934048Y2353523D01*
X3934448Y2354456D01*
X3935048Y2355256D01*
X3935748Y2355790D01*
X3936548Y2355923D01*
X3937348Y2355790D01*
X3938048Y2355256D01*
X3938648Y2354456D01*
X3939048Y2353523D01*
X3939248Y2352456D01*
Y2351390D01*
X3939048Y2350323D01*
X3938648Y2349390D01*
X3938048Y2348590D01*
X3937348Y2348056D01*
X3936548Y2347923D01*
G01X3954748Y2355256D02*
X3954148Y2355656D01*
X3953448Y2355923D01*
X3952648D01*
X3951748Y2355523D01*
X3951048Y2354856D01*
X3950548Y2354056D01*
X3950148Y2352723D01*
X3950048Y2351523D01*
X3950248Y2350323D01*
X3950548Y2349523D01*
X3951148Y2348723D01*
X3951848Y2348190D01*
X3952548Y2347923D01*
X3953248D01*
X3953948Y2348190D01*
X3954548Y2348590D01*
X3955048Y2349123D01*
G01X3962548Y2347923D02*
X3958548D01*
Y2355923D01*
X3962548D01*
G01X3960948Y2352056D02*
X3958548D01*
G01X3966248Y2347923D02*
Y2355923D01*
X3970848Y2347923D01*
Y2355923D01*
G01X3976548D02*
Y2347923D01*
G01X3974248Y2355923D02*
X3978848D01*
G01X3986548Y2347923D02*
X3982548D01*
Y2355923D01*
X3986548D01*
G01X3984948Y2352056D02*
X3982548D01*
G01X3990548Y2347923D02*
Y2355923D01*
X3993048D01*
X3993848Y2355523D01*
X3994348Y2354990D01*
X3994548Y2353923D01*
X3994348Y2352856D01*
X3993748Y2352190D01*
X3993048Y2351790D01*
X3990548D01*
G01X3993048D02*
X3994548Y2347923D01*
G01X4001048Y2345256D02*
X4002048Y2346590D01*
X4002548Y2347923D01*
Y2353256D01*
X4002048Y2354590D01*
X4001048Y2355923D01*
G01X4008548Y2347656D02*
X4008348Y2347790D01*
Y2348056D01*
X4008548Y2348190D01*
X4008748Y2348056D01*
Y2347790D01*
X4008548Y2347656D01*
G01Y2351256D02*
X4008348Y2351390D01*
Y2351656D01*
X4008548Y2351790D01*
X4008748Y2351656D01*
Y2351390D01*
X4008548Y2351256D01*
G01X4024548Y2347923D02*
Y2355923D01*
X4023348Y2354323D01*
G01Y2347923D02*
X4025748D01*
G01X4032548Y2355923D02*
X4031748Y2355656D01*
X4031148Y2354990D01*
X4030748Y2354190D01*
X4030448Y2353123D01*
X4030348Y2351923D01*
X4030448Y2350723D01*
X4030748Y2349656D01*
X4031148Y2348856D01*
X4031748Y2348190D01*
X4032548Y2347923D01*
X4033348Y2348190D01*
X4033948Y2348856D01*
X4034348Y2349656D01*
X4034648Y2350723D01*
X4034748Y2351923D01*
X4034648Y2353123D01*
X4034348Y2354190D01*
X4033948Y2354990D01*
X4033348Y2355656D01*
X4032548Y2355923D01*
G01X4040548D02*
X4039748Y2355656D01*
X4039148Y2354990D01*
X4038748Y2354190D01*
X4038448Y2353123D01*
X4038348Y2351923D01*
X4038448Y2350723D01*
X4038748Y2349656D01*
X4039148Y2348856D01*
X4039748Y2348190D01*
X4040548Y2347923D01*
X4041348Y2348190D01*
X4041948Y2348856D01*
X4042348Y2349656D01*
X4042648Y2350723D01*
X4042748Y2351923D01*
X4042648Y2353123D01*
X4042348Y2354190D01*
X4041948Y2354990D01*
X4041348Y2355656D01*
X4040548Y2355923D01*
G01X4045948Y2347923D02*
Y2355923D01*
X4048548Y2349256D01*
X4051148Y2355923D01*
Y2347923D01*
G01X4055348Y2355923D02*
X4057748D01*
G01X4056548D02*
Y2347923D01*
G01X4055348D02*
X4057748D01*
G01X4062548Y2355923D02*
Y2347923D01*
X4066548D01*
G01X4070448Y2348989D02*
X4071248Y2348323D01*
X4072148Y2347923D01*
X4072948D01*
X4073748Y2348323D01*
X4074348Y2348989D01*
X4074648Y2349923D01*
X4074448Y2350856D01*
X4073948Y2351656D01*
X4073048Y2352190D01*
X4071848Y2352456D01*
X4071148Y2352990D01*
X4070848Y2353923D01*
X4071048Y2354856D01*
X4071548Y2355523D01*
X4072248Y2355923D01*
X4072948D01*
X4073648Y2355656D01*
X4074248Y2354990D01*
G01X4080548Y2347656D02*
X4080348Y2347790D01*
Y2348056D01*
X4080548Y2348190D01*
X4080748Y2348056D01*
Y2347790D01*
X4080548Y2347656D01*
G01X4094348Y2347923D02*
Y2355923D01*
X4096348D01*
X4097148Y2355523D01*
X4097748Y2354990D01*
X4098248Y2354190D01*
X4098648Y2353256D01*
X4098748Y2351923D01*
X4098648Y2350590D01*
X4098248Y2349656D01*
X4097748Y2348856D01*
X4097148Y2348323D01*
X4096348Y2347923D01*
X4094348D01*
G01X4102548D02*
Y2355923D01*
X4105048D01*
X4105848Y2355523D01*
X4106348Y2354990D01*
X4106548Y2353923D01*
X4106348Y2352856D01*
X4105748Y2352190D01*
X4105048Y2351790D01*
X4102548D01*
G01X4105048D02*
X4106548Y2347923D01*
G01X4111348Y2355923D02*
X4113748D01*
G01X4112548D02*
Y2347923D01*
G01X4111348D02*
X4113748D01*
G01X4118548Y2355923D02*
Y2347923D01*
X4122548D01*
G01X4126548Y2355923D02*
Y2347923D01*
X4130548D01*
G01X4134748Y2347656D02*
X4138348Y2355923D01*
G01X4142648Y2347923D02*
Y2355923D01*
X4146448D01*
G01X4145048Y2352056D02*
X4142648D01*
G01X4154548Y2347923D02*
X4150548D01*
Y2355923D01*
X4154548D01*
G01X4152948Y2352056D02*
X4150548D01*
G01X4158048Y2347923D02*
X4160548Y2355923D01*
X4163048Y2347923D01*
G01X4162148Y2350723D02*
X4158948D01*
G01X4168548Y2355923D02*
Y2347923D01*
G01X4166248Y2355923D02*
X4170848D01*
G01X4174348D02*
Y2350190D01*
X4174748Y2348989D01*
X4175548Y2348190D01*
X4176548Y2347923D01*
X4177548Y2348190D01*
X4178348Y2348989D01*
X4178748Y2350190D01*
Y2355923D01*
G01X4182548Y2347923D02*
Y2355923D01*
X4185048D01*
X4185848Y2355523D01*
X4186348Y2354990D01*
X4186548Y2353923D01*
X4186348Y2352856D01*
X4185748Y2352190D01*
X4185048Y2351790D01*
X4182548D01*
G01X4185048D02*
X4186548Y2347923D01*
G01X4194548D02*
X4190548D01*
Y2355923D01*
X4194548D01*
G01X4192948Y2352056D02*
X4190548D01*
G01X4198748Y2347656D02*
X4202348Y2355923D01*
G01X4206548Y2347923D02*
Y2355923D01*
X4209048D01*
X4209848Y2355523D01*
X4210348Y2354990D01*
X4210548Y2353923D01*
X4210348Y2352856D01*
X4209748Y2352190D01*
X4209048Y2351790D01*
X4206548D01*
G01X4209048D02*
X4210548Y2347923D01*
G01X4216548D02*
X4215748Y2348056D01*
X4215048Y2348590D01*
X4214448Y2349390D01*
X4214048Y2350323D01*
X4213848Y2351390D01*
Y2352456D01*
X4214048Y2353523D01*
X4214448Y2354456D01*
X4215048Y2355256D01*
X4215748Y2355790D01*
X4216548Y2355923D01*
X4217348Y2355790D01*
X4218048Y2355256D01*
X4218648Y2354456D01*
X4219048Y2353523D01*
X4219248Y2352456D01*
Y2351390D01*
X4219048Y2350323D01*
X4218648Y2349390D01*
X4218048Y2348590D01*
X4217348Y2348056D01*
X4216548Y2347923D01*
G01X4222348Y2355923D02*
Y2350190D01*
X4222748Y2348989D01*
X4223548Y2348190D01*
X4224548Y2347923D01*
X4225548Y2348190D01*
X4226348Y2348989D01*
X4226748Y2350190D01*
Y2355923D01*
G01X4232548D02*
Y2347923D01*
G01X4230248Y2355923D02*
X4234848D01*
G01X4242548Y2347923D02*
X4238548D01*
Y2355923D01*
X4242548D01*
G01X4240948Y2352056D02*
X4238548D01*
G01X4246748Y2347656D02*
X4250348Y2355923D01*
G01X4254548Y2347923D02*
Y2355923D01*
X4256948D01*
X4257748Y2355523D01*
X4258348Y2354590D01*
X4258548Y2353523D01*
X4258348Y2352456D01*
X4257848Y2351656D01*
X4256948Y2351256D01*
X4254548D01*
G01X4262548Y2347923D02*
Y2355923D01*
X4265048D01*
X4265848Y2355523D01*
X4266348Y2354990D01*
X4266548Y2353923D01*
X4266348Y2352856D01*
X4265748Y2352190D01*
X4265048Y2351790D01*
X4262548D01*
G01X4265048D02*
X4266548Y2347923D01*
G01X4272548D02*
X4271748Y2348056D01*
X4271048Y2348590D01*
X4270448Y2349390D01*
X4270048Y2350323D01*
X4269848Y2351390D01*
Y2352456D01*
X4270048Y2353523D01*
X4270448Y2354456D01*
X4271048Y2355256D01*
X4271748Y2355790D01*
X4272548Y2355923D01*
X4273348Y2355790D01*
X4274048Y2355256D01*
X4274648Y2354456D01*
X4275048Y2353523D01*
X4275248Y2352456D01*
Y2351390D01*
X4275048Y2350323D01*
X4274648Y2349390D01*
X4274048Y2348590D01*
X4273348Y2348056D01*
X4272548Y2347923D01*
G01X4278648D02*
Y2355923D01*
X4282448D01*
G01X4281048Y2352056D02*
X4278648D01*
G01X4287348Y2355923D02*
X4289748D01*
G01X4288548D02*
Y2347923D01*
G01X4287348D02*
X4289748D01*
G01X4294548Y2355923D02*
Y2347923D01*
X4298548D01*
G01X4306548D02*
X4302548D01*
Y2355923D01*
X4306548D01*
G01X4304948Y2352056D02*
X4302548D01*
G01X4318448Y2348989D02*
X4319248Y2348323D01*
X4320148Y2347923D01*
X4320948D01*
X4321748Y2348323D01*
X4322348Y2348989D01*
X4322648Y2349923D01*
X4322448Y2350856D01*
X4321948Y2351656D01*
X4321048Y2352190D01*
X4319848Y2352456D01*
X4319148Y2352990D01*
X4318848Y2353923D01*
X4319048Y2354856D01*
X4319548Y2355523D01*
X4320248Y2355923D01*
X4320948D01*
X4321648Y2355656D01*
X4322248Y2354990D01*
G01X4326548Y2347923D02*
Y2355923D01*
X4328948D01*
X4329748Y2355523D01*
X4330348Y2354590D01*
X4330548Y2353523D01*
X4330348Y2352456D01*
X4329848Y2351656D01*
X4328948Y2351256D01*
X4326548D01*
G01X4334048Y2347923D02*
X4336548Y2355923D01*
X4339048Y2347923D01*
G01X4338148Y2350723D02*
X4334948D01*
G01X4346748Y2355256D02*
X4346148Y2355656D01*
X4345448Y2355923D01*
X4344648D01*
X4343748Y2355523D01*
X4343048Y2354856D01*
X4342548Y2354056D01*
X4342148Y2352723D01*
X4342048Y2351523D01*
X4342248Y2350323D01*
X4342548Y2349523D01*
X4343148Y2348723D01*
X4343848Y2348190D01*
X4344548Y2347923D01*
X4345248D01*
X4345948Y2348190D01*
X4346548Y2348590D01*
X4347048Y2349123D01*
G01X4351348Y2355923D02*
X4353748D01*
G01X4352548D02*
Y2347923D01*
G01X4351348D02*
X4353748D01*
G01X4358248D02*
Y2355923D01*
X4362848Y2347923D01*
Y2355923D01*
G01X4369148Y2351923D02*
X4371148D01*
Y2349523D01*
X4370548Y2348723D01*
X4369848Y2348190D01*
X4368848Y2347923D01*
X4367848Y2348190D01*
X4367148Y2348723D01*
X4366548Y2349523D01*
X4366148Y2350456D01*
X4365948Y2351523D01*
Y2352456D01*
X4366148Y2353256D01*
X4366548Y2354190D01*
X4367148Y2354990D01*
X4367748Y2355523D01*
X4368548Y2355923D01*
X4369248D01*
X4370048Y2355656D01*
X4370648Y2355123D01*
G01X4382048Y2347923D02*
X4384548Y2355923D01*
X4387048Y2347923D01*
G01X4386148Y2350723D02*
X4382948D01*
G01X4390548Y2355923D02*
Y2347923D01*
X4394548D01*
G01X4398548Y2355923D02*
Y2347923D01*
X4402548D01*
G01X4414348Y2355923D02*
Y2350190D01*
X4414748Y2348989D01*
X4415548Y2348190D01*
X4416548Y2347923D01*
X4417548Y2348190D01*
X4418348Y2348989D01*
X4418748Y2350190D01*
Y2355923D01*
G01X4422448Y2348989D02*
X4423248Y2348323D01*
X4424148Y2347923D01*
X4424948D01*
X4425748Y2348323D01*
X4426348Y2348989D01*
X4426648Y2349923D01*
X4426448Y2350856D01*
X4425948Y2351656D01*
X4425048Y2352190D01*
X4423848Y2352456D01*
X4423148Y2352990D01*
X4422848Y2353923D01*
X4423048Y2354856D01*
X4423548Y2355523D01*
X4424248Y2355923D01*
X4424948D01*
X4425648Y2355656D01*
X4426248Y2354990D01*
G01X4431348Y2355923D02*
X4433748D01*
G01X4432548D02*
Y2347923D01*
G01X4431348D02*
X4433748D01*
G01X4438248D02*
Y2355923D01*
X4442848Y2347923D01*
Y2355923D01*
G01X4449148Y2351923D02*
X4451148D01*
Y2349523D01*
X4450548Y2348723D01*
X4449848Y2348190D01*
X4448848Y2347923D01*
X4447848Y2348190D01*
X4447148Y2348723D01*
X4446548Y2349523D01*
X4446148Y2350456D01*
X4445948Y2351523D01*
Y2352456D01*
X4446148Y2353256D01*
X4446548Y2354190D01*
X4447148Y2354990D01*
X4447748Y2355523D01*
X4448548Y2355923D01*
X4449248D01*
X4450048Y2355656D01*
X4450648Y2355123D01*
G01X4464548Y2347923D02*
Y2355923D01*
X4463348Y2354323D01*
G01Y2347923D02*
X4465748D01*
G01X4472548Y2355923D02*
X4471748Y2355656D01*
X4471148Y2354990D01*
X4470748Y2354190D01*
X4470448Y2353123D01*
X4470348Y2351923D01*
X4470448Y2350723D01*
X4470748Y2349656D01*
X4471148Y2348856D01*
X4471748Y2348190D01*
X4472548Y2347923D01*
X4473348Y2348190D01*
X4473948Y2348856D01*
X4474348Y2349656D01*
X4474648Y2350723D01*
X4474748Y2351923D01*
X4474648Y2353123D01*
X4474348Y2354190D01*
X4473948Y2354990D01*
X4473348Y2355656D01*
X4472548Y2355923D01*
G01X4480548D02*
X4479748Y2355656D01*
X4479148Y2354990D01*
X4478748Y2354190D01*
X4478448Y2353123D01*
X4478348Y2351923D01*
X4478448Y2350723D01*
X4478748Y2349656D01*
X4479148Y2348856D01*
X4479748Y2348190D01*
X4480548Y2347923D01*
X4481348Y2348190D01*
X4481948Y2348856D01*
X4482348Y2349656D01*
X4482648Y2350723D01*
X4482748Y2351923D01*
X4482648Y2353123D01*
X4482348Y2354190D01*
X4481948Y2354990D01*
X4481348Y2355656D01*
X4480548Y2355923D01*
G01X4485948Y2347923D02*
Y2355923D01*
X4488548Y2349256D01*
X4491148Y2355923D01*
Y2347923D01*
G01X4495348Y2355923D02*
X4497748D01*
G01X4496548D02*
Y2347923D01*
G01X4495348D02*
X4497748D01*
G01X4502548Y2355923D02*
Y2347923D01*
X4506548D01*
G01X4510448Y2348989D02*
X4511248Y2348323D01*
X4512148Y2347923D01*
X4512948D01*
X4513748Y2348323D01*
X4514348Y2348989D01*
X4514648Y2349923D01*
X4514448Y2350856D01*
X4513948Y2351656D01*
X4513048Y2352190D01*
X4511848Y2352456D01*
X4511148Y2352990D01*
X4510848Y2353923D01*
X4511048Y2354856D01*
X4511548Y2355523D01*
X4512248Y2355923D01*
X4512948D01*
X4513648Y2355656D01*
X4514248Y2354990D01*
G01X4520548Y2347656D02*
X4520348Y2347790D01*
Y2348056D01*
X4520548Y2348190D01*
X4520748Y2348056D01*
Y2347790D01*
X4520548Y2347656D01*
G01X4542548Y2355923D02*
Y2347923D01*
X4546548D01*
G01X4550048D02*
X4552548Y2355923D01*
X4555048Y2347923D01*
G01X4554148Y2350723D02*
X4550948D01*
G01X4561348Y2352190D02*
X4561748Y2352590D01*
X4562048Y2353256D01*
X4562248Y2354190D01*
X4562048Y2354990D01*
X4561648Y2355523D01*
X4560948Y2355923D01*
X4558248D01*
Y2347923D01*
X4561548D01*
X4562248Y2348456D01*
X4562648Y2349256D01*
X4562848Y2350190D01*
X4562648Y2351123D01*
X4562048Y2351923D01*
X4561348Y2352190D01*
X4558248D01*
G01X4570548Y2347923D02*
X4566548D01*
Y2355923D01*
X4570548D01*
G01X4568948Y2352056D02*
X4566548D01*
G01X4574548Y2355923D02*
Y2347923D01*
X4578548D01*
G01X4590048D02*
X4592548Y2355923D01*
X4595048Y2347923D01*
G01X4594148Y2350723D02*
X4590948D01*
G01X4598548Y2347923D02*
Y2355923D01*
X4601048D01*
X4601848Y2355523D01*
X4602348Y2354990D01*
X4602548Y2353923D01*
X4602348Y2352856D01*
X4601748Y2352190D01*
X4601048Y2351790D01*
X4598548D01*
G01X4601048D02*
X4602548Y2347923D01*
G01X4610548D02*
X4606548D01*
Y2355923D01*
X4610548D01*
G01X4608948Y2352056D02*
X4606548D01*
G01X4614048Y2347923D02*
X4616548Y2355923D01*
X4619048Y2347923D01*
G01X4618148Y2350723D02*
X4614948D01*
G01X4630248Y2347923D02*
Y2355923D01*
X4634848Y2347923D01*
Y2355923D01*
G01X4640548Y2347923D02*
X4639748Y2348056D01*
X4639048Y2348590D01*
X4638448Y2349390D01*
X4638048Y2350323D01*
X4637848Y2351390D01*
Y2352456D01*
X4638048Y2353523D01*
X4638448Y2354456D01*
X4639048Y2355256D01*
X4639748Y2355790D01*
X4640548Y2355923D01*
X4641348Y2355790D01*
X4642048Y2355256D01*
X4642648Y2354456D01*
X4643048Y2353523D01*
X4643248Y2352456D01*
Y2351390D01*
X4643048Y2350323D01*
X4642648Y2349390D01*
X4642048Y2348590D01*
X4641348Y2348056D01*
X4640548Y2347923D01*
G01X4654048D02*
X4656548Y2355923D01*
X4659048Y2347923D01*
G01X4658148Y2350723D02*
X4654948D01*
G01X4662348Y2347923D02*
Y2355923D01*
X4664348D01*
X4665148Y2355523D01*
X4665748Y2354990D01*
X4666248Y2354190D01*
X4666648Y2353256D01*
X4666748Y2351923D01*
X4666648Y2350590D01*
X4666248Y2349656D01*
X4665748Y2348856D01*
X4665148Y2348323D01*
X4664348Y2347923D01*
X4662348D01*
G01X4670348D02*
Y2355923D01*
X4672348D01*
X4673148Y2355523D01*
X4673748Y2354990D01*
X4674248Y2354190D01*
X4674648Y2353256D01*
X4674748Y2351923D01*
X4674648Y2350590D01*
X4674248Y2349656D01*
X4673748Y2348856D01*
X4673148Y2348323D01*
X4672348Y2347923D01*
X4670348D01*
G01X4686348D02*
Y2355923D01*
X4688348D01*
X4689148Y2355523D01*
X4689748Y2354990D01*
X4690248Y2354190D01*
X4690648Y2353256D01*
X4690748Y2351923D01*
X4690648Y2350590D01*
X4690248Y2349656D01*
X4689748Y2348856D01*
X4689148Y2348323D01*
X4688348Y2347923D01*
X4686348D01*
G01X4694348Y2355923D02*
Y2350190D01*
X4694748Y2348989D01*
X4695548Y2348190D01*
X4696548Y2347923D01*
X4697548Y2348190D01*
X4698348Y2348989D01*
X4698748Y2350190D01*
Y2355923D01*
G01X4701948Y2347923D02*
Y2355923D01*
X4704548Y2349256D01*
X4707148Y2355923D01*
Y2347923D01*
G01X4709948D02*
Y2355923D01*
X4712548Y2349256D01*
X4715148Y2355923D01*
Y2347923D01*
G01X4720548D02*
Y2351523D01*
X4718548Y2355923D01*
G01X4722548D02*
X4720548Y2351523D01*
G01X4734548Y2347923D02*
Y2355923D01*
X4736948D01*
X4737748Y2355523D01*
X4738348Y2354590D01*
X4738548Y2353523D01*
X4738348Y2352456D01*
X4737848Y2351656D01*
X4736948Y2351256D01*
X4734548D01*
G01X4742048Y2347923D02*
X4744548Y2355923D01*
X4747048Y2347923D01*
G01X4746148Y2350723D02*
X4742948D01*
G01X4750348Y2347923D02*
Y2355923D01*
X4752348D01*
X4753148Y2355523D01*
X4753748Y2354990D01*
X4754248Y2354190D01*
X4754648Y2353256D01*
X4754748Y2351923D01*
X4754648Y2350590D01*
X4754248Y2349656D01*
X4753748Y2348856D01*
X4753148Y2348323D01*
X4752348Y2347923D01*
X4750348D01*
G01X4760548Y2347656D02*
X4760348Y2347790D01*
Y2348056D01*
X4760548Y2348190D01*
X4760748Y2348056D01*
Y2347790D01*
X4760548Y2347656D01*
G01X3142348Y2409123D02*
X3142948Y2408456D01*
X3143648Y2408056D01*
X3144548Y2407923D01*
X3145448Y2408190D01*
X3146148Y2408723D01*
X3146648Y2409656D01*
X3146748Y2410723D01*
X3146548Y2411790D01*
X3146048Y2412456D01*
X3145348Y2412990D01*
X3144648Y2413123D01*
X3143948Y2412990D01*
X3143048Y2412456D01*
X3143348Y2415923D01*
X3146048D01*
G01X3152548Y2407656D02*
X3152348Y2407790D01*
Y2408056D01*
X3152548Y2408190D01*
X3152748Y2408056D01*
Y2407790D01*
X3152548Y2407656D01*
G01X3158548Y2407923D02*
Y2415923D01*
X3160948D01*
X3161748Y2415523D01*
X3162348Y2414590D01*
X3162548Y2413523D01*
X3162348Y2412456D01*
X3161848Y2411656D01*
X3160948Y2411256D01*
X3158548D01*
G01X3170548Y2407923D02*
X3166548D01*
Y2415923D01*
X3170548D01*
G01X3168948Y2412056D02*
X3166548D01*
G01X3178548Y2407923D02*
X3174548D01*
Y2415923D01*
X3178548D01*
G01X3176948Y2412056D02*
X3174548D01*
G01X3182548Y2415923D02*
Y2407923D01*
X3186548D01*
G01X3191348Y2415923D02*
X3193748D01*
G01X3192548D02*
Y2407923D01*
G01X3191348D02*
X3193748D01*
G01X3198248D02*
Y2415923D01*
X3202848Y2407923D01*
Y2415923D01*
G01X3209148Y2411923D02*
X3211148D01*
Y2409523D01*
X3210548Y2408723D01*
X3209848Y2408190D01*
X3208848Y2407923D01*
X3207848Y2408190D01*
X3207148Y2408723D01*
X3206548Y2409523D01*
X3206148Y2410456D01*
X3205948Y2411523D01*
Y2412456D01*
X3206148Y2413256D01*
X3206548Y2414190D01*
X3207148Y2414990D01*
X3207748Y2415523D01*
X3208548Y2415923D01*
X3209248D01*
X3210048Y2415656D01*
X3210648Y2415123D01*
G01X3222448Y2408989D02*
X3223248Y2408323D01*
X3224148Y2407923D01*
X3224948D01*
X3225748Y2408323D01*
X3226348Y2408989D01*
X3226648Y2409923D01*
X3226448Y2410856D01*
X3225948Y2411656D01*
X3225048Y2412190D01*
X3223848Y2412456D01*
X3223148Y2412990D01*
X3222848Y2413923D01*
X3223048Y2414856D01*
X3223548Y2415523D01*
X3224248Y2415923D01*
X3224948D01*
X3225648Y2415656D01*
X3226248Y2414990D01*
G01X3232548Y2415923D02*
Y2407923D01*
G01X3230248Y2415923D02*
X3234848D01*
G01X3238548Y2407923D02*
Y2415923D01*
X3241048D01*
X3241848Y2415523D01*
X3242348Y2414990D01*
X3242548Y2413923D01*
X3242348Y2412856D01*
X3241748Y2412190D01*
X3241048Y2411790D01*
X3238548D01*
G01X3241048D02*
X3242548Y2407923D01*
G01X3250548D02*
X3246548D01*
Y2415923D01*
X3250548D01*
G01X3248948Y2412056D02*
X3246548D01*
G01X3254248Y2407923D02*
Y2415923D01*
X3258848Y2407923D01*
Y2415923D01*
G01X3265148Y2411923D02*
X3267148D01*
Y2409523D01*
X3266548Y2408723D01*
X3265848Y2408190D01*
X3264848Y2407923D01*
X3263848Y2408190D01*
X3263148Y2408723D01*
X3262548Y2409523D01*
X3262148Y2410456D01*
X3261948Y2411523D01*
Y2412456D01*
X3262148Y2413256D01*
X3262548Y2414190D01*
X3263148Y2414990D01*
X3263748Y2415523D01*
X3264548Y2415923D01*
X3265248D01*
X3266048Y2415656D01*
X3266648Y2415123D01*
G01X3272548Y2415923D02*
Y2407923D01*
G01X3270248Y2415923D02*
X3274848D01*
G01X3278448Y2407923D02*
Y2415923D01*
G01X3282648D02*
Y2407923D01*
G01Y2411923D02*
X3278448D01*
G01X3294048Y2407923D02*
X3296548Y2415923D01*
X3299048Y2407923D01*
G01X3298148Y2410723D02*
X3294948D01*
G01X3302248Y2407923D02*
Y2415923D01*
X3306848Y2407923D01*
Y2415923D01*
G01X3310348Y2407923D02*
Y2415923D01*
X3312348D01*
X3313148Y2415523D01*
X3313748Y2414990D01*
X3314248Y2414190D01*
X3314648Y2413256D01*
X3314748Y2411923D01*
X3314648Y2410590D01*
X3314248Y2409656D01*
X3313748Y2408856D01*
X3313148Y2408323D01*
X3312348Y2407923D01*
X3310348D01*
G01X3329348Y2412190D02*
X3329748Y2412590D01*
X3330048Y2413256D01*
X3330248Y2414190D01*
X3330048Y2414990D01*
X3329648Y2415523D01*
X3328948Y2415923D01*
X3326248D01*
Y2407923D01*
X3329548D01*
X3330248Y2408456D01*
X3330648Y2409256D01*
X3330848Y2410190D01*
X3330648Y2411123D01*
X3330048Y2411923D01*
X3329348Y2412190D01*
X3326248D01*
G01X3337148Y2411923D02*
X3339148D01*
Y2409523D01*
X3338548Y2408723D01*
X3337848Y2408190D01*
X3336848Y2407923D01*
X3335848Y2408190D01*
X3335148Y2408723D01*
X3334548Y2409523D01*
X3334148Y2410456D01*
X3333948Y2411523D01*
Y2412456D01*
X3334148Y2413256D01*
X3334548Y2414190D01*
X3335148Y2414990D01*
X3335748Y2415523D01*
X3336548Y2415923D01*
X3337248D01*
X3338048Y2415656D01*
X3338648Y2415123D01*
G01X3342048Y2407923D02*
X3344548Y2415923D01*
X3347048Y2407923D01*
G01X3346148Y2410723D02*
X3342948D01*
G01X3358548Y2407923D02*
Y2415923D01*
X3360948D01*
X3361748Y2415523D01*
X3362348Y2414590D01*
X3362548Y2413523D01*
X3362348Y2412456D01*
X3361848Y2411656D01*
X3360948Y2411256D01*
X3358548D01*
G01X3366048Y2407923D02*
X3368548Y2415923D01*
X3371048Y2407923D01*
G01X3370148Y2410723D02*
X3366948D01*
G01X3374348Y2407923D02*
Y2415923D01*
X3376348D01*
X3377148Y2415523D01*
X3377748Y2414990D01*
X3378248Y2414190D01*
X3378648Y2413256D01*
X3378748Y2411923D01*
X3378648Y2410590D01*
X3378248Y2409656D01*
X3377748Y2408856D01*
X3377148Y2408323D01*
X3376348Y2407923D01*
X3374348D01*
G01X3382448Y2408989D02*
X3383248Y2408323D01*
X3384148Y2407923D01*
X3384948D01*
X3385748Y2408323D01*
X3386348Y2408989D01*
X3386648Y2409923D01*
X3386448Y2410856D01*
X3385948Y2411656D01*
X3385048Y2412190D01*
X3383848Y2412456D01*
X3383148Y2412990D01*
X3382848Y2413923D01*
X3383048Y2414856D01*
X3383548Y2415523D01*
X3384248Y2415923D01*
X3384948D01*
X3385648Y2415656D01*
X3386248Y2414990D01*
G01X3398048Y2407923D02*
X3400548Y2415923D01*
X3403048Y2407923D01*
G01X3402148Y2410723D02*
X3398948D01*
G01X3406348Y2407923D02*
Y2415923D01*
X3408348D01*
X3409148Y2415523D01*
X3409748Y2414990D01*
X3410248Y2414190D01*
X3410648Y2413256D01*
X3410748Y2411923D01*
X3410648Y2410590D01*
X3410248Y2409656D01*
X3409748Y2408856D01*
X3409148Y2408323D01*
X3408348Y2407923D01*
X3406348D01*
G01X3414448D02*
Y2415923D01*
G01X3418648D02*
Y2407923D01*
G01Y2411923D02*
X3414448D01*
G01X3426548Y2407923D02*
X3422548D01*
Y2415923D01*
X3426548D01*
G01X3424948Y2412056D02*
X3422548D01*
G01X3430448Y2408989D02*
X3431248Y2408323D01*
X3432148Y2407923D01*
X3432948D01*
X3433748Y2408323D01*
X3434348Y2408989D01*
X3434648Y2409923D01*
X3434448Y2410856D01*
X3433948Y2411656D01*
X3433048Y2412190D01*
X3431848Y2412456D01*
X3431148Y2412990D01*
X3430848Y2413923D01*
X3431048Y2414856D01*
X3431548Y2415523D01*
X3432248Y2415923D01*
X3432948D01*
X3433648Y2415656D01*
X3434248Y2414990D01*
G01X3439348Y2415923D02*
X3441748D01*
G01X3440548D02*
Y2407923D01*
G01X3439348D02*
X3441748D01*
G01X3448548D02*
X3447748Y2408056D01*
X3447048Y2408590D01*
X3446448Y2409390D01*
X3446048Y2410323D01*
X3445848Y2411390D01*
Y2412456D01*
X3446048Y2413523D01*
X3446448Y2414456D01*
X3447048Y2415256D01*
X3447748Y2415790D01*
X3448548Y2415923D01*
X3449348Y2415790D01*
X3450048Y2415256D01*
X3450648Y2414456D01*
X3451048Y2413523D01*
X3451248Y2412456D01*
Y2411390D01*
X3451048Y2410323D01*
X3450648Y2409390D01*
X3450048Y2408590D01*
X3449348Y2408056D01*
X3448548Y2407923D01*
G01X3454248D02*
Y2415923D01*
X3458848Y2407923D01*
Y2415923D01*
G01X3472548D02*
Y2407923D01*
G01X3470248Y2415923D02*
X3474848D01*
G01X3482548Y2407923D02*
X3478548D01*
Y2415923D01*
X3482548D01*
G01X3480948Y2412056D02*
X3478548D01*
G01X3486448Y2408989D02*
X3487248Y2408323D01*
X3488148Y2407923D01*
X3488948D01*
X3489748Y2408323D01*
X3490348Y2408989D01*
X3490648Y2409923D01*
X3490448Y2410856D01*
X3489948Y2411656D01*
X3489048Y2412190D01*
X3487848Y2412456D01*
X3487148Y2412990D01*
X3486848Y2413923D01*
X3487048Y2414856D01*
X3487548Y2415523D01*
X3488248Y2415923D01*
X3488948D01*
X3489648Y2415656D01*
X3490248Y2414990D01*
G01X3496548Y2415923D02*
Y2407923D01*
G01X3494248Y2415923D02*
X3498848D01*
G01X3510548Y2407923D02*
Y2415923D01*
X3512948D01*
X3513748Y2415523D01*
X3514348Y2414590D01*
X3514548Y2413523D01*
X3514348Y2412456D01*
X3513848Y2411656D01*
X3512948Y2411256D01*
X3510548D01*
G01X3518048Y2407923D02*
X3520548Y2415923D01*
X3523048Y2407923D01*
G01X3522148Y2410723D02*
X3518948D01*
G01X3528548Y2415923D02*
Y2407923D01*
G01X3526248Y2415923D02*
X3530848D01*
G01X3536548D02*
Y2407923D01*
G01X3534248Y2415923D02*
X3538848D01*
G01X3546548Y2407923D02*
X3542548D01*
Y2415923D01*
X3546548D01*
G01X3544948Y2412056D02*
X3542548D01*
G01X3550548Y2407923D02*
Y2415923D01*
X3553048D01*
X3553848Y2415523D01*
X3554348Y2414990D01*
X3554548Y2413923D01*
X3554348Y2412856D01*
X3553748Y2412190D01*
X3553048Y2411790D01*
X3550548D01*
G01X3553048D02*
X3554548Y2407923D01*
G01X3558248D02*
Y2415923D01*
X3562848Y2407923D01*
Y2415923D01*
G01X3566448Y2408989D02*
X3567248Y2408323D01*
X3568148Y2407923D01*
X3568948D01*
X3569748Y2408323D01*
X3570348Y2408989D01*
X3570648Y2409923D01*
X3570448Y2410856D01*
X3569948Y2411656D01*
X3569048Y2412190D01*
X3567848Y2412456D01*
X3567148Y2412990D01*
X3566848Y2413923D01*
X3567048Y2414856D01*
X3567548Y2415523D01*
X3568248Y2415923D01*
X3568948D01*
X3569648Y2415656D01*
X3570248Y2414990D01*
G01X3576548Y2407656D02*
X3576348Y2407790D01*
Y2408056D01*
X3576548Y2408190D01*
X3576748Y2408056D01*
Y2407790D01*
X3576548Y2407656D01*
G01X3145748Y2482923D02*
Y2490923D01*
X3142048Y2485190D01*
X3147048D01*
G01X3152548Y2482656D02*
X3152348Y2482790D01*
Y2483056D01*
X3152548Y2483190D01*
X3152748Y2483056D01*
Y2482790D01*
X3152548Y2482656D01*
G01X3162748Y2490256D02*
X3162148Y2490656D01*
X3161448Y2490923D01*
X3160648D01*
X3159748Y2490523D01*
X3159048Y2489856D01*
X3158548Y2489056D01*
X3158148Y2487723D01*
X3158048Y2486523D01*
X3158248Y2485323D01*
X3158548Y2484523D01*
X3159148Y2483723D01*
X3159848Y2483190D01*
X3160548Y2482923D01*
X3161248D01*
X3161948Y2483190D01*
X3162548Y2483590D01*
X3163048Y2484123D01*
G01X3168548Y2482923D02*
X3167748Y2483056D01*
X3167048Y2483590D01*
X3166448Y2484390D01*
X3166048Y2485323D01*
X3165848Y2486390D01*
Y2487456D01*
X3166048Y2488523D01*
X3166448Y2489456D01*
X3167048Y2490256D01*
X3167748Y2490790D01*
X3168548Y2490923D01*
X3169348Y2490790D01*
X3170048Y2490256D01*
X3170648Y2489456D01*
X3171048Y2488523D01*
X3171248Y2487456D01*
Y2486390D01*
X3171048Y2485323D01*
X3170648Y2484390D01*
X3170048Y2483590D01*
X3169348Y2483056D01*
X3168548Y2482923D01*
G01X3174248D02*
Y2490923D01*
X3178848Y2482923D01*
Y2490923D01*
G01X3184548D02*
Y2482923D01*
G01X3182248Y2490923D02*
X3186848D01*
G01X3190548Y2482923D02*
Y2490923D01*
X3193048D01*
X3193848Y2490523D01*
X3194348Y2489990D01*
X3194548Y2488923D01*
X3194348Y2487856D01*
X3193748Y2487190D01*
X3193048Y2486790D01*
X3190548D01*
G01X3193048D02*
X3194548Y2482923D01*
G01X3200548D02*
X3199748Y2483056D01*
X3199048Y2483590D01*
X3198448Y2484390D01*
X3198048Y2485323D01*
X3197848Y2486390D01*
Y2487456D01*
X3198048Y2488523D01*
X3198448Y2489456D01*
X3199048Y2490256D01*
X3199748Y2490790D01*
X3200548Y2490923D01*
X3201348Y2490790D01*
X3202048Y2490256D01*
X3202648Y2489456D01*
X3203048Y2488523D01*
X3203248Y2487456D01*
Y2486390D01*
X3203048Y2485323D01*
X3202648Y2484390D01*
X3202048Y2483590D01*
X3201348Y2483056D01*
X3200548Y2482923D01*
G01X3206548Y2490923D02*
Y2482923D01*
X3210548D01*
G01X3214548Y2490923D02*
Y2482923D01*
X3218548D01*
G01X3226548D02*
X3222548D01*
Y2490923D01*
X3226548D01*
G01X3224948Y2487056D02*
X3222548D01*
G01X3230348Y2482923D02*
Y2490923D01*
X3232348D01*
X3233148Y2490523D01*
X3233748Y2489990D01*
X3234248Y2489190D01*
X3234648Y2488256D01*
X3234748Y2486923D01*
X3234648Y2485590D01*
X3234248Y2484656D01*
X3233748Y2483856D01*
X3233148Y2483323D01*
X3232348Y2482923D01*
X3230348D01*
G01X3247348Y2490923D02*
X3249748D01*
G01X3248548D02*
Y2482923D01*
G01X3247348D02*
X3249748D01*
G01X3253948D02*
Y2490923D01*
X3256548Y2484256D01*
X3259148Y2490923D01*
Y2482923D01*
G01X3262548D02*
Y2490923D01*
X3264948D01*
X3265748Y2490523D01*
X3266348Y2489590D01*
X3266548Y2488523D01*
X3266348Y2487456D01*
X3265848Y2486656D01*
X3264948Y2486256D01*
X3262548D01*
G01X3274548Y2482923D02*
X3270548D01*
Y2490923D01*
X3274548D01*
G01X3272948Y2487056D02*
X3270548D01*
G01X3278348Y2482923D02*
Y2490923D01*
X3280348D01*
X3281148Y2490523D01*
X3281748Y2489990D01*
X3282248Y2489190D01*
X3282648Y2488256D01*
X3282748Y2486923D01*
X3282648Y2485590D01*
X3282248Y2484656D01*
X3281748Y2483856D01*
X3281148Y2483323D01*
X3280348Y2482923D01*
X3278348D01*
G01X3286048D02*
X3288548Y2490923D01*
X3291048Y2482923D01*
G01X3290148Y2485723D02*
X3286948D01*
G01X3294248Y2482923D02*
Y2490923D01*
X3298848Y2482923D01*
Y2490923D01*
G01X3306748Y2490256D02*
X3306148Y2490656D01*
X3305448Y2490923D01*
X3304648D01*
X3303748Y2490523D01*
X3303048Y2489856D01*
X3302548Y2489056D01*
X3302148Y2487723D01*
X3302048Y2486523D01*
X3302248Y2485323D01*
X3302548Y2484523D01*
X3303148Y2483723D01*
X3303848Y2483190D01*
X3304548Y2482923D01*
X3305248D01*
X3305948Y2483190D01*
X3306548Y2483590D01*
X3307048Y2484123D01*
G01X3314548Y2482923D02*
X3310548D01*
Y2490923D01*
X3314548D01*
G01X3312948Y2487056D02*
X3310548D01*
G01X3329348Y2487190D02*
X3329748Y2487590D01*
X3330048Y2488256D01*
X3330248Y2489190D01*
X3330048Y2489990D01*
X3329648Y2490523D01*
X3328948Y2490923D01*
X3326248D01*
Y2482923D01*
X3329548D01*
X3330248Y2483456D01*
X3330648Y2484256D01*
X3330848Y2485190D01*
X3330648Y2486123D01*
X3330048Y2486923D01*
X3329348Y2487190D01*
X3326248D01*
G01X3336548Y2482923D02*
X3335748Y2483056D01*
X3335048Y2483590D01*
X3334448Y2484390D01*
X3334048Y2485323D01*
X3333848Y2486390D01*
Y2487456D01*
X3334048Y2488523D01*
X3334448Y2489456D01*
X3335048Y2490256D01*
X3335748Y2490790D01*
X3336548Y2490923D01*
X3337348Y2490790D01*
X3338048Y2490256D01*
X3338648Y2489456D01*
X3339048Y2488523D01*
X3339248Y2487456D01*
Y2486390D01*
X3339048Y2485323D01*
X3338648Y2484390D01*
X3338048Y2483590D01*
X3337348Y2483056D01*
X3336548Y2482923D01*
G01X3342048D02*
X3344548Y2490923D01*
X3347048Y2482923D01*
G01X3346148Y2485723D02*
X3342948D01*
G01X3350548Y2482923D02*
Y2490923D01*
X3353048D01*
X3353848Y2490523D01*
X3354348Y2489990D01*
X3354548Y2488923D01*
X3354348Y2487856D01*
X3353748Y2487190D01*
X3353048Y2486790D01*
X3350548D01*
G01X3353048D02*
X3354548Y2482923D01*
G01X3358348D02*
Y2490923D01*
X3360348D01*
X3361148Y2490523D01*
X3361748Y2489990D01*
X3362248Y2489190D01*
X3362648Y2488256D01*
X3362748Y2486923D01*
X3362648Y2485590D01*
X3362248Y2484656D01*
X3361748Y2483856D01*
X3361148Y2483323D01*
X3360348Y2482923D01*
X3358348D01*
G01X3368548Y2482656D02*
X3368348Y2482790D01*
Y2483056D01*
X3368548Y2483190D01*
X3368748Y2483056D01*
Y2482790D01*
X3368548Y2482656D01*
G01X3382448Y2483989D02*
X3383248Y2483323D01*
X3384148Y2482923D01*
X3384948D01*
X3385748Y2483323D01*
X3386348Y2483989D01*
X3386648Y2484923D01*
X3386448Y2485856D01*
X3385948Y2486656D01*
X3385048Y2487190D01*
X3383848Y2487456D01*
X3383148Y2487990D01*
X3382848Y2488923D01*
X3383048Y2489856D01*
X3383548Y2490523D01*
X3384248Y2490923D01*
X3384948D01*
X3385648Y2490656D01*
X3386248Y2489990D01*
G01X3394548Y2482923D02*
X3390548D01*
Y2490923D01*
X3394548D01*
G01X3392948Y2487056D02*
X3390548D01*
G01X3402548Y2482923D02*
X3398548D01*
Y2490923D01*
X3402548D01*
G01X3400948Y2487056D02*
X3398548D01*
G01X3414548Y2490923D02*
Y2482923D01*
X3418548D01*
G01X3422048D02*
X3424548Y2490923D01*
X3427048Y2482923D01*
G01X3426148Y2485723D02*
X3422948D01*
G01X3432548Y2482923D02*
Y2486523D01*
X3430548Y2490923D01*
G01X3434548D02*
X3432548Y2486523D01*
G01X3442548Y2482923D02*
X3438548D01*
Y2490923D01*
X3442548D01*
G01X3440948Y2487056D02*
X3438548D01*
G01X3446548Y2482923D02*
Y2490923D01*
X3449048D01*
X3449848Y2490523D01*
X3450348Y2489990D01*
X3450548Y2488923D01*
X3450348Y2487856D01*
X3449748Y2487190D01*
X3449048Y2486790D01*
X3446548D01*
G01X3449048D02*
X3450548Y2482923D01*
G01X3462448Y2483989D02*
X3463248Y2483323D01*
X3464148Y2482923D01*
X3464948D01*
X3465748Y2483323D01*
X3466348Y2483989D01*
X3466648Y2484923D01*
X3466448Y2485856D01*
X3465948Y2486656D01*
X3465048Y2487190D01*
X3463848Y2487456D01*
X3463148Y2487990D01*
X3462848Y2488923D01*
X3463048Y2489856D01*
X3463548Y2490523D01*
X3464248Y2490923D01*
X3464948D01*
X3465648Y2490656D01*
X3466248Y2489990D01*
G01X3472548Y2490923D02*
Y2482923D01*
G01X3470248Y2490923D02*
X3474848D01*
G01X3478048Y2482923D02*
X3480548Y2490923D01*
X3483048Y2482923D01*
G01X3482148Y2485723D02*
X3478948D01*
G01X3490748Y2490256D02*
X3490148Y2490656D01*
X3489448Y2490923D01*
X3488648D01*
X3487748Y2490523D01*
X3487048Y2489856D01*
X3486548Y2489056D01*
X3486148Y2487723D01*
X3486048Y2486523D01*
X3486248Y2485323D01*
X3486548Y2484523D01*
X3487148Y2483723D01*
X3487848Y2483190D01*
X3488548Y2482923D01*
X3489248D01*
X3489948Y2483190D01*
X3490548Y2483590D01*
X3491048Y2484123D01*
G01X3494348Y2482923D02*
Y2490923D01*
G01X3498148D02*
X3494348Y2485989D01*
G01X3498748Y2482923D02*
X3496048Y2488256D01*
G01X3502348Y2490923D02*
Y2485190D01*
X3502748Y2483989D01*
X3503548Y2483190D01*
X3504548Y2482923D01*
X3505548Y2483190D01*
X3506348Y2483989D01*
X3506748Y2485190D01*
Y2490923D01*
G01X3510548Y2482923D02*
Y2490923D01*
X3512948D01*
X3513748Y2490523D01*
X3514348Y2489590D01*
X3514548Y2488523D01*
X3514348Y2487456D01*
X3513848Y2486656D01*
X3512948Y2486256D01*
X3510548D01*
G01X3526048Y2482923D02*
X3528548Y2490923D01*
X3531048Y2482923D01*
G01X3530148Y2485723D02*
X3526948D01*
G01X3534248Y2482923D02*
Y2490923D01*
X3538848Y2482923D01*
Y2490923D01*
G01X3542348Y2482923D02*
Y2490923D01*
X3544348D01*
X3545148Y2490523D01*
X3545748Y2489990D01*
X3546248Y2489190D01*
X3546648Y2488256D01*
X3546748Y2486923D01*
X3546648Y2485590D01*
X3546248Y2484656D01*
X3545748Y2483856D01*
X3545148Y2483323D01*
X3544348Y2482923D01*
X3542348D01*
G01X3559348Y2490923D02*
X3561748D01*
G01X3560548D02*
Y2482923D01*
G01X3559348D02*
X3561748D01*
G01X3565948D02*
Y2490923D01*
X3568548Y2484256D01*
X3571148Y2490923D01*
Y2482923D01*
G01X3574548D02*
Y2490923D01*
X3576948D01*
X3577748Y2490523D01*
X3578348Y2489590D01*
X3578548Y2488523D01*
X3578348Y2487456D01*
X3577848Y2486656D01*
X3576948Y2486256D01*
X3574548D01*
G01X3586548Y2482923D02*
X3582548D01*
Y2490923D01*
X3586548D01*
G01X3584948Y2487056D02*
X3582548D01*
G01X3590348Y2482923D02*
Y2490923D01*
X3592348D01*
X3593148Y2490523D01*
X3593748Y2489990D01*
X3594248Y2489190D01*
X3594648Y2488256D01*
X3594748Y2486923D01*
X3594648Y2485590D01*
X3594248Y2484656D01*
X3593748Y2483856D01*
X3593148Y2483323D01*
X3592348Y2482923D01*
X3590348D01*
G01X3598048D02*
X3600548Y2490923D01*
X3603048Y2482923D01*
G01X3602148Y2485723D02*
X3598948D01*
G01X3606248Y2482923D02*
Y2490923D01*
X3610848Y2482923D01*
Y2490923D01*
G01X3618748Y2490256D02*
X3618148Y2490656D01*
X3617448Y2490923D01*
X3616648D01*
X3615748Y2490523D01*
X3615048Y2489856D01*
X3614548Y2489056D01*
X3614148Y2487723D01*
X3614048Y2486523D01*
X3614248Y2485323D01*
X3614548Y2484523D01*
X3615148Y2483723D01*
X3615848Y2483190D01*
X3616548Y2482923D01*
X3617248D01*
X3617948Y2483190D01*
X3618548Y2483590D01*
X3619048Y2484123D01*
G01X3626548Y2482923D02*
X3622548D01*
Y2490923D01*
X3626548D01*
G01X3624948Y2487056D02*
X3622548D01*
G01X3163148Y2501923D02*
X3165148D01*
Y2499523D01*
X3164548Y2498723D01*
X3163848Y2498190D01*
X3162848Y2497923D01*
X3161848Y2498190D01*
X3161148Y2498723D01*
X3160548Y2499523D01*
X3160148Y2500456D01*
X3159948Y2501523D01*
Y2502456D01*
X3160148Y2503256D01*
X3160548Y2504190D01*
X3161148Y2504990D01*
X3161748Y2505523D01*
X3162548Y2505923D01*
X3163248D01*
X3164048Y2505656D01*
X3164648Y2505123D01*
G01X3170548Y2497656D02*
X3170348Y2497790D01*
Y2498056D01*
X3170548Y2498190D01*
X3170748Y2498056D01*
Y2497790D01*
X3170548Y2497656D01*
G01X3176248Y2497923D02*
Y2505923D01*
X3180848Y2497923D01*
Y2505923D01*
G01X3188548Y2497923D02*
X3184548D01*
Y2505923D01*
X3188548D01*
G01X3186948Y2502056D02*
X3184548D01*
G01X3196548Y2497923D02*
X3192548D01*
Y2505923D01*
X3196548D01*
G01X3194948Y2502056D02*
X3192548D01*
G01X3200348Y2497923D02*
Y2505923D01*
X3202348D01*
X3203148Y2505523D01*
X3203748Y2504990D01*
X3204248Y2504190D01*
X3204648Y2503256D01*
X3204748Y2501923D01*
X3204648Y2500590D01*
X3204248Y2499656D01*
X3203748Y2498856D01*
X3203148Y2498323D01*
X3202348Y2497923D01*
X3200348D01*
G01X3216348Y2505923D02*
Y2500190D01*
X3216748Y2498989D01*
X3217548Y2498190D01*
X3218548Y2497923D01*
X3219548Y2498190D01*
X3220348Y2498989D01*
X3220748Y2500190D01*
Y2505923D01*
G01X3224548D02*
Y2497923D01*
X3228548D01*
G01X3239948D02*
Y2505923D01*
X3242548Y2499256D01*
X3245148Y2505923D01*
Y2497923D01*
G01X3248048D02*
X3250548Y2505923D01*
X3253048Y2497923D01*
G01X3252148Y2500723D02*
X3248948D01*
G01X3256548Y2497923D02*
Y2505923D01*
X3259048D01*
X3259848Y2505523D01*
X3260348Y2504990D01*
X3260548Y2503923D01*
X3260348Y2502856D01*
X3259748Y2502190D01*
X3259048Y2501790D01*
X3256548D01*
G01X3259048D02*
X3260548Y2497923D01*
G01X3264348D02*
Y2505923D01*
G01X3268148D02*
X3264348Y2500989D01*
G01X3268748Y2497923D02*
X3266048Y2503256D01*
G01X3280048Y2497923D02*
X3282548Y2505923D01*
X3285048Y2497923D01*
G01X3284148Y2500723D02*
X3280948D01*
G01X3288248Y2497923D02*
Y2505923D01*
X3292848Y2497923D01*
Y2505923D01*
G01X3296348Y2497923D02*
Y2505923D01*
X3298348D01*
X3299148Y2505523D01*
X3299748Y2504990D01*
X3300248Y2504190D01*
X3300648Y2503256D01*
X3300748Y2501923D01*
X3300648Y2500590D01*
X3300248Y2499656D01*
X3299748Y2498856D01*
X3299148Y2498323D01*
X3298348Y2497923D01*
X3296348D01*
G01X3312348Y2505923D02*
Y2500190D01*
X3312748Y2498989D01*
X3313548Y2498190D01*
X3314548Y2497923D01*
X3315548Y2498190D01*
X3316348Y2498989D01*
X3316748Y2500190D01*
Y2505923D01*
G01X3320548D02*
Y2497923D01*
X3324548D01*
G01X3336648D02*
Y2505923D01*
X3340448D01*
G01X3339048Y2502056D02*
X3336648D01*
G01X3345348Y2505923D02*
X3347748D01*
G01X3346548D02*
Y2497923D01*
G01X3345348D02*
X3347748D01*
G01X3352548Y2505923D02*
Y2497923D01*
X3356548D01*
G01X3364548D02*
X3360548D01*
Y2505923D01*
X3364548D01*
G01X3362948Y2502056D02*
X3360548D01*
G01X3376248Y2497923D02*
Y2505923D01*
X3380848Y2497923D01*
Y2505923D01*
G01X3384348D02*
Y2500190D01*
X3384748Y2498989D01*
X3385548Y2498190D01*
X3386548Y2497923D01*
X3387548Y2498190D01*
X3388348Y2498989D01*
X3388748Y2500190D01*
Y2505923D01*
G01X3391948Y2497923D02*
Y2505923D01*
X3394548Y2499256D01*
X3397148Y2505923D01*
Y2497923D01*
G01X3403348Y2502190D02*
X3403748Y2502590D01*
X3404048Y2503256D01*
X3404248Y2504190D01*
X3404048Y2504990D01*
X3403648Y2505523D01*
X3402948Y2505923D01*
X3400248D01*
Y2497923D01*
X3403548D01*
X3404248Y2498456D01*
X3404648Y2499256D01*
X3404848Y2500190D01*
X3404648Y2501123D01*
X3404048Y2501923D01*
X3403348Y2502190D01*
X3400248D01*
G01X3412548Y2497923D02*
X3408548D01*
Y2505923D01*
X3412548D01*
G01X3410948Y2502056D02*
X3408548D01*
G01X3416548Y2497923D02*
Y2505923D01*
X3419048D01*
X3419848Y2505523D01*
X3420348Y2504990D01*
X3420548Y2503923D01*
X3420348Y2502856D01*
X3419748Y2502190D01*
X3419048Y2501790D01*
X3416548D01*
G01X3419048D02*
X3420548Y2497923D01*
G01X3434548D02*
X3433948Y2498056D01*
X3433348Y2498590D01*
X3432948Y2499523D01*
X3432748Y2500590D01*
X3432948Y2501656D01*
X3433348Y2502590D01*
X3433948Y2503123D01*
X3434548Y2503256D01*
X3435148Y2503123D01*
X3435748Y2502590D01*
X3436148Y2501656D01*
X3436248Y2500590D01*
X3436148Y2499523D01*
X3435748Y2498590D01*
X3435148Y2498056D01*
X3434548Y2497923D01*
G01X3440848D02*
Y2503256D01*
G01Y2501923D02*
X3441248Y2502590D01*
X3441848Y2503123D01*
X3442648Y2503256D01*
X3443348Y2503123D01*
X3443948Y2502590D01*
X3444248Y2501656D01*
Y2497923D01*
G01X3456448Y2498989D02*
X3457248Y2498323D01*
X3458148Y2497923D01*
X3458948D01*
X3459748Y2498323D01*
X3460348Y2498989D01*
X3460648Y2499923D01*
X3460448Y2500856D01*
X3459948Y2501656D01*
X3459048Y2502190D01*
X3457848Y2502456D01*
X3457148Y2502990D01*
X3456848Y2503923D01*
X3457048Y2504856D01*
X3457548Y2505523D01*
X3458248Y2505923D01*
X3458948D01*
X3459648Y2505656D01*
X3460248Y2504990D01*
G01X3465348Y2505923D02*
X3467748D01*
G01X3466548D02*
Y2497923D01*
G01X3465348D02*
X3467748D01*
G01X3472548Y2505923D02*
Y2497923D01*
X3476548D01*
G01X3480348D02*
Y2505923D01*
G01X3484148D02*
X3480348Y2500989D01*
G01X3484748Y2497923D02*
X3482048Y2503256D01*
G01X3488448Y2498989D02*
X3489248Y2498323D01*
X3490148Y2497923D01*
X3490948D01*
X3491748Y2498323D01*
X3492348Y2498989D01*
X3492648Y2499923D01*
X3492448Y2500856D01*
X3491948Y2501656D01*
X3491048Y2502190D01*
X3489848Y2502456D01*
X3489148Y2502990D01*
X3488848Y2503923D01*
X3489048Y2504856D01*
X3489548Y2505523D01*
X3490248Y2505923D01*
X3490948D01*
X3491648Y2505656D01*
X3492248Y2504990D01*
G01X3500748Y2505256D02*
X3500148Y2505656D01*
X3499448Y2505923D01*
X3498648D01*
X3497748Y2505523D01*
X3497048Y2504856D01*
X3496548Y2504056D01*
X3496148Y2502723D01*
X3496048Y2501523D01*
X3496248Y2500323D01*
X3496548Y2499523D01*
X3497148Y2498723D01*
X3497848Y2498190D01*
X3498548Y2497923D01*
X3499248D01*
X3499948Y2498190D01*
X3500548Y2498590D01*
X3501048Y2499123D01*
G01X3504548Y2497923D02*
Y2505923D01*
X3507048D01*
X3507848Y2505523D01*
X3508348Y2504990D01*
X3508548Y2503923D01*
X3508348Y2502856D01*
X3507748Y2502190D01*
X3507048Y2501790D01*
X3504548D01*
G01X3507048D02*
X3508548Y2497923D01*
G01X3516548D02*
X3512548D01*
Y2505923D01*
X3516548D01*
G01X3514948Y2502056D02*
X3512548D01*
G01X3524548Y2497923D02*
X3520548D01*
Y2505923D01*
X3524548D01*
G01X3522948Y2502056D02*
X3520548D01*
G01X3528248Y2497923D02*
Y2505923D01*
X3532848Y2497923D01*
Y2505923D01*
G01X3546548D02*
Y2497923D01*
G01X3544248Y2505923D02*
X3548848D01*
G01X3554548Y2497923D02*
X3553748Y2498056D01*
X3553048Y2498590D01*
X3552448Y2499390D01*
X3552048Y2500323D01*
X3551848Y2501390D01*
Y2502456D01*
X3552048Y2503523D01*
X3552448Y2504456D01*
X3553048Y2505256D01*
X3553748Y2505790D01*
X3554548Y2505923D01*
X3555348Y2505790D01*
X3556048Y2505256D01*
X3556648Y2504456D01*
X3557048Y2503523D01*
X3557248Y2502456D01*
Y2501390D01*
X3557048Y2500323D01*
X3556648Y2499390D01*
X3556048Y2498590D01*
X3555348Y2498056D01*
X3554548Y2497923D01*
G01X3560548D02*
Y2505923D01*
X3562948D01*
X3563748Y2505523D01*
X3564348Y2504590D01*
X3564548Y2503523D01*
X3564348Y2502456D01*
X3563848Y2501656D01*
X3562948Y2501256D01*
X3560548D01*
G01X3576448Y2498989D02*
X3577248Y2498323D01*
X3578148Y2497923D01*
X3578948D01*
X3579748Y2498323D01*
X3580348Y2498989D01*
X3580648Y2499923D01*
X3580448Y2500856D01*
X3579948Y2501656D01*
X3579048Y2502190D01*
X3577848Y2502456D01*
X3577148Y2502990D01*
X3576848Y2503923D01*
X3577048Y2504856D01*
X3577548Y2505523D01*
X3578248Y2505923D01*
X3578948D01*
X3579648Y2505656D01*
X3580248Y2504990D01*
G01X3585348Y2505923D02*
X3587748D01*
G01X3586548D02*
Y2497923D01*
G01X3585348D02*
X3587748D01*
G01X3592348D02*
Y2505923D01*
X3594348D01*
X3595148Y2505523D01*
X3595748Y2504990D01*
X3596248Y2504190D01*
X3596648Y2503256D01*
X3596748Y2501923D01*
X3596648Y2500590D01*
X3596248Y2499656D01*
X3595748Y2498856D01*
X3595148Y2498323D01*
X3594348Y2497923D01*
X3592348D01*
G01X3604548D02*
X3600548D01*
Y2505923D01*
X3604548D01*
G01X3602948Y2502056D02*
X3600548D01*
G01X3160648Y2512923D02*
Y2520923D01*
X3164448D01*
G01X3163048Y2517056D02*
X3160648D01*
G01X3170548Y2512656D02*
X3170348Y2512790D01*
Y2513056D01*
X3170548Y2513190D01*
X3170748Y2513056D01*
Y2512790D01*
X3170548Y2512656D01*
G01X3176248Y2512923D02*
Y2520923D01*
X3180848Y2512923D01*
Y2520923D01*
G01X3188548Y2512923D02*
X3184548D01*
Y2520923D01*
X3188548D01*
G01X3186948Y2517056D02*
X3184548D01*
G01X3196548Y2512923D02*
X3192548D01*
Y2520923D01*
X3196548D01*
G01X3194948Y2517056D02*
X3192548D01*
G01X3200348Y2512923D02*
Y2520923D01*
X3202348D01*
X3203148Y2520523D01*
X3203748Y2519990D01*
X3204248Y2519190D01*
X3204648Y2518256D01*
X3204748Y2516923D01*
X3204648Y2515590D01*
X3204248Y2514656D01*
X3203748Y2513856D01*
X3203148Y2513323D01*
X3202348Y2512923D01*
X3200348D01*
G01X3216548D02*
Y2520923D01*
X3218948D01*
X3219748Y2520523D01*
X3220348Y2519590D01*
X3220548Y2518523D01*
X3220348Y2517456D01*
X3219848Y2516656D01*
X3218948Y2516256D01*
X3216548D01*
G01X3228748Y2520256D02*
X3228148Y2520656D01*
X3227448Y2520923D01*
X3226648D01*
X3225748Y2520523D01*
X3225048Y2519856D01*
X3224548Y2519056D01*
X3224148Y2517723D01*
X3224048Y2516523D01*
X3224248Y2515323D01*
X3224548Y2514523D01*
X3225148Y2513723D01*
X3225848Y2513190D01*
X3226548Y2512923D01*
X3227248D01*
X3227948Y2513190D01*
X3228548Y2513590D01*
X3229048Y2514123D01*
G01X3235348Y2517190D02*
X3235748Y2517590D01*
X3236048Y2518256D01*
X3236248Y2519190D01*
X3236048Y2519990D01*
X3235648Y2520523D01*
X3234948Y2520923D01*
X3232248D01*
Y2512923D01*
X3235548D01*
X3236248Y2513456D01*
X3236648Y2514256D01*
X3236848Y2515190D01*
X3236648Y2516123D01*
X3236048Y2516923D01*
X3235348Y2517190D01*
X3232248D01*
G01X3247948Y2512923D02*
Y2520923D01*
X3250548Y2514256D01*
X3253148Y2520923D01*
Y2512923D01*
G01X3256048D02*
X3258548Y2520923D01*
X3261048Y2512923D01*
G01X3260148Y2515723D02*
X3256948D01*
G01X3264348Y2512923D02*
Y2520923D01*
G01X3268148D02*
X3264348Y2515989D01*
G01X3268748Y2512923D02*
X3266048Y2518256D01*
G01X3276548Y2512923D02*
X3272548D01*
Y2520923D01*
X3276548D01*
G01X3274948Y2517056D02*
X3272548D01*
G01X3280548Y2512923D02*
Y2520923D01*
X3283048D01*
X3283848Y2520523D01*
X3284348Y2519990D01*
X3284548Y2518923D01*
X3284348Y2517856D01*
X3283748Y2517190D01*
X3283048Y2516790D01*
X3280548D01*
G01X3283048D02*
X3284548Y2512923D01*
G01X3296548Y2520923D02*
Y2512923D01*
X3300548D01*
G01X3306548D02*
X3305748Y2513056D01*
X3305048Y2513590D01*
X3304448Y2514390D01*
X3304048Y2515323D01*
X3303848Y2516390D01*
Y2517456D01*
X3304048Y2518523D01*
X3304448Y2519456D01*
X3305048Y2520256D01*
X3305748Y2520790D01*
X3306548Y2520923D01*
X3307348Y2520790D01*
X3308048Y2520256D01*
X3308648Y2519456D01*
X3309048Y2518523D01*
X3309248Y2517456D01*
Y2516390D01*
X3309048Y2515323D01*
X3308648Y2514390D01*
X3308048Y2513590D01*
X3307348Y2513056D01*
X3306548Y2512923D01*
G01X3315148Y2516923D02*
X3317148D01*
Y2514523D01*
X3316548Y2513723D01*
X3315848Y2513190D01*
X3314848Y2512923D01*
X3313848Y2513190D01*
X3313148Y2513723D01*
X3312548Y2514523D01*
X3312148Y2515456D01*
X3311948Y2516523D01*
Y2517456D01*
X3312148Y2518256D01*
X3312548Y2519190D01*
X3313148Y2519990D01*
X3313748Y2520523D01*
X3314548Y2520923D01*
X3315248D01*
X3316048Y2520656D01*
X3316648Y2520123D01*
G01X3322548Y2512923D02*
X3321748Y2513056D01*
X3321048Y2513590D01*
X3320448Y2514390D01*
X3320048Y2515323D01*
X3319848Y2516390D01*
Y2517456D01*
X3320048Y2518523D01*
X3320448Y2519456D01*
X3321048Y2520256D01*
X3321748Y2520790D01*
X3322548Y2520923D01*
X3323348Y2520790D01*
X3324048Y2520256D01*
X3324648Y2519456D01*
X3325048Y2518523D01*
X3325248Y2517456D01*
Y2516390D01*
X3325048Y2515323D01*
X3324648Y2514390D01*
X3324048Y2513590D01*
X3323348Y2513056D01*
X3322548Y2512923D01*
G01X3336048D02*
X3338548Y2520923D01*
X3341048Y2512923D01*
G01X3340148Y2515723D02*
X3336948D01*
G01X3344248Y2512923D02*
Y2520923D01*
X3348848Y2512923D01*
Y2520923D01*
G01X3352348Y2512923D02*
Y2520923D01*
X3354348D01*
X3355148Y2520523D01*
X3355748Y2519990D01*
X3356248Y2519190D01*
X3356648Y2518256D01*
X3356748Y2516923D01*
X3356648Y2515590D01*
X3356248Y2514656D01*
X3355748Y2513856D01*
X3355148Y2513323D01*
X3354348Y2512923D01*
X3352348D01*
G01X3368348D02*
Y2520923D01*
X3370348D01*
X3371148Y2520523D01*
X3371748Y2519990D01*
X3372248Y2519190D01*
X3372648Y2518256D01*
X3372748Y2516923D01*
X3372648Y2515590D01*
X3372248Y2514656D01*
X3371748Y2513856D01*
X3371148Y2513323D01*
X3370348Y2512923D01*
X3368348D01*
G01X3376048D02*
X3378548Y2520923D01*
X3381048Y2512923D01*
G01X3380148Y2515723D02*
X3376948D01*
G01X3386548Y2520923D02*
Y2512923D01*
G01X3384248Y2520923D02*
X3388848D01*
G01X3396548Y2512923D02*
X3392548D01*
Y2520923D01*
X3396548D01*
G01X3394948Y2517056D02*
X3392548D01*
G01X3412748Y2520256D02*
X3412148Y2520656D01*
X3411448Y2520923D01*
X3410648D01*
X3409748Y2520523D01*
X3409048Y2519856D01*
X3408548Y2519056D01*
X3408148Y2517723D01*
X3408048Y2516523D01*
X3408248Y2515323D01*
X3408548Y2514523D01*
X3409148Y2513723D01*
X3409848Y2513190D01*
X3410548Y2512923D01*
X3411248D01*
X3411948Y2513190D01*
X3412548Y2513590D01*
X3413048Y2514123D01*
G01X3418548Y2512923D02*
X3417748Y2513056D01*
X3417048Y2513590D01*
X3416448Y2514390D01*
X3416048Y2515323D01*
X3415848Y2516390D01*
Y2517456D01*
X3416048Y2518523D01*
X3416448Y2519456D01*
X3417048Y2520256D01*
X3417748Y2520790D01*
X3418548Y2520923D01*
X3419348Y2520790D01*
X3420048Y2520256D01*
X3420648Y2519456D01*
X3421048Y2518523D01*
X3421248Y2517456D01*
Y2516390D01*
X3421048Y2515323D01*
X3420648Y2514390D01*
X3420048Y2513590D01*
X3419348Y2513056D01*
X3418548Y2512923D01*
G01X3424348D02*
Y2520923D01*
X3426348D01*
X3427148Y2520523D01*
X3427748Y2519990D01*
X3428248Y2519190D01*
X3428648Y2518256D01*
X3428748Y2516923D01*
X3428648Y2515590D01*
X3428248Y2514656D01*
X3427748Y2513856D01*
X3427148Y2513323D01*
X3426348Y2512923D01*
X3424348D01*
G01X3436548D02*
X3432548D01*
Y2520923D01*
X3436548D01*
G01X3434948Y2517056D02*
X3432548D01*
G01X3450048Y2510256D02*
X3449048Y2511590D01*
X3448548Y2512923D01*
Y2518256D01*
X3449048Y2519590D01*
X3450048Y2520923D01*
G01X3455548D02*
X3456948Y2512923D01*
X3458548Y2520923D01*
X3460148Y2512923D01*
X3461548Y2520923D01*
G01X3463548D02*
X3464948Y2512923D01*
X3466548Y2520923D01*
X3468148Y2512923D01*
X3469548Y2520923D01*
G01X3474548Y2512923D02*
Y2516523D01*
X3472548Y2520923D01*
G01X3476548D02*
X3474548Y2516523D01*
G01X3482548Y2512923D02*
Y2516523D01*
X3480548Y2520923D01*
G01X3484548D02*
X3482548Y2516523D01*
G01X3491048Y2510256D02*
X3492048Y2511590D01*
X3492548Y2512923D01*
Y2518256D01*
X3492048Y2519590D01*
X3491048Y2520923D01*
G01X3506548Y2512923D02*
X3505948Y2513056D01*
X3505348Y2513590D01*
X3504948Y2514523D01*
X3504748Y2515590D01*
X3504948Y2516656D01*
X3505348Y2517590D01*
X3505948Y2518123D01*
X3506548Y2518256D01*
X3507148Y2518123D01*
X3507748Y2517590D01*
X3508148Y2516656D01*
X3508248Y2515590D01*
X3508148Y2514523D01*
X3507748Y2513590D01*
X3507148Y2513056D01*
X3506548Y2512923D01*
G01X3512848D02*
Y2518256D01*
G01Y2516923D02*
X3513248Y2517590D01*
X3513848Y2518123D01*
X3514648Y2518256D01*
X3515348Y2518123D01*
X3515948Y2517590D01*
X3516248Y2516656D01*
Y2512923D01*
G01X3528448Y2513989D02*
X3529248Y2513323D01*
X3530148Y2512923D01*
X3530948D01*
X3531748Y2513323D01*
X3532348Y2513989D01*
X3532648Y2514923D01*
X3532448Y2515856D01*
X3531948Y2516656D01*
X3531048Y2517190D01*
X3529848Y2517456D01*
X3529148Y2517990D01*
X3528848Y2518923D01*
X3529048Y2519856D01*
X3529548Y2520523D01*
X3530248Y2520923D01*
X3530948D01*
X3531648Y2520656D01*
X3532248Y2519990D01*
G01X3537348Y2520923D02*
X3539748D01*
G01X3538548D02*
Y2512923D01*
G01X3537348D02*
X3539748D01*
G01X3544548Y2520923D02*
Y2512923D01*
X3548548D01*
G01X3552348D02*
Y2520923D01*
G01X3556148D02*
X3552348Y2515989D01*
G01X3556748Y2512923D02*
X3554048Y2518256D01*
G01X3560448Y2513989D02*
X3561248Y2513323D01*
X3562148Y2512923D01*
X3562948D01*
X3563748Y2513323D01*
X3564348Y2513989D01*
X3564648Y2514923D01*
X3564448Y2515856D01*
X3563948Y2516656D01*
X3563048Y2517190D01*
X3561848Y2517456D01*
X3561148Y2517990D01*
X3560848Y2518923D01*
X3561048Y2519856D01*
X3561548Y2520523D01*
X3562248Y2520923D01*
X3562948D01*
X3563648Y2520656D01*
X3564248Y2519990D01*
G01X3572748Y2520256D02*
X3572148Y2520656D01*
X3571448Y2520923D01*
X3570648D01*
X3569748Y2520523D01*
X3569048Y2519856D01*
X3568548Y2519056D01*
X3568148Y2517723D01*
X3568048Y2516523D01*
X3568248Y2515323D01*
X3568548Y2514523D01*
X3569148Y2513723D01*
X3569848Y2513190D01*
X3570548Y2512923D01*
X3571248D01*
X3571948Y2513190D01*
X3572548Y2513590D01*
X3573048Y2514123D01*
G01X3576548Y2512923D02*
Y2520923D01*
X3579048D01*
X3579848Y2520523D01*
X3580348Y2519990D01*
X3580548Y2518923D01*
X3580348Y2517856D01*
X3579748Y2517190D01*
X3579048Y2516790D01*
X3576548D01*
G01X3579048D02*
X3580548Y2512923D01*
G01X3588548D02*
X3584548D01*
Y2520923D01*
X3588548D01*
G01X3586948Y2517056D02*
X3584548D01*
G01X3596548Y2512923D02*
X3592548D01*
Y2520923D01*
X3596548D01*
G01X3594948Y2517056D02*
X3592548D01*
G01X3600248Y2512923D02*
Y2520923D01*
X3604848Y2512923D01*
Y2520923D01*
G01X3618548D02*
Y2512923D01*
G01X3616248Y2520923D02*
X3620848D01*
G01X3626548Y2512923D02*
X3625748Y2513056D01*
X3625048Y2513590D01*
X3624448Y2514390D01*
X3624048Y2515323D01*
X3623848Y2516390D01*
Y2517456D01*
X3624048Y2518523D01*
X3624448Y2519456D01*
X3625048Y2520256D01*
X3625748Y2520790D01*
X3626548Y2520923D01*
X3627348Y2520790D01*
X3628048Y2520256D01*
X3628648Y2519456D01*
X3629048Y2518523D01*
X3629248Y2517456D01*
Y2516390D01*
X3629048Y2515323D01*
X3628648Y2514390D01*
X3628048Y2513590D01*
X3627348Y2513056D01*
X3626548Y2512923D01*
G01X3632548D02*
Y2520923D01*
X3634948D01*
X3635748Y2520523D01*
X3636348Y2519590D01*
X3636548Y2518523D01*
X3636348Y2517456D01*
X3635848Y2516656D01*
X3634948Y2516256D01*
X3632548D01*
G01X3648448Y2513989D02*
X3649248Y2513323D01*
X3650148Y2512923D01*
X3650948D01*
X3651748Y2513323D01*
X3652348Y2513989D01*
X3652648Y2514923D01*
X3652448Y2515856D01*
X3651948Y2516656D01*
X3651048Y2517190D01*
X3649848Y2517456D01*
X3649148Y2517990D01*
X3648848Y2518923D01*
X3649048Y2519856D01*
X3649548Y2520523D01*
X3650248Y2520923D01*
X3650948D01*
X3651648Y2520656D01*
X3652248Y2519990D01*
G01X3657348Y2520923D02*
X3659748D01*
G01X3658548D02*
Y2512923D01*
G01X3657348D02*
X3659748D01*
G01X3664348D02*
Y2520923D01*
X3666348D01*
X3667148Y2520523D01*
X3667748Y2519990D01*
X3668248Y2519190D01*
X3668648Y2518256D01*
X3668748Y2516923D01*
X3668648Y2515590D01*
X3668248Y2514656D01*
X3667748Y2513856D01*
X3667148Y2513323D01*
X3666348Y2512923D01*
X3664348D01*
G01X3676548D02*
X3672548D01*
Y2520923D01*
X3676548D01*
G01X3674948Y2517056D02*
X3672548D01*
G01X3693548Y2510256D02*
X3688548Y2518256D01*
Y2519590D01*
X3689548Y2520923D01*
X3690548D01*
X3691548Y2519590D01*
Y2518256D01*
X3690548Y2516923D01*
X3688548Y2515590D01*
X3687548Y2514256D01*
Y2511590D01*
X3688548Y2510256D01*
X3691548D01*
X3693548Y2512923D01*
G01X3707348Y2517190D02*
X3707748Y2517590D01*
X3708048Y2518256D01*
X3708248Y2519190D01*
X3708048Y2519990D01*
X3707648Y2520523D01*
X3706948Y2520923D01*
X3704248D01*
Y2512923D01*
X3707548D01*
X3708248Y2513456D01*
X3708648Y2514256D01*
X3708848Y2515190D01*
X3708648Y2516123D01*
X3708048Y2516923D01*
X3707348Y2517190D01*
X3704248D01*
G01X3712548Y2512923D02*
Y2520923D01*
X3715048D01*
X3715848Y2520523D01*
X3716348Y2519990D01*
X3716548Y2518923D01*
X3716348Y2517856D01*
X3715748Y2517190D01*
X3715048Y2516790D01*
X3712548D01*
G01X3715048D02*
X3716548Y2512923D01*
G01X3724548D02*
X3720548D01*
Y2520923D01*
X3724548D01*
G01X3722948Y2517056D02*
X3720548D01*
G01X3728048Y2512923D02*
X3730548Y2520923D01*
X3733048Y2512923D01*
G01X3732148Y2515723D02*
X3728948D01*
G01X3736348Y2512923D02*
Y2520923D01*
G01X3740148D02*
X3736348Y2515989D01*
G01X3740748Y2512923D02*
X3738048Y2518256D01*
G01X3744048Y2512923D02*
X3746548Y2520923D01*
X3749048Y2512923D01*
G01X3748148Y2515723D02*
X3744948D01*
G01X3751548Y2520923D02*
X3752948Y2512923D01*
X3754548Y2520923D01*
X3756148Y2512923D01*
X3757548Y2520923D01*
G01X3760048Y2512923D02*
X3762548Y2520923D01*
X3765048Y2512923D01*
G01X3764148Y2515723D02*
X3760948D01*
G01X3770548Y2512923D02*
Y2516523D01*
X3768548Y2520923D01*
G01X3772548D02*
X3770548Y2516523D01*
G01X3164548Y2527923D02*
X3160548D01*
Y2535923D01*
X3164548D01*
G01X3162948Y2532056D02*
X3160548D01*
G01X3170548Y2527656D02*
X3170348Y2527790D01*
Y2528056D01*
X3170548Y2528190D01*
X3170748Y2528056D01*
Y2527790D01*
X3170548Y2527656D01*
G01X3176548Y2527923D02*
Y2535923D01*
X3178948D01*
X3179748Y2535523D01*
X3180348Y2534590D01*
X3180548Y2533523D01*
X3180348Y2532456D01*
X3179848Y2531656D01*
X3178948Y2531256D01*
X3176548D01*
G01X3184548Y2527923D02*
Y2535923D01*
X3187048D01*
X3187848Y2535523D01*
X3188348Y2534990D01*
X3188548Y2533923D01*
X3188348Y2532856D01*
X3187748Y2532190D01*
X3187048Y2531790D01*
X3184548D01*
G01X3187048D02*
X3188548Y2527923D01*
G01X3194548D02*
X3193748Y2528056D01*
X3193048Y2528590D01*
X3192448Y2529390D01*
X3192048Y2530323D01*
X3191848Y2531390D01*
Y2532456D01*
X3192048Y2533523D01*
X3192448Y2534456D01*
X3193048Y2535256D01*
X3193748Y2535790D01*
X3194548Y2535923D01*
X3195348Y2535790D01*
X3196048Y2535256D01*
X3196648Y2534456D01*
X3197048Y2533523D01*
X3197248Y2532456D01*
Y2531390D01*
X3197048Y2530323D01*
X3196648Y2529390D01*
X3196048Y2528590D01*
X3195348Y2528056D01*
X3194548Y2527923D01*
G01X3200048Y2535923D02*
X3202548Y2527923D01*
X3205048Y2535923D01*
G01X3209348D02*
X3211748D01*
G01X3210548D02*
Y2527923D01*
G01X3209348D02*
X3211748D01*
G01X3216348D02*
Y2535923D01*
X3218348D01*
X3219148Y2535523D01*
X3219748Y2534990D01*
X3220248Y2534190D01*
X3220648Y2533256D01*
X3220748Y2531923D01*
X3220648Y2530590D01*
X3220248Y2529656D01*
X3219748Y2528856D01*
X3219148Y2528323D01*
X3218348Y2527923D01*
X3216348D01*
G01X3228548D02*
X3224548D01*
Y2535923D01*
X3228548D01*
G01X3226948Y2532056D02*
X3224548D01*
G01X3240548Y2527923D02*
Y2535923D01*
X3242948D01*
X3243748Y2535523D01*
X3244348Y2534590D01*
X3244548Y2533523D01*
X3244348Y2532456D01*
X3243848Y2531656D01*
X3242948Y2531256D01*
X3240548D01*
G01X3252748Y2535256D02*
X3252148Y2535656D01*
X3251448Y2535923D01*
X3250648D01*
X3249748Y2535523D01*
X3249048Y2534856D01*
X3248548Y2534056D01*
X3248148Y2532723D01*
X3248048Y2531523D01*
X3248248Y2530323D01*
X3248548Y2529523D01*
X3249148Y2528723D01*
X3249848Y2528190D01*
X3250548Y2527923D01*
X3251248D01*
X3251948Y2528190D01*
X3252548Y2528590D01*
X3253048Y2529123D01*
G01X3259348Y2532190D02*
X3259748Y2532590D01*
X3260048Y2533256D01*
X3260248Y2534190D01*
X3260048Y2534990D01*
X3259648Y2535523D01*
X3258948Y2535923D01*
X3256248D01*
Y2527923D01*
X3259548D01*
X3260248Y2528456D01*
X3260648Y2529256D01*
X3260848Y2530190D01*
X3260648Y2531123D01*
X3260048Y2531923D01*
X3259348Y2532190D01*
X3256248D01*
G01X3272648Y2527923D02*
Y2535923D01*
X3276448D01*
G01X3275048Y2532056D02*
X3272648D01*
G01X3281348Y2535923D02*
X3283748D01*
G01X3282548D02*
Y2527923D01*
G01X3281348D02*
X3283748D01*
G01X3288548Y2535923D02*
Y2527923D01*
X3292548D01*
G01X3295948D02*
Y2535923D01*
X3298548Y2529256D01*
X3301148Y2535923D01*
Y2527923D01*
G01X3160348Y2542923D02*
Y2550923D01*
X3162348D01*
X3163148Y2550523D01*
X3163748Y2549990D01*
X3164248Y2549190D01*
X3164648Y2548256D01*
X3164748Y2546923D01*
X3164648Y2545590D01*
X3164248Y2544656D01*
X3163748Y2543856D01*
X3163148Y2543323D01*
X3162348Y2542923D01*
X3160348D01*
G01X3170548Y2542656D02*
X3170348Y2542790D01*
Y2543056D01*
X3170548Y2543190D01*
X3170748Y2543056D01*
Y2542790D01*
X3170548Y2542656D01*
G01X3176548Y2542923D02*
Y2550923D01*
X3178948D01*
X3179748Y2550523D01*
X3180348Y2549590D01*
X3180548Y2548523D01*
X3180348Y2547456D01*
X3179848Y2546656D01*
X3178948Y2546256D01*
X3176548D01*
G01X3184548Y2542923D02*
Y2550923D01*
X3187048D01*
X3187848Y2550523D01*
X3188348Y2549990D01*
X3188548Y2548923D01*
X3188348Y2547856D01*
X3187748Y2547190D01*
X3187048Y2546790D01*
X3184548D01*
G01X3187048D02*
X3188548Y2542923D01*
G01X3194548D02*
X3193748Y2543056D01*
X3193048Y2543590D01*
X3192448Y2544390D01*
X3192048Y2545323D01*
X3191848Y2546390D01*
Y2547456D01*
X3192048Y2548523D01*
X3192448Y2549456D01*
X3193048Y2550256D01*
X3193748Y2550790D01*
X3194548Y2550923D01*
X3195348Y2550790D01*
X3196048Y2550256D01*
X3196648Y2549456D01*
X3197048Y2548523D01*
X3197248Y2547456D01*
Y2546390D01*
X3197048Y2545323D01*
X3196648Y2544390D01*
X3196048Y2543590D01*
X3195348Y2543056D01*
X3194548Y2542923D01*
G01X3200048Y2550923D02*
X3202548Y2542923D01*
X3205048Y2550923D01*
G01X3209348D02*
X3211748D01*
G01X3210548D02*
Y2542923D01*
G01X3209348D02*
X3211748D01*
G01X3216348D02*
Y2550923D01*
X3218348D01*
X3219148Y2550523D01*
X3219748Y2549990D01*
X3220248Y2549190D01*
X3220648Y2548256D01*
X3220748Y2546923D01*
X3220648Y2545590D01*
X3220248Y2544656D01*
X3219748Y2543856D01*
X3219148Y2543323D01*
X3218348Y2542923D01*
X3216348D01*
G01X3228548D02*
X3224548D01*
Y2550923D01*
X3228548D01*
G01X3226948Y2547056D02*
X3224548D01*
G01X3241348Y2550923D02*
X3243748D01*
G01X3242548D02*
Y2542923D01*
G01X3241348D02*
X3243748D01*
G01X3247948D02*
Y2550923D01*
X3250548Y2544256D01*
X3253148Y2550923D01*
Y2542923D01*
G01X3256548D02*
Y2550923D01*
X3258948D01*
X3259748Y2550523D01*
X3260348Y2549590D01*
X3260548Y2548523D01*
X3260348Y2547456D01*
X3259848Y2546656D01*
X3258948Y2546256D01*
X3256548D01*
G01X3268548Y2542923D02*
X3264548D01*
Y2550923D01*
X3268548D01*
G01X3266948Y2547056D02*
X3264548D01*
G01X3272348Y2542923D02*
Y2550923D01*
X3274348D01*
X3275148Y2550523D01*
X3275748Y2549990D01*
X3276248Y2549190D01*
X3276648Y2548256D01*
X3276748Y2546923D01*
X3276648Y2545590D01*
X3276248Y2544656D01*
X3275748Y2543856D01*
X3275148Y2543323D01*
X3274348Y2542923D01*
X3272348D01*
G01X3280048D02*
X3282548Y2550923D01*
X3285048Y2542923D01*
G01X3284148Y2545723D02*
X3280948D01*
G01X3288248Y2542923D02*
Y2550923D01*
X3292848Y2542923D01*
Y2550923D01*
G01X3300748Y2550256D02*
X3300148Y2550656D01*
X3299448Y2550923D01*
X3298648D01*
X3297748Y2550523D01*
X3297048Y2549856D01*
X3296548Y2549056D01*
X3296148Y2547723D01*
X3296048Y2546523D01*
X3296248Y2545323D01*
X3296548Y2544523D01*
X3297148Y2543723D01*
X3297848Y2543190D01*
X3298548Y2542923D01*
X3299248D01*
X3299948Y2543190D01*
X3300548Y2543590D01*
X3301048Y2544123D01*
G01X3308548Y2542923D02*
X3304548D01*
Y2550923D01*
X3308548D01*
G01X3306948Y2547056D02*
X3304548D01*
G01X3324748Y2550256D02*
X3324148Y2550656D01*
X3323448Y2550923D01*
X3322648D01*
X3321748Y2550523D01*
X3321048Y2549856D01*
X3320548Y2549056D01*
X3320148Y2547723D01*
X3320048Y2546523D01*
X3320248Y2545323D01*
X3320548Y2544523D01*
X3321148Y2543723D01*
X3321848Y2543190D01*
X3322548Y2542923D01*
X3323248D01*
X3323948Y2543190D01*
X3324548Y2543590D01*
X3325048Y2544123D01*
G01X3330548Y2542923D02*
X3329748Y2543056D01*
X3329048Y2543590D01*
X3328448Y2544390D01*
X3328048Y2545323D01*
X3327848Y2546390D01*
Y2547456D01*
X3328048Y2548523D01*
X3328448Y2549456D01*
X3329048Y2550256D01*
X3329748Y2550790D01*
X3330548Y2550923D01*
X3331348Y2550790D01*
X3332048Y2550256D01*
X3332648Y2549456D01*
X3333048Y2548523D01*
X3333248Y2547456D01*
Y2546390D01*
X3333048Y2545323D01*
X3332648Y2544390D01*
X3332048Y2543590D01*
X3331348Y2543056D01*
X3330548Y2542923D01*
G01X3336348Y2550923D02*
Y2545190D01*
X3336748Y2543989D01*
X3337548Y2543190D01*
X3338548Y2542923D01*
X3339548Y2543190D01*
X3340348Y2543989D01*
X3340748Y2545190D01*
Y2550923D01*
G01X3344548Y2542923D02*
Y2550923D01*
X3346948D01*
X3347748Y2550523D01*
X3348348Y2549590D01*
X3348548Y2548523D01*
X3348348Y2547456D01*
X3347848Y2546656D01*
X3346948Y2546256D01*
X3344548D01*
G01X3354548Y2542923D02*
X3353748Y2543056D01*
X3353048Y2543590D01*
X3352448Y2544390D01*
X3352048Y2545323D01*
X3351848Y2546390D01*
Y2547456D01*
X3352048Y2548523D01*
X3352448Y2549456D01*
X3353048Y2550256D01*
X3353748Y2550790D01*
X3354548Y2550923D01*
X3355348Y2550790D01*
X3356048Y2550256D01*
X3356648Y2549456D01*
X3357048Y2548523D01*
X3357248Y2547456D01*
Y2546390D01*
X3357048Y2545323D01*
X3356648Y2544390D01*
X3356048Y2543590D01*
X3355348Y2543056D01*
X3354548Y2542923D01*
G01X3360248D02*
Y2550923D01*
X3364848Y2542923D01*
Y2550923D01*
G01X3376048Y2542923D02*
X3378548Y2550923D01*
X3381048Y2542923D01*
G01X3380148Y2545723D02*
X3376948D01*
G01X3384248Y2542923D02*
Y2550923D01*
X3388848Y2542923D01*
Y2550923D01*
G01X3392348Y2542923D02*
Y2550923D01*
X3394348D01*
X3395148Y2550523D01*
X3395748Y2549990D01*
X3396248Y2549190D01*
X3396648Y2548256D01*
X3396748Y2546923D01*
X3396648Y2545590D01*
X3396248Y2544656D01*
X3395748Y2543856D01*
X3395148Y2543323D01*
X3394348Y2542923D01*
X3392348D01*
G01X3407948D02*
Y2550923D01*
X3410548Y2544256D01*
X3413148Y2550923D01*
Y2542923D01*
G01X3420548D02*
X3416548D01*
Y2550923D01*
X3420548D01*
G01X3418948Y2547056D02*
X3416548D01*
G01X3424048Y2542923D02*
X3426548Y2550923D01*
X3429048Y2542923D01*
G01X3428148Y2545723D02*
X3424948D01*
G01X3432448Y2543989D02*
X3433248Y2543323D01*
X3434148Y2542923D01*
X3434948D01*
X3435748Y2543323D01*
X3436348Y2543989D01*
X3436648Y2544923D01*
X3436448Y2545856D01*
X3435948Y2546656D01*
X3435048Y2547190D01*
X3433848Y2547456D01*
X3433148Y2547990D01*
X3432848Y2548923D01*
X3433048Y2549856D01*
X3433548Y2550523D01*
X3434248Y2550923D01*
X3434948D01*
X3435648Y2550656D01*
X3436248Y2549990D01*
G01X3440348Y2550923D02*
Y2545190D01*
X3440748Y2543989D01*
X3441548Y2543190D01*
X3442548Y2542923D01*
X3443548Y2543190D01*
X3444348Y2543989D01*
X3444748Y2545190D01*
Y2550923D01*
G01X3448548Y2542923D02*
Y2550923D01*
X3451048D01*
X3451848Y2550523D01*
X3452348Y2549990D01*
X3452548Y2548923D01*
X3452348Y2547856D01*
X3451748Y2547190D01*
X3451048Y2546790D01*
X3448548D01*
G01X3451048D02*
X3452548Y2542923D01*
G01X3460548D02*
X3456548D01*
Y2550923D01*
X3460548D01*
G01X3458948Y2547056D02*
X3456548D01*
G01X3463948Y2542923D02*
Y2550923D01*
X3466548Y2544256D01*
X3469148Y2550923D01*
Y2542923D01*
G01X3476548D02*
X3472548D01*
Y2550923D01*
X3476548D01*
G01X3474948Y2547056D02*
X3472548D01*
G01X3480248Y2542923D02*
Y2550923D01*
X3484848Y2542923D01*
Y2550923D01*
G01X3490548D02*
Y2542923D01*
G01X3488248Y2550923D02*
X3492848D01*
G01X3504548Y2542923D02*
Y2550923D01*
X3507048D01*
X3507848Y2550523D01*
X3508348Y2549990D01*
X3508548Y2548923D01*
X3508348Y2547856D01*
X3507748Y2547190D01*
X3507048Y2546790D01*
X3504548D01*
G01X3507048D02*
X3508548Y2542923D01*
G01X3516548D02*
X3512548D01*
Y2550923D01*
X3516548D01*
G01X3514948Y2547056D02*
X3512548D01*
G01X3520548Y2542923D02*
Y2550923D01*
X3522948D01*
X3523748Y2550523D01*
X3524348Y2549590D01*
X3524548Y2548523D01*
X3524348Y2547456D01*
X3523848Y2546656D01*
X3522948Y2546256D01*
X3520548D01*
G01X3530548Y2542923D02*
X3529748Y2543056D01*
X3529048Y2543590D01*
X3528448Y2544390D01*
X3528048Y2545323D01*
X3527848Y2546390D01*
Y2547456D01*
X3528048Y2548523D01*
X3528448Y2549456D01*
X3529048Y2550256D01*
X3529748Y2550790D01*
X3530548Y2550923D01*
X3531348Y2550790D01*
X3532048Y2550256D01*
X3532648Y2549456D01*
X3533048Y2548523D01*
X3533248Y2547456D01*
Y2546390D01*
X3533048Y2545323D01*
X3532648Y2544390D01*
X3532048Y2543590D01*
X3531348Y2543056D01*
X3530548Y2542923D01*
G01X3536548D02*
Y2550923D01*
X3539048D01*
X3539848Y2550523D01*
X3540348Y2549990D01*
X3540548Y2548923D01*
X3540348Y2547856D01*
X3539748Y2547190D01*
X3539048Y2546790D01*
X3536548D01*
G01X3539048D02*
X3540548Y2542923D01*
G01X3546548Y2550923D02*
Y2542923D01*
G01X3544248Y2550923D02*
X3548848D01*
G01X3164748Y2565256D02*
X3164148Y2565656D01*
X3163448Y2565923D01*
X3162648D01*
X3161748Y2565523D01*
X3161048Y2564856D01*
X3160548Y2564056D01*
X3160148Y2562723D01*
X3160048Y2561523D01*
X3160248Y2560323D01*
X3160548Y2559523D01*
X3161148Y2558723D01*
X3161848Y2558190D01*
X3162548Y2557923D01*
X3163248D01*
X3163948Y2558190D01*
X3164548Y2558590D01*
X3165048Y2559123D01*
G01X3170548Y2557656D02*
X3170348Y2557790D01*
Y2558056D01*
X3170548Y2558190D01*
X3170748Y2558056D01*
Y2557790D01*
X3170548Y2557656D01*
G01X3176248Y2557923D02*
Y2565923D01*
X3180848Y2557923D01*
Y2565923D01*
G01X3186548Y2557923D02*
X3185748Y2558056D01*
X3185048Y2558590D01*
X3184448Y2559390D01*
X3184048Y2560323D01*
X3183848Y2561390D01*
Y2562456D01*
X3184048Y2563523D01*
X3184448Y2564456D01*
X3185048Y2565256D01*
X3185748Y2565790D01*
X3186548Y2565923D01*
X3187348Y2565790D01*
X3188048Y2565256D01*
X3188648Y2564456D01*
X3189048Y2563523D01*
X3189248Y2562456D01*
Y2561390D01*
X3189048Y2560323D01*
X3188648Y2559390D01*
X3188048Y2558590D01*
X3187348Y2558056D01*
X3186548Y2557923D01*
G01X3200248D02*
Y2565923D01*
X3204848Y2557923D01*
Y2565923D01*
G01X3212548Y2557923D02*
X3208548D01*
Y2565923D01*
X3212548D01*
G01X3210948Y2562056D02*
X3208548D01*
G01X3220548Y2557923D02*
X3216548D01*
Y2565923D01*
X3220548D01*
G01X3218948Y2562056D02*
X3216548D01*
G01X3224348Y2557923D02*
Y2565923D01*
X3226348D01*
X3227148Y2565523D01*
X3227748Y2564990D01*
X3228248Y2564190D01*
X3228648Y2563256D01*
X3228748Y2561923D01*
X3228648Y2560590D01*
X3228248Y2559656D01*
X3227748Y2558856D01*
X3227148Y2558323D01*
X3226348Y2557923D01*
X3224348D01*
G01X3242548Y2565923D02*
Y2557923D01*
G01X3240248Y2565923D02*
X3244848D01*
G01X3250548Y2557923D02*
X3249748Y2558056D01*
X3249048Y2558590D01*
X3248448Y2559390D01*
X3248048Y2560323D01*
X3247848Y2561390D01*
Y2562456D01*
X3248048Y2563523D01*
X3248448Y2564456D01*
X3249048Y2565256D01*
X3249748Y2565790D01*
X3250548Y2565923D01*
X3251348Y2565790D01*
X3252048Y2565256D01*
X3252648Y2564456D01*
X3253048Y2563523D01*
X3253248Y2562456D01*
Y2561390D01*
X3253048Y2560323D01*
X3252648Y2559390D01*
X3252048Y2558590D01*
X3251348Y2558056D01*
X3250548Y2557923D01*
G01X3264548D02*
Y2565923D01*
X3266948D01*
X3267748Y2565523D01*
X3268348Y2564590D01*
X3268548Y2563523D01*
X3268348Y2562456D01*
X3267848Y2561656D01*
X3266948Y2561256D01*
X3264548D01*
G01X3272548Y2565923D02*
Y2557923D01*
X3276548D01*
G01X3280348Y2565923D02*
Y2560190D01*
X3280748Y2558989D01*
X3281548Y2558190D01*
X3282548Y2557923D01*
X3283548Y2558190D01*
X3284348Y2558989D01*
X3284748Y2560190D01*
Y2565923D01*
G01X3291148Y2561923D02*
X3293148D01*
Y2559523D01*
X3292548Y2558723D01*
X3291848Y2558190D01*
X3290848Y2557923D01*
X3289848Y2558190D01*
X3289148Y2558723D01*
X3288548Y2559523D01*
X3288148Y2560456D01*
X3287948Y2561523D01*
Y2562456D01*
X3288148Y2563256D01*
X3288548Y2564190D01*
X3289148Y2564990D01*
X3289748Y2565523D01*
X3290548Y2565923D01*
X3291248D01*
X3292048Y2565656D01*
X3292648Y2565123D01*
G01X3306548Y2557923D02*
X3307248Y2558056D01*
X3308048Y2558456D01*
X3308548Y2559123D01*
X3308748Y2560056D01*
X3308548Y2560989D01*
X3307948Y2561790D01*
X3307048Y2562190D01*
X3306048D01*
X3305448Y2562456D01*
X3304948Y2563123D01*
X3304748Y2564056D01*
X3305048Y2564990D01*
X3305748Y2565656D01*
X3306548Y2565923D01*
X3307348Y2565656D01*
X3308048Y2564990D01*
X3308348Y2564056D01*
X3308148Y2563123D01*
X3307648Y2562456D01*
X3307048Y2562190D01*
X3306048D01*
X3305148Y2561790D01*
X3304548Y2560989D01*
X3304348Y2560056D01*
X3304548Y2559123D01*
X3305048Y2558456D01*
X3305848Y2558056D01*
X3306548Y2557923D01*
G01X3320448D02*
Y2565923D01*
G01X3324648D02*
Y2557923D01*
G01Y2561923D02*
X3320448D01*
G01X3330548Y2557923D02*
X3329748Y2558056D01*
X3329048Y2558590D01*
X3328448Y2559390D01*
X3328048Y2560323D01*
X3327848Y2561390D01*
Y2562456D01*
X3328048Y2563523D01*
X3328448Y2564456D01*
X3329048Y2565256D01*
X3329748Y2565790D01*
X3330548Y2565923D01*
X3331348Y2565790D01*
X3332048Y2565256D01*
X3332648Y2564456D01*
X3333048Y2563523D01*
X3333248Y2562456D01*
Y2561390D01*
X3333048Y2560323D01*
X3332648Y2559390D01*
X3332048Y2558590D01*
X3331348Y2558056D01*
X3330548Y2557923D01*
G01X3336548Y2565923D02*
Y2557923D01*
X3340548D01*
G01X3348548D02*
X3344548D01*
Y2565923D01*
X3348548D01*
G01X3346948Y2562056D02*
X3344548D01*
G01X3352448Y2558989D02*
X3353248Y2558323D01*
X3354148Y2557923D01*
X3354948D01*
X3355748Y2558323D01*
X3356348Y2558989D01*
X3356648Y2559923D01*
X3356448Y2560856D01*
X3355948Y2561656D01*
X3355048Y2562190D01*
X3353848Y2562456D01*
X3353148Y2562990D01*
X3352848Y2563923D01*
X3353048Y2564856D01*
X3353548Y2565523D01*
X3354248Y2565923D01*
X3354948D01*
X3355648Y2565656D01*
X3356248Y2564990D01*
G01X3368448Y2558989D02*
X3369248Y2558323D01*
X3370148Y2557923D01*
X3370948D01*
X3371748Y2558323D01*
X3372348Y2558989D01*
X3372648Y2559923D01*
X3372448Y2560856D01*
X3371948Y2561656D01*
X3371048Y2562190D01*
X3369848Y2562456D01*
X3369148Y2562990D01*
X3368848Y2563923D01*
X3369048Y2564856D01*
X3369548Y2565523D01*
X3370248Y2565923D01*
X3370948D01*
X3371648Y2565656D01*
X3372248Y2564990D01*
G01X3376348Y2565923D02*
Y2560190D01*
X3376748Y2558989D01*
X3377548Y2558190D01*
X3378548Y2557923D01*
X3379548Y2558190D01*
X3380348Y2558989D01*
X3380748Y2560190D01*
Y2565923D01*
G01X3384548Y2557923D02*
Y2565923D01*
X3387048D01*
X3387848Y2565523D01*
X3388348Y2564990D01*
X3388548Y2563923D01*
X3388348Y2562856D01*
X3387748Y2562190D01*
X3387048Y2561790D01*
X3384548D01*
G01X3387048D02*
X3388548Y2557923D01*
G01X3392548D02*
Y2565923D01*
X3395048D01*
X3395848Y2565523D01*
X3396348Y2564990D01*
X3396548Y2563923D01*
X3396348Y2562856D01*
X3395748Y2562190D01*
X3395048Y2561790D01*
X3392548D01*
G01X3395048D02*
X3396548Y2557923D01*
G01X3402548D02*
X3401748Y2558056D01*
X3401048Y2558590D01*
X3400448Y2559390D01*
X3400048Y2560323D01*
X3399848Y2561390D01*
Y2562456D01*
X3400048Y2563523D01*
X3400448Y2564456D01*
X3401048Y2565256D01*
X3401748Y2565790D01*
X3402548Y2565923D01*
X3403348Y2565790D01*
X3404048Y2565256D01*
X3404648Y2564456D01*
X3405048Y2563523D01*
X3405248Y2562456D01*
Y2561390D01*
X3405048Y2560323D01*
X3404648Y2559390D01*
X3404048Y2558590D01*
X3403348Y2558056D01*
X3402548Y2557923D01*
G01X3408348Y2565923D02*
Y2560190D01*
X3408748Y2558989D01*
X3409548Y2558190D01*
X3410548Y2557923D01*
X3411548Y2558190D01*
X3412348Y2558989D01*
X3412748Y2560190D01*
Y2565923D01*
G01X3416248Y2557923D02*
Y2565923D01*
X3420848Y2557923D01*
Y2565923D01*
G01X3424348Y2557923D02*
Y2565923D01*
X3426348D01*
X3427148Y2565523D01*
X3427748Y2564990D01*
X3428248Y2564190D01*
X3428648Y2563256D01*
X3428748Y2561923D01*
X3428648Y2560590D01*
X3428248Y2559656D01*
X3427748Y2558856D01*
X3427148Y2558323D01*
X3426348Y2557923D01*
X3424348D01*
G01X3433348Y2565923D02*
X3435748D01*
G01X3434548D02*
Y2557923D01*
G01X3433348D02*
X3435748D01*
G01X3440248D02*
Y2565923D01*
X3444848Y2557923D01*
Y2565923D01*
G01X3451148Y2561923D02*
X3453148D01*
Y2559523D01*
X3452548Y2558723D01*
X3451848Y2558190D01*
X3450848Y2557923D01*
X3449848Y2558190D01*
X3449148Y2558723D01*
X3448548Y2559523D01*
X3448148Y2560456D01*
X3447948Y2561523D01*
Y2562456D01*
X3448148Y2563256D01*
X3448548Y2564190D01*
X3449148Y2564990D01*
X3449748Y2565523D01*
X3450548Y2565923D01*
X3451248D01*
X3452048Y2565656D01*
X3452648Y2565123D01*
G01X3464448Y2558989D02*
X3465248Y2558323D01*
X3466148Y2557923D01*
X3466948D01*
X3467748Y2558323D01*
X3468348Y2558989D01*
X3468648Y2559923D01*
X3468448Y2560856D01*
X3467948Y2561656D01*
X3467048Y2562190D01*
X3465848Y2562456D01*
X3465148Y2562990D01*
X3464848Y2563923D01*
X3465048Y2564856D01*
X3465548Y2565523D01*
X3466248Y2565923D01*
X3466948D01*
X3467648Y2565656D01*
X3468248Y2564990D01*
G01X3476748Y2565256D02*
X3476148Y2565656D01*
X3475448Y2565923D01*
X3474648D01*
X3473748Y2565523D01*
X3473048Y2564856D01*
X3472548Y2564056D01*
X3472148Y2562723D01*
X3472048Y2561523D01*
X3472248Y2560323D01*
X3472548Y2559523D01*
X3473148Y2558723D01*
X3473848Y2558190D01*
X3474548Y2557923D01*
X3475248D01*
X3475948Y2558190D01*
X3476548Y2558590D01*
X3477048Y2559123D01*
G01X3480548Y2557923D02*
Y2565923D01*
X3483048D01*
X3483848Y2565523D01*
X3484348Y2564990D01*
X3484548Y2563923D01*
X3484348Y2562856D01*
X3483748Y2562190D01*
X3483048Y2561790D01*
X3480548D01*
G01X3483048D02*
X3484548Y2557923D01*
G01X3492548D02*
X3488548D01*
Y2565923D01*
X3492548D01*
G01X3490948Y2562056D02*
X3488548D01*
G01X3495548Y2565923D02*
X3496948Y2557923D01*
X3498548Y2565923D01*
X3500148Y2557923D01*
X3501548Y2565923D01*
G01X3506548Y2557656D02*
X3506348Y2557790D01*
Y2558056D01*
X3506548Y2558190D01*
X3506748Y2558056D01*
Y2557790D01*
X3506548Y2557656D01*
G01X3514048Y2555256D02*
X3513048Y2556590D01*
X3512548Y2557923D01*
Y2563256D01*
X3513048Y2564590D01*
X3514048Y2565923D01*
G01X3520548Y2557923D02*
Y2565923D01*
X3522948D01*
X3523748Y2565523D01*
X3524348Y2564590D01*
X3524548Y2563523D01*
X3524348Y2562456D01*
X3523848Y2561656D01*
X3522948Y2561256D01*
X3520548D01*
G01X3528548Y2565923D02*
Y2557923D01*
X3532548D01*
G01X3540548D02*
X3536548D01*
Y2565923D01*
X3540548D01*
G01X3538948Y2562056D02*
X3536548D01*
G01X3544048Y2557923D02*
X3546548Y2565923D01*
X3549048Y2557923D01*
G01X3548148Y2560723D02*
X3544948D01*
G01X3552448Y2558989D02*
X3553248Y2558323D01*
X3554148Y2557923D01*
X3554948D01*
X3555748Y2558323D01*
X3556348Y2558989D01*
X3556648Y2559923D01*
X3556448Y2560856D01*
X3555948Y2561656D01*
X3555048Y2562190D01*
X3553848Y2562456D01*
X3553148Y2562990D01*
X3552848Y2563923D01*
X3553048Y2564856D01*
X3553548Y2565523D01*
X3554248Y2565923D01*
X3554948D01*
X3555648Y2565656D01*
X3556248Y2564990D01*
G01X3564548Y2557923D02*
X3560548D01*
Y2565923D01*
X3564548D01*
G01X3562948Y2562056D02*
X3560548D01*
G01X3577348Y2565923D02*
X3579748D01*
G01X3578548D02*
Y2557923D01*
G01X3577348D02*
X3579748D01*
G01X3587148Y2561923D02*
X3589148D01*
Y2559523D01*
X3588548Y2558723D01*
X3587848Y2558190D01*
X3586848Y2557923D01*
X3585848Y2558190D01*
X3585148Y2558723D01*
X3584548Y2559523D01*
X3584148Y2560456D01*
X3583948Y2561523D01*
Y2562456D01*
X3584148Y2563256D01*
X3584548Y2564190D01*
X3585148Y2564990D01*
X3585748Y2565523D01*
X3586548Y2565923D01*
X3587248D01*
X3588048Y2565656D01*
X3588648Y2565123D01*
G01X3592248Y2557923D02*
Y2565923D01*
X3596848Y2557923D01*
Y2565923D01*
G01X3602548Y2557923D02*
X3601748Y2558056D01*
X3601048Y2558590D01*
X3600448Y2559390D01*
X3600048Y2560323D01*
X3599848Y2561390D01*
Y2562456D01*
X3600048Y2563523D01*
X3600448Y2564456D01*
X3601048Y2565256D01*
X3601748Y2565790D01*
X3602548Y2565923D01*
X3603348Y2565790D01*
X3604048Y2565256D01*
X3604648Y2564456D01*
X3605048Y2563523D01*
X3605248Y2562456D01*
Y2561390D01*
X3605048Y2560323D01*
X3604648Y2559390D01*
X3604048Y2558590D01*
X3603348Y2558056D01*
X3602548Y2557923D01*
G01X3608548D02*
Y2565923D01*
X3611048D01*
X3611848Y2565523D01*
X3612348Y2564990D01*
X3612548Y2563923D01*
X3612348Y2562856D01*
X3611748Y2562190D01*
X3611048Y2561790D01*
X3608548D01*
G01X3611048D02*
X3612548Y2557923D01*
G01X3620548D02*
X3616548D01*
Y2565923D01*
X3620548D01*
G01X3618948Y2562056D02*
X3616548D01*
G01X3634548Y2565923D02*
Y2557923D01*
G01X3632248Y2565923D02*
X3636848D01*
G01X3640448Y2557923D02*
Y2565923D01*
G01X3644648D02*
Y2557923D01*
G01Y2561923D02*
X3640448D01*
G01X3649348Y2565923D02*
X3651748D01*
G01X3650548D02*
Y2557923D01*
G01X3649348D02*
X3651748D01*
G01X3656448Y2558989D02*
X3657248Y2558323D01*
X3658148Y2557923D01*
X3658948D01*
X3659748Y2558323D01*
X3660348Y2558989D01*
X3660648Y2559923D01*
X3660448Y2560856D01*
X3659948Y2561656D01*
X3659048Y2562190D01*
X3657848Y2562456D01*
X3657148Y2562990D01*
X3656848Y2563923D01*
X3657048Y2564856D01*
X3657548Y2565523D01*
X3658248Y2565923D01*
X3658948D01*
X3659648Y2565656D01*
X3660248Y2564990D01*
G01X3673348Y2565923D02*
X3675748D01*
G01X3674548D02*
Y2557923D01*
G01X3673348D02*
X3675748D01*
G01X3680648D02*
Y2565923D01*
X3684448D01*
G01X3683048Y2562056D02*
X3680648D01*
G01X3696248Y2557923D02*
Y2565923D01*
X3700848Y2557923D01*
Y2565923D01*
G01X3706548Y2557923D02*
X3705748Y2558056D01*
X3705048Y2558590D01*
X3704448Y2559390D01*
X3704048Y2560323D01*
X3703848Y2561390D01*
Y2562456D01*
X3704048Y2563523D01*
X3704448Y2564456D01*
X3705048Y2565256D01*
X3705748Y2565790D01*
X3706548Y2565923D01*
X3707348Y2565790D01*
X3708048Y2565256D01*
X3708648Y2564456D01*
X3709048Y2563523D01*
X3709248Y2562456D01*
Y2561390D01*
X3709048Y2560323D01*
X3708648Y2559390D01*
X3708048Y2558590D01*
X3707348Y2558056D01*
X3706548Y2557923D01*
G01X3722548Y2565923D02*
Y2557923D01*
G01X3720248Y2565923D02*
X3724848D01*
G01X3728448Y2557923D02*
Y2565923D01*
G01X3732648D02*
Y2557923D01*
G01Y2561923D02*
X3728448D01*
G01X3737348Y2565923D02*
X3739748D01*
G01X3738548D02*
Y2557923D01*
G01X3737348D02*
X3739748D01*
G01X3744448Y2558989D02*
X3745248Y2558323D01*
X3746148Y2557923D01*
X3746948D01*
X3747748Y2558323D01*
X3748348Y2558989D01*
X3748648Y2559923D01*
X3748448Y2560856D01*
X3747948Y2561656D01*
X3747048Y2562190D01*
X3745848Y2562456D01*
X3745148Y2562990D01*
X3744848Y2563923D01*
X3745048Y2564856D01*
X3745548Y2565523D01*
X3746248Y2565923D01*
X3746948D01*
X3747648Y2565656D01*
X3748248Y2564990D01*
G01X3761348Y2565923D02*
X3763748D01*
G01X3762548D02*
Y2557923D01*
G01X3761348D02*
X3763748D01*
G01X3770548Y2565923D02*
Y2557923D01*
G01X3768248Y2565923D02*
X3772848D01*
G01X3780548Y2557923D02*
X3776548D01*
Y2565923D01*
X3780548D01*
G01X3778948Y2562056D02*
X3776548D01*
G01X3783948Y2557923D02*
Y2565923D01*
X3786548Y2559256D01*
X3789148Y2565923D01*
Y2557923D01*
G01X3801348Y2565923D02*
X3803748D01*
G01X3802548D02*
Y2557923D01*
G01X3801348D02*
X3803748D01*
G01X3808248D02*
Y2565923D01*
X3812848Y2557923D01*
Y2565923D01*
G01X3827348Y2562190D02*
X3827748Y2562590D01*
X3828048Y2563256D01*
X3828248Y2564190D01*
X3828048Y2564990D01*
X3827648Y2565523D01*
X3826948Y2565923D01*
X3824248D01*
Y2557923D01*
X3827548D01*
X3828248Y2558456D01*
X3828648Y2559256D01*
X3828848Y2560190D01*
X3828648Y2561123D01*
X3828048Y2561923D01*
X3827348Y2562190D01*
X3824248D01*
G01X3834548Y2557923D02*
X3833748Y2558056D01*
X3833048Y2558590D01*
X3832448Y2559390D01*
X3832048Y2560323D01*
X3831848Y2561390D01*
Y2562456D01*
X3832048Y2563523D01*
X3832448Y2564456D01*
X3833048Y2565256D01*
X3833748Y2565790D01*
X3834548Y2565923D01*
X3835348Y2565790D01*
X3836048Y2565256D01*
X3836648Y2564456D01*
X3837048Y2563523D01*
X3837248Y2562456D01*
Y2561390D01*
X3837048Y2560323D01*
X3836648Y2559390D01*
X3836048Y2558590D01*
X3835348Y2558056D01*
X3834548Y2557923D01*
G01X3840048D02*
X3842548Y2565923D01*
X3845048Y2557923D01*
G01X3844148Y2560723D02*
X3840948D01*
G01X3848548Y2557923D02*
Y2565923D01*
X3851048D01*
X3851848Y2565523D01*
X3852348Y2564990D01*
X3852548Y2563923D01*
X3852348Y2562856D01*
X3851748Y2562190D01*
X3851048Y2561790D01*
X3848548D01*
G01X3851048D02*
X3852548Y2557923D01*
G01X3856348D02*
Y2565923D01*
X3858348D01*
X3859148Y2565523D01*
X3859748Y2564990D01*
X3860248Y2564190D01*
X3860648Y2563256D01*
X3860748Y2561923D01*
X3860648Y2560590D01*
X3860248Y2559656D01*
X3859748Y2558856D01*
X3859148Y2558323D01*
X3858348Y2557923D01*
X3856348D01*
G01X3872648D02*
Y2565923D01*
X3876448D01*
G01X3875048Y2562056D02*
X3872648D01*
G01X3881348Y2565923D02*
X3883748D01*
G01X3882548D02*
Y2557923D01*
G01X3881348D02*
X3883748D01*
G01X3888548Y2565923D02*
Y2557923D01*
X3892548D01*
G01X3900548D02*
X3896548D01*
Y2565923D01*
X3900548D01*
G01X3898948Y2562056D02*
X3896548D01*
G01X3907048Y2555256D02*
X3908048Y2556590D01*
X3908548Y2557923D01*
Y2563256D01*
X3908048Y2564590D01*
X3907048Y2565923D01*
G01X3163348Y2577190D02*
X3163748Y2577590D01*
X3164048Y2578256D01*
X3164248Y2579190D01*
X3164048Y2579990D01*
X3163648Y2580523D01*
X3162948Y2580923D01*
X3160248D01*
Y2572923D01*
X3163548D01*
X3164248Y2573456D01*
X3164648Y2574256D01*
X3164848Y2575190D01*
X3164648Y2576123D01*
X3164048Y2576923D01*
X3163348Y2577190D01*
X3160248D01*
G01X3170548Y2572656D02*
X3170348Y2572790D01*
Y2573056D01*
X3170548Y2573190D01*
X3170748Y2573056D01*
Y2572790D01*
X3170548Y2572656D01*
G01X3176048Y2572923D02*
X3178548Y2580923D01*
X3181048Y2572923D01*
G01X3180148Y2575723D02*
X3176948D01*
G01X3184548Y2580923D02*
Y2572923D01*
X3188548D01*
G01X3192548Y2580923D02*
Y2572923D01*
X3196548D01*
G01X3208048Y2580923D02*
X3210548Y2572923D01*
X3213048Y2580923D01*
G01X3217348D02*
X3219748D01*
G01X3218548D02*
Y2572923D01*
G01X3217348D02*
X3219748D01*
G01X3224048D02*
X3226548Y2580923D01*
X3229048Y2572923D01*
G01X3228148Y2575723D02*
X3224948D01*
G01X3232448Y2573989D02*
X3233248Y2573323D01*
X3234148Y2572923D01*
X3234948D01*
X3235748Y2573323D01*
X3236348Y2573989D01*
X3236648Y2574923D01*
X3236448Y2575856D01*
X3235948Y2576656D01*
X3235048Y2577190D01*
X3233848Y2577456D01*
X3233148Y2577990D01*
X3232848Y2578923D01*
X3233048Y2579856D01*
X3233548Y2580523D01*
X3234248Y2580923D01*
X3234948D01*
X3235648Y2580656D01*
X3236248Y2579990D01*
G01X3248548Y2572923D02*
Y2580923D01*
X3250948D01*
X3251748Y2580523D01*
X3252348Y2579590D01*
X3252548Y2578523D01*
X3252348Y2577456D01*
X3251848Y2576656D01*
X3250948Y2576256D01*
X3248548D01*
G01X3256548Y2580923D02*
Y2572923D01*
X3260548D01*
G01X3264348Y2580923D02*
Y2575190D01*
X3264748Y2573989D01*
X3265548Y2573190D01*
X3266548Y2572923D01*
X3267548Y2573190D01*
X3268348Y2573989D01*
X3268748Y2575190D01*
Y2580923D01*
G01X3275148Y2576923D02*
X3277148D01*
Y2574523D01*
X3276548Y2573723D01*
X3275848Y2573190D01*
X3274848Y2572923D01*
X3273848Y2573190D01*
X3273148Y2573723D01*
X3272548Y2574523D01*
X3272148Y2575456D01*
X3271948Y2576523D01*
Y2577456D01*
X3272148Y2578256D01*
X3272548Y2579190D01*
X3273148Y2579990D01*
X3273748Y2580523D01*
X3274548Y2580923D01*
X3275248D01*
X3276048Y2580656D01*
X3276648Y2580123D01*
G01X3283148Y2576923D02*
X3285148D01*
Y2574523D01*
X3284548Y2573723D01*
X3283848Y2573190D01*
X3282848Y2572923D01*
X3281848Y2573190D01*
X3281148Y2573723D01*
X3280548Y2574523D01*
X3280148Y2575456D01*
X3279948Y2576523D01*
Y2577456D01*
X3280148Y2578256D01*
X3280548Y2579190D01*
X3281148Y2579990D01*
X3281748Y2580523D01*
X3282548Y2580923D01*
X3283248D01*
X3284048Y2580656D01*
X3284648Y2580123D01*
G01X3292548Y2572923D02*
X3288548D01*
Y2580923D01*
X3292548D01*
G01X3290948Y2577056D02*
X3288548D01*
G01X3296348Y2572923D02*
Y2580923D01*
X3298348D01*
X3299148Y2580523D01*
X3299748Y2579990D01*
X3300248Y2579190D01*
X3300648Y2578256D01*
X3300748Y2576923D01*
X3300648Y2575590D01*
X3300248Y2574656D01*
X3299748Y2573856D01*
X3299148Y2573323D01*
X3298348Y2572923D01*
X3296348D01*
G01X3316548D02*
X3312548D01*
Y2580923D01*
X3316548D01*
G01X3314948Y2577056D02*
X3312548D01*
G01X3320448Y2572923D02*
X3324648Y2580923D01*
G01X3320448D02*
X3324648Y2572923D01*
G01X3332748Y2580256D02*
X3332148Y2580656D01*
X3331448Y2580923D01*
X3330648D01*
X3329748Y2580523D01*
X3329048Y2579856D01*
X3328548Y2579056D01*
X3328148Y2577723D01*
X3328048Y2576523D01*
X3328248Y2575323D01*
X3328548Y2574523D01*
X3329148Y2573723D01*
X3329848Y2573190D01*
X3330548Y2572923D01*
X3331248D01*
X3331948Y2573190D01*
X3332548Y2573590D01*
X3333048Y2574123D01*
G01X3340548Y2572923D02*
X3336548D01*
Y2580923D01*
X3340548D01*
G01X3338948Y2577056D02*
X3336548D01*
G01X3344548Y2572923D02*
Y2580923D01*
X3346948D01*
X3347748Y2580523D01*
X3348348Y2579590D01*
X3348548Y2578523D01*
X3348348Y2577456D01*
X3347848Y2576656D01*
X3346948Y2576256D01*
X3344548D01*
G01X3354548Y2580923D02*
Y2572923D01*
G01X3352248Y2580923D02*
X3356848D01*
G01X3368648Y2572923D02*
Y2580923D01*
X3372448D01*
G01X3371048Y2577056D02*
X3368648D01*
G01X3378548Y2572923D02*
X3377748Y2573056D01*
X3377048Y2573590D01*
X3376448Y2574390D01*
X3376048Y2575323D01*
X3375848Y2576390D01*
Y2577456D01*
X3376048Y2578523D01*
X3376448Y2579456D01*
X3377048Y2580256D01*
X3377748Y2580790D01*
X3378548Y2580923D01*
X3379348Y2580790D01*
X3380048Y2580256D01*
X3380648Y2579456D01*
X3381048Y2578523D01*
X3381248Y2577456D01*
Y2576390D01*
X3381048Y2575323D01*
X3380648Y2574390D01*
X3380048Y2573590D01*
X3379348Y2573056D01*
X3378548Y2572923D01*
G01X3384548D02*
Y2580923D01*
X3387048D01*
X3387848Y2580523D01*
X3388348Y2579990D01*
X3388548Y2578923D01*
X3388348Y2577856D01*
X3387748Y2577190D01*
X3387048Y2576790D01*
X3384548D01*
G01X3387048D02*
X3388548Y2572923D01*
G01X3160048Y2587923D02*
X3162548Y2595923D01*
X3165048Y2587923D01*
G01X3164148Y2590723D02*
X3160948D01*
G01X3170548Y2587656D02*
X3170348Y2587790D01*
Y2588056D01*
X3170548Y2588190D01*
X3170748Y2588056D01*
Y2587790D01*
X3170548Y2587656D01*
G01X3176048Y2595923D02*
X3178548Y2587923D01*
X3181048Y2595923D01*
G01X3185348D02*
X3187748D01*
G01X3186548D02*
Y2587923D01*
G01X3185348D02*
X3187748D01*
G01X3192048D02*
X3194548Y2595923D01*
X3197048Y2587923D01*
G01X3196148Y2590723D02*
X3192948D01*
G01X3210548Y2595923D02*
Y2587923D01*
G01X3208248Y2595923D02*
X3212848D01*
G01X3220548Y2587923D02*
X3216548D01*
Y2595923D01*
X3220548D01*
G01X3218948Y2592056D02*
X3216548D01*
G01X3224048Y2587923D02*
X3226548Y2595923D01*
X3229048Y2587923D01*
G01X3228148Y2590723D02*
X3224948D01*
G01X3232548Y2587923D02*
Y2595923D01*
X3235048D01*
X3235848Y2595523D01*
X3236348Y2594990D01*
X3236548Y2593923D01*
X3236348Y2592856D01*
X3235748Y2592190D01*
X3235048Y2591790D01*
X3232548D01*
G01X3235048D02*
X3236548Y2587923D01*
G01X3248348D02*
Y2595923D01*
X3250348D01*
X3251148Y2595523D01*
X3251748Y2594990D01*
X3252248Y2594190D01*
X3252648Y2593256D01*
X3252748Y2591923D01*
X3252648Y2590590D01*
X3252248Y2589656D01*
X3251748Y2588856D01*
X3251148Y2588323D01*
X3250348Y2587923D01*
X3248348D01*
G01X3256548D02*
Y2595923D01*
X3259048D01*
X3259848Y2595523D01*
X3260348Y2594990D01*
X3260548Y2593923D01*
X3260348Y2592856D01*
X3259748Y2592190D01*
X3259048Y2591790D01*
X3256548D01*
G01X3259048D02*
X3260548Y2587923D01*
G01X3266548D02*
X3265748Y2588056D01*
X3265048Y2588590D01*
X3264448Y2589390D01*
X3264048Y2590323D01*
X3263848Y2591390D01*
Y2592456D01*
X3264048Y2593523D01*
X3264448Y2594456D01*
X3265048Y2595256D01*
X3265748Y2595790D01*
X3266548Y2595923D01*
X3267348Y2595790D01*
X3268048Y2595256D01*
X3268648Y2594456D01*
X3269048Y2593523D01*
X3269248Y2592456D01*
Y2591390D01*
X3269048Y2590323D01*
X3268648Y2589390D01*
X3268048Y2588590D01*
X3267348Y2588056D01*
X3266548Y2587923D01*
G01X3272548D02*
Y2595923D01*
X3274948D01*
X3275748Y2595523D01*
X3276348Y2594590D01*
X3276548Y2593523D01*
X3276348Y2592456D01*
X3275848Y2591656D01*
X3274948Y2591256D01*
X3272548D01*
G01X3290048Y2585256D02*
X3289048Y2586590D01*
X3288548Y2587923D01*
Y2593256D01*
X3289048Y2594590D01*
X3290048Y2595923D01*
G01X3296648Y2587923D02*
Y2595923D01*
X3300448D01*
G01X3299048Y2592056D02*
X3296648D01*
G01X3306548Y2587923D02*
X3305748Y2588056D01*
X3305048Y2588590D01*
X3304448Y2589390D01*
X3304048Y2590323D01*
X3303848Y2591390D01*
Y2592456D01*
X3304048Y2593523D01*
X3304448Y2594456D01*
X3305048Y2595256D01*
X3305748Y2595790D01*
X3306548Y2595923D01*
X3307348Y2595790D01*
X3308048Y2595256D01*
X3308648Y2594456D01*
X3309048Y2593523D01*
X3309248Y2592456D01*
Y2591390D01*
X3309048Y2590323D01*
X3308648Y2589390D01*
X3308048Y2588590D01*
X3307348Y2588056D01*
X3306548Y2587923D01*
G01X3312548D02*
Y2595923D01*
X3315048D01*
X3315848Y2595523D01*
X3316348Y2594990D01*
X3316548Y2593923D01*
X3316348Y2592856D01*
X3315748Y2592190D01*
X3315048Y2591790D01*
X3312548D01*
G01X3315048D02*
X3316548Y2587923D01*
G01X3328048D02*
X3330548Y2595923D01*
X3333048Y2587923D01*
G01X3332148Y2590723D02*
X3328948D01*
G01X3336548Y2595923D02*
Y2587923D01*
X3340548D01*
G01X3344548Y2595923D02*
Y2587923D01*
X3348548D01*
G01X3360048Y2595923D02*
X3362548Y2587923D01*
X3365048Y2595923D01*
G01X3369348D02*
X3371748D01*
G01X3370548D02*
Y2587923D01*
G01X3369348D02*
X3371748D01*
G01X3376048D02*
X3378548Y2595923D01*
X3381048Y2587923D01*
G01X3380148Y2590723D02*
X3376948D01*
G01X3384448Y2588989D02*
X3385248Y2588323D01*
X3386148Y2587923D01*
X3386948D01*
X3387748Y2588323D01*
X3388348Y2588989D01*
X3388648Y2589923D01*
X3388448Y2590856D01*
X3387948Y2591656D01*
X3387048Y2592190D01*
X3385848Y2592456D01*
X3385148Y2592990D01*
X3384848Y2593923D01*
X3385048Y2594856D01*
X3385548Y2595523D01*
X3386248Y2595923D01*
X3386948D01*
X3387648Y2595656D01*
X3388248Y2594990D01*
G01X3400048Y2587923D02*
X3402548Y2595923D01*
X3405048Y2587923D01*
G01X3404148Y2590723D02*
X3400948D01*
G01X3408248Y2587923D02*
Y2595923D01*
X3412848Y2587923D01*
Y2595923D01*
G01X3416348Y2587923D02*
Y2595923D01*
X3418348D01*
X3419148Y2595523D01*
X3419748Y2594990D01*
X3420248Y2594190D01*
X3420648Y2593256D01*
X3420748Y2591923D01*
X3420648Y2590590D01*
X3420248Y2589656D01*
X3419748Y2588856D01*
X3419148Y2588323D01*
X3418348Y2587923D01*
X3416348D01*
G01X3432548D02*
Y2595923D01*
X3434948D01*
X3435748Y2595523D01*
X3436348Y2594590D01*
X3436548Y2593523D01*
X3436348Y2592456D01*
X3435848Y2591656D01*
X3434948Y2591256D01*
X3432548D01*
G01X3441348Y2595923D02*
X3443748D01*
G01X3442548D02*
Y2587923D01*
G01X3441348D02*
X3443748D01*
G01X3448248D02*
Y2595923D01*
X3452848Y2587923D01*
Y2595923D01*
G01X3456448Y2588989D02*
X3457248Y2588323D01*
X3458148Y2587923D01*
X3458948D01*
X3459748Y2588323D01*
X3460348Y2588989D01*
X3460648Y2589923D01*
X3460448Y2590856D01*
X3459948Y2591656D01*
X3459048Y2592190D01*
X3457848Y2592456D01*
X3457148Y2592990D01*
X3456848Y2593923D01*
X3457048Y2594856D01*
X3457548Y2595523D01*
X3458248Y2595923D01*
X3458948D01*
X3459648Y2595656D01*
X3460248Y2594990D01*
G01X3467048Y2585256D02*
X3468048Y2586590D01*
X3468548Y2587923D01*
Y2593256D01*
X3468048Y2594590D01*
X3467048Y2595923D01*
G01X3474548Y2587656D02*
X3474348Y2587790D01*
Y2588056D01*
X3474548Y2588190D01*
X3474748Y2588056D01*
Y2587790D01*
X3474548Y2587656D01*
G01X3142348Y2604523D02*
X3142948Y2603590D01*
X3143748Y2603056D01*
X3144648Y2602923D01*
X3145448Y2603056D01*
X3146248Y2603723D01*
X3146748Y2604523D01*
X3146848Y2605323D01*
X3146648Y2606256D01*
X3145948Y2606923D01*
X3145248Y2607190D01*
X3144348D01*
G01X3145248D02*
X3145848Y2607590D01*
X3146348Y2608256D01*
X3146548Y2609056D01*
X3146348Y2609856D01*
X3145848Y2610523D01*
X3144948Y2610923D01*
X3144048Y2610790D01*
X3143148Y2610256D01*
G01X3152548Y2602656D02*
X3152348Y2602790D01*
Y2603056D01*
X3152548Y2603190D01*
X3152748Y2603056D01*
Y2602790D01*
X3152548Y2602656D01*
G01X3158548Y2602923D02*
Y2610923D01*
X3160948D01*
X3161748Y2610523D01*
X3162348Y2609590D01*
X3162548Y2608523D01*
X3162348Y2607456D01*
X3161848Y2606656D01*
X3160948Y2606256D01*
X3158548D01*
G01X3170748Y2610256D02*
X3170148Y2610656D01*
X3169448Y2610923D01*
X3168648D01*
X3167748Y2610523D01*
X3167048Y2609856D01*
X3166548Y2609056D01*
X3166148Y2607723D01*
X3166048Y2606523D01*
X3166248Y2605323D01*
X3166548Y2604523D01*
X3167148Y2603723D01*
X3167848Y2603190D01*
X3168548Y2602923D01*
X3169248D01*
X3169948Y2603190D01*
X3170548Y2603590D01*
X3171048Y2604123D01*
G01X3177348Y2607190D02*
X3177748Y2607590D01*
X3178048Y2608256D01*
X3178248Y2609190D01*
X3178048Y2609990D01*
X3177648Y2610523D01*
X3176948Y2610923D01*
X3174248D01*
Y2602923D01*
X3177548D01*
X3178248Y2603456D01*
X3178648Y2604256D01*
X3178848Y2605190D01*
X3178648Y2606123D01*
X3178048Y2606923D01*
X3177348Y2607190D01*
X3174248D01*
G01X3190548Y2602923D02*
Y2610923D01*
X3192948D01*
X3193748Y2610523D01*
X3194348Y2609590D01*
X3194548Y2608523D01*
X3194348Y2607456D01*
X3193848Y2606656D01*
X3192948Y2606256D01*
X3190548D01*
G01X3198548Y2602923D02*
Y2610923D01*
X3201048D01*
X3201848Y2610523D01*
X3202348Y2609990D01*
X3202548Y2608923D01*
X3202348Y2607856D01*
X3201748Y2607190D01*
X3201048Y2606790D01*
X3198548D01*
G01X3201048D02*
X3202548Y2602923D01*
G01X3208548D02*
X3207748Y2603056D01*
X3207048Y2603590D01*
X3206448Y2604390D01*
X3206048Y2605323D01*
X3205848Y2606390D01*
Y2607456D01*
X3206048Y2608523D01*
X3206448Y2609456D01*
X3207048Y2610256D01*
X3207748Y2610790D01*
X3208548Y2610923D01*
X3209348Y2610790D01*
X3210048Y2610256D01*
X3210648Y2609456D01*
X3211048Y2608523D01*
X3211248Y2607456D01*
Y2606390D01*
X3211048Y2605323D01*
X3210648Y2604390D01*
X3210048Y2603590D01*
X3209348Y2603056D01*
X3208548Y2602923D01*
G01X3218748Y2610256D02*
X3218148Y2610656D01*
X3217448Y2610923D01*
X3216648D01*
X3215748Y2610523D01*
X3215048Y2609856D01*
X3214548Y2609056D01*
X3214148Y2607723D01*
X3214048Y2606523D01*
X3214248Y2605323D01*
X3214548Y2604523D01*
X3215148Y2603723D01*
X3215848Y2603190D01*
X3216548Y2602923D01*
X3217248D01*
X3217948Y2603190D01*
X3218548Y2603590D01*
X3219048Y2604123D01*
G01X3226548Y2602923D02*
X3222548D01*
Y2610923D01*
X3226548D01*
G01X3224948Y2607056D02*
X3222548D01*
G01X3230448Y2603989D02*
X3231248Y2603323D01*
X3232148Y2602923D01*
X3232948D01*
X3233748Y2603323D01*
X3234348Y2603989D01*
X3234648Y2604923D01*
X3234448Y2605856D01*
X3233948Y2606656D01*
X3233048Y2607190D01*
X3231848Y2607456D01*
X3231148Y2607990D01*
X3230848Y2608923D01*
X3231048Y2609856D01*
X3231548Y2610523D01*
X3232248Y2610923D01*
X3232948D01*
X3233648Y2610656D01*
X3234248Y2609990D01*
G01X3238448Y2603989D02*
X3239248Y2603323D01*
X3240148Y2602923D01*
X3240948D01*
X3241748Y2603323D01*
X3242348Y2603989D01*
X3242648Y2604923D01*
X3242448Y2605856D01*
X3241948Y2606656D01*
X3241048Y2607190D01*
X3239848Y2607456D01*
X3239148Y2607990D01*
X3238848Y2608923D01*
X3239048Y2609856D01*
X3239548Y2610523D01*
X3240248Y2610923D01*
X3240948D01*
X3241648Y2610656D01*
X3242248Y2609990D01*
G01X3248548Y2602656D02*
X3248348Y2602790D01*
Y2603056D01*
X3248548Y2603190D01*
X3248748Y2603056D01*
Y2602790D01*
X3248548Y2602656D01*
G01Y2606256D02*
X3248348Y2606390D01*
Y2606656D01*
X3248548Y2606790D01*
X3248748Y2606656D01*
Y2606390D01*
X3248548Y2606256D01*
G01X3142648Y2624590D02*
X3143248Y2625390D01*
X3143948Y2625790D01*
X3144748Y2625923D01*
X3145748Y2625656D01*
X3146448Y2624990D01*
X3146648Y2624190D01*
X3146548Y2623389D01*
X3146148Y2622723D01*
X3144148Y2621390D01*
X3143248Y2620456D01*
X3142648Y2619123D01*
X3142448Y2617923D01*
X3146648D01*
G01X3152548Y2617656D02*
X3152348Y2617790D01*
Y2618056D01*
X3152548Y2618190D01*
X3152748Y2618056D01*
Y2617790D01*
X3152548Y2617656D01*
G01X3158648Y2617923D02*
Y2625923D01*
X3162448D01*
G01X3161048Y2622056D02*
X3158648D01*
G01X3166048Y2617923D02*
X3168548Y2625923D01*
X3171048Y2617923D01*
G01X3170148Y2620723D02*
X3166948D01*
G01X3177348Y2622190D02*
X3177748Y2622590D01*
X3178048Y2623256D01*
X3178248Y2624190D01*
X3178048Y2624990D01*
X3177648Y2625523D01*
X3176948Y2625923D01*
X3174248D01*
Y2617923D01*
X3177548D01*
X3178248Y2618456D01*
X3178648Y2619256D01*
X3178848Y2620190D01*
X3178648Y2621123D01*
X3178048Y2621923D01*
X3177348Y2622190D01*
X3174248D01*
G01X3182548Y2617923D02*
Y2625923D01*
X3185048D01*
X3185848Y2625523D01*
X3186348Y2624990D01*
X3186548Y2623923D01*
X3186348Y2622856D01*
X3185748Y2622190D01*
X3185048Y2621790D01*
X3182548D01*
G01X3185048D02*
X3186548Y2617923D01*
G01X3191348Y2625923D02*
X3193748D01*
G01X3192548D02*
Y2617923D01*
G01X3191348D02*
X3193748D01*
G01X3202748Y2625256D02*
X3202148Y2625656D01*
X3201448Y2625923D01*
X3200648D01*
X3199748Y2625523D01*
X3199048Y2624856D01*
X3198548Y2624056D01*
X3198148Y2622723D01*
X3198048Y2621523D01*
X3198248Y2620323D01*
X3198548Y2619523D01*
X3199148Y2618723D01*
X3199848Y2618190D01*
X3200548Y2617923D01*
X3201248D01*
X3201948Y2618190D01*
X3202548Y2618590D01*
X3203048Y2619123D01*
G01X3206048Y2617923D02*
X3208548Y2625923D01*
X3211048Y2617923D01*
G01X3210148Y2620723D02*
X3206948D01*
G01X3216548Y2625923D02*
Y2617923D01*
G01X3214248Y2625923D02*
X3218848D01*
G01X3226548Y2617923D02*
X3222548D01*
Y2625923D01*
X3226548D01*
G01X3224948Y2622056D02*
X3222548D01*
G01X3238548Y2617923D02*
Y2625923D01*
X3240948D01*
X3241748Y2625523D01*
X3242348Y2624590D01*
X3242548Y2623523D01*
X3242348Y2622456D01*
X3241848Y2621656D01*
X3240948Y2621256D01*
X3238548D01*
G01X3250548Y2617923D02*
X3246548D01*
Y2625923D01*
X3250548D01*
G01X3248948Y2622056D02*
X3246548D01*
G01X3254548Y2617923D02*
Y2625923D01*
X3257048D01*
X3257848Y2625523D01*
X3258348Y2624990D01*
X3258548Y2623923D01*
X3258348Y2622856D01*
X3257748Y2622190D01*
X3257048Y2621790D01*
X3254548D01*
G01X3257048D02*
X3258548Y2617923D01*
G01X3272548D02*
X3271748Y2618056D01*
X3271048Y2618590D01*
X3270448Y2619390D01*
X3270048Y2620323D01*
X3269848Y2621390D01*
Y2622456D01*
X3270048Y2623523D01*
X3270448Y2624456D01*
X3271048Y2625256D01*
X3271748Y2625790D01*
X3272548Y2625923D01*
X3273348Y2625790D01*
X3274048Y2625256D01*
X3274648Y2624456D01*
X3275048Y2623523D01*
X3275248Y2622456D01*
Y2621390D01*
X3275048Y2620323D01*
X3274648Y2619390D01*
X3274048Y2618590D01*
X3273348Y2618056D01*
X3272548Y2617923D01*
G01X3273348Y2620056D02*
X3274548Y2617923D01*
G01X3278348Y2625923D02*
Y2620190D01*
X3278748Y2618989D01*
X3279548Y2618190D01*
X3280548Y2617923D01*
X3281548Y2618190D01*
X3282348Y2618989D01*
X3282748Y2620190D01*
Y2625923D01*
G01X3286048Y2617923D02*
X3288548Y2625923D01*
X3291048Y2617923D01*
G01X3290148Y2620723D02*
X3286948D01*
G01X3294248Y2617923D02*
Y2625923D01*
X3298848Y2617923D01*
Y2625923D01*
G01X3304548D02*
Y2617923D01*
G01X3302248Y2625923D02*
X3306848D01*
G01X3310048Y2617923D02*
X3312548Y2625923D01*
X3315048Y2617923D01*
G01X3314148Y2620723D02*
X3310948D01*
G01X3326548Y2617923D02*
Y2625923D01*
X3328948D01*
X3329748Y2625523D01*
X3330348Y2624590D01*
X3330548Y2623523D01*
X3330348Y2622456D01*
X3329848Y2621656D01*
X3328948Y2621256D01*
X3326548D01*
G01X3338748Y2625256D02*
X3338148Y2625656D01*
X3337448Y2625923D01*
X3336648D01*
X3335748Y2625523D01*
X3335048Y2624856D01*
X3334548Y2624056D01*
X3334148Y2622723D01*
X3334048Y2621523D01*
X3334248Y2620323D01*
X3334548Y2619523D01*
X3335148Y2618723D01*
X3335848Y2618190D01*
X3336548Y2617923D01*
X3337248D01*
X3337948Y2618190D01*
X3338548Y2618590D01*
X3339048Y2619123D01*
G01X3345348Y2622190D02*
X3345748Y2622590D01*
X3346048Y2623256D01*
X3346248Y2624190D01*
X3346048Y2624990D01*
X3345648Y2625523D01*
X3344948Y2625923D01*
X3342248D01*
Y2617923D01*
X3345548D01*
X3346248Y2618456D01*
X3346648Y2619256D01*
X3346848Y2620190D01*
X3346648Y2621123D01*
X3346048Y2621923D01*
X3345348Y2622190D01*
X3342248D01*
G01X3358448Y2618989D02*
X3359248Y2618323D01*
X3360148Y2617923D01*
X3360948D01*
X3361748Y2618323D01*
X3362348Y2618989D01*
X3362648Y2619923D01*
X3362448Y2620856D01*
X3361948Y2621656D01*
X3361048Y2622190D01*
X3359848Y2622456D01*
X3359148Y2622990D01*
X3358848Y2623923D01*
X3359048Y2624856D01*
X3359548Y2625523D01*
X3360248Y2625923D01*
X3360948D01*
X3361648Y2625656D01*
X3362248Y2624990D01*
G01X3366548Y2617923D02*
Y2625923D01*
X3368948D01*
X3369748Y2625523D01*
X3370348Y2624590D01*
X3370548Y2623523D01*
X3370348Y2622456D01*
X3369848Y2621656D01*
X3368948Y2621256D01*
X3366548D01*
G01X3378548Y2617923D02*
X3374548D01*
Y2625923D01*
X3378548D01*
G01X3376948Y2622056D02*
X3374548D01*
G01X3386748Y2625256D02*
X3386148Y2625656D01*
X3385448Y2625923D01*
X3384648D01*
X3383748Y2625523D01*
X3383048Y2624856D01*
X3382548Y2624056D01*
X3382148Y2622723D01*
X3382048Y2621523D01*
X3382248Y2620323D01*
X3382548Y2619523D01*
X3383148Y2618723D01*
X3383848Y2618190D01*
X3384548Y2617923D01*
X3385248D01*
X3385948Y2618190D01*
X3386548Y2618590D01*
X3387048Y2619123D01*
G01X3391348Y2625923D02*
X3393748D01*
G01X3392548D02*
Y2617923D01*
G01X3391348D02*
X3393748D01*
G01X3398648D02*
Y2625923D01*
X3402448D01*
G01X3401048Y2622056D02*
X3398648D01*
G01X3407348Y2625923D02*
X3409748D01*
G01X3408548D02*
Y2617923D01*
G01X3407348D02*
X3409748D01*
G01X3418748Y2625256D02*
X3418148Y2625656D01*
X3417448Y2625923D01*
X3416648D01*
X3415748Y2625523D01*
X3415048Y2624856D01*
X3414548Y2624056D01*
X3414148Y2622723D01*
X3414048Y2621523D01*
X3414248Y2620323D01*
X3414548Y2619523D01*
X3415148Y2618723D01*
X3415848Y2618190D01*
X3416548Y2617923D01*
X3417248D01*
X3417948Y2618190D01*
X3418548Y2618590D01*
X3419048Y2619123D01*
G01X3422048Y2617923D02*
X3424548Y2625923D01*
X3427048Y2617923D01*
G01X3426148Y2620723D02*
X3422948D01*
G01X3432548Y2625923D02*
Y2617923D01*
G01X3430248Y2625923D02*
X3434848D01*
G01X3439348D02*
X3441748D01*
G01X3440548D02*
Y2617923D01*
G01X3439348D02*
X3441748D01*
G01X3448548D02*
X3447748Y2618056D01*
X3447048Y2618590D01*
X3446448Y2619390D01*
X3446048Y2620323D01*
X3445848Y2621390D01*
Y2622456D01*
X3446048Y2623523D01*
X3446448Y2624456D01*
X3447048Y2625256D01*
X3447748Y2625790D01*
X3448548Y2625923D01*
X3449348Y2625790D01*
X3450048Y2625256D01*
X3450648Y2624456D01*
X3451048Y2623523D01*
X3451248Y2622456D01*
Y2621390D01*
X3451048Y2620323D01*
X3450648Y2619390D01*
X3450048Y2618590D01*
X3449348Y2618056D01*
X3448548Y2617923D01*
G01X3454248D02*
Y2625923D01*
X3458848Y2617923D01*
Y2625923D01*
G01X3475548Y2615256D02*
X3470548Y2623256D01*
Y2624590D01*
X3471548Y2625923D01*
X3472548D01*
X3473548Y2624590D01*
Y2623256D01*
X3472548Y2621923D01*
X3470548Y2620590D01*
X3469548Y2619256D01*
Y2616590D01*
X3470548Y2615256D01*
X3473548D01*
X3475548Y2617923D01*
G01X3488548D02*
X3487748Y2618056D01*
X3487048Y2618590D01*
X3486448Y2619390D01*
X3486048Y2620323D01*
X3485848Y2621390D01*
Y2622456D01*
X3486048Y2623523D01*
X3486448Y2624456D01*
X3487048Y2625256D01*
X3487748Y2625790D01*
X3488548Y2625923D01*
X3489348Y2625790D01*
X3490048Y2625256D01*
X3490648Y2624456D01*
X3491048Y2623523D01*
X3491248Y2622456D01*
Y2621390D01*
X3491048Y2620323D01*
X3490648Y2619390D01*
X3490048Y2618590D01*
X3489348Y2618056D01*
X3488548Y2617923D01*
G01X3489348Y2620056D02*
X3490548Y2617923D01*
G01X3498748Y2625256D02*
X3498148Y2625656D01*
X3497448Y2625923D01*
X3496648D01*
X3495748Y2625523D01*
X3495048Y2624856D01*
X3494548Y2624056D01*
X3494148Y2622723D01*
X3494048Y2621523D01*
X3494248Y2620323D01*
X3494548Y2619523D01*
X3495148Y2618723D01*
X3495848Y2618190D01*
X3496548Y2617923D01*
X3497248D01*
X3497948Y2618190D01*
X3498548Y2618590D01*
X3499048Y2619123D01*
G01X3504548Y2625923D02*
Y2617923D01*
G01X3502248Y2625923D02*
X3506848D01*
G01X3522548Y2617923D02*
X3518548D01*
Y2625923D01*
X3522548D01*
G01X3520948Y2622056D02*
X3518548D01*
G01X3528548Y2617923D02*
X3527748Y2618056D01*
X3527048Y2618590D01*
X3526448Y2619390D01*
X3526048Y2620323D01*
X3525848Y2621390D01*
Y2622456D01*
X3526048Y2623523D01*
X3526448Y2624456D01*
X3527048Y2625256D01*
X3527748Y2625790D01*
X3528548Y2625923D01*
X3529348Y2625790D01*
X3530048Y2625256D01*
X3530648Y2624456D01*
X3531048Y2623523D01*
X3531248Y2622456D01*
Y2621390D01*
X3531048Y2620323D01*
X3530648Y2619390D01*
X3530048Y2618590D01*
X3529348Y2618056D01*
X3528548Y2617923D01*
G01X3529348Y2620056D02*
X3530548Y2617923D01*
G01X3542648D02*
Y2625923D01*
X3546448D01*
G01X3545048Y2622056D02*
X3542648D01*
G01X3550048Y2617923D02*
X3552548Y2625923D01*
X3555048Y2617923D01*
G01X3554148Y2620723D02*
X3550948D01*
G01X3560548Y2617923D02*
X3559748Y2618056D01*
X3559048Y2618590D01*
X3558448Y2619390D01*
X3558048Y2620323D01*
X3557848Y2621390D01*
Y2622456D01*
X3558048Y2623523D01*
X3558448Y2624456D01*
X3559048Y2625256D01*
X3559748Y2625790D01*
X3560548Y2625923D01*
X3561348Y2625790D01*
X3562048Y2625256D01*
X3562648Y2624456D01*
X3563048Y2623523D01*
X3563248Y2622456D01*
Y2621390D01*
X3563048Y2620323D01*
X3562648Y2619390D01*
X3562048Y2618590D01*
X3561348Y2618056D01*
X3560548Y2617923D01*
G01X3561348Y2620056D02*
X3562548Y2617923D01*
G01X3568548Y2617656D02*
X3568348Y2617790D01*
Y2618056D01*
X3568548Y2618190D01*
X3568748Y2618056D01*
Y2617790D01*
X3568548Y2617656D01*
G01X3144548Y2632923D02*
Y2640923D01*
X3143348Y2639323D01*
G01Y2632923D02*
X3145748D01*
G01X3152548Y2632656D02*
X3152348Y2632790D01*
Y2633056D01*
X3152548Y2633190D01*
X3152748Y2633056D01*
Y2632790D01*
X3152548Y2632656D01*
G01X3158548Y2632923D02*
Y2640923D01*
X3160948D01*
X3161748Y2640523D01*
X3162348Y2639590D01*
X3162548Y2638523D01*
X3162348Y2637456D01*
X3161848Y2636656D01*
X3160948Y2636256D01*
X3158548D01*
G01X3170748Y2640256D02*
X3170148Y2640656D01*
X3169448Y2640923D01*
X3168648D01*
X3167748Y2640523D01*
X3167048Y2639856D01*
X3166548Y2639056D01*
X3166148Y2637723D01*
X3166048Y2636523D01*
X3166248Y2635323D01*
X3166548Y2634523D01*
X3167148Y2633723D01*
X3167848Y2633190D01*
X3168548Y2632923D01*
X3169248D01*
X3169948Y2633190D01*
X3170548Y2633590D01*
X3171048Y2634123D01*
G01X3177348Y2637190D02*
X3177748Y2637590D01*
X3178048Y2638256D01*
X3178248Y2639190D01*
X3178048Y2639990D01*
X3177648Y2640523D01*
X3176948Y2640923D01*
X3174248D01*
Y2632923D01*
X3177548D01*
X3178248Y2633456D01*
X3178648Y2634256D01*
X3178848Y2635190D01*
X3178648Y2636123D01*
X3178048Y2636923D01*
X3177348Y2637190D01*
X3174248D01*
G01X3190448Y2633989D02*
X3191248Y2633323D01*
X3192148Y2632923D01*
X3192948D01*
X3193748Y2633323D01*
X3194348Y2633989D01*
X3194648Y2634923D01*
X3194448Y2635856D01*
X3193948Y2636656D01*
X3193048Y2637190D01*
X3191848Y2637456D01*
X3191148Y2637990D01*
X3190848Y2638923D01*
X3191048Y2639856D01*
X3191548Y2640523D01*
X3192248Y2640923D01*
X3192948D01*
X3193648Y2640656D01*
X3194248Y2639990D01*
G01X3199348Y2640923D02*
X3201748D01*
G01X3200548D02*
Y2632923D01*
G01X3199348D02*
X3201748D01*
G01X3206648Y2640923D02*
X3210448D01*
X3206648Y2632923D01*
X3210448D01*
G01X3218548D02*
X3214548D01*
Y2640923D01*
X3218548D01*
G01X3216948Y2637056D02*
X3214548D01*
G01X3248548Y2632656D02*
X3248348Y2632790D01*
Y2633056D01*
X3248548Y2633190D01*
X3248748Y2633056D01*
Y2632790D01*
X3248548Y2632656D01*
G01Y2636256D02*
X3248348Y2636390D01*
Y2636656D01*
X3248548Y2636790D01*
X3248748Y2636656D01*
Y2636390D01*
X3248548Y2636256D01*
G01X3262648Y2632923D02*
Y2640923D01*
X3266448D01*
G01X3265048Y2637056D02*
X3262648D01*
G01X3272548Y2632923D02*
X3271748Y2633056D01*
X3271048Y2633590D01*
X3270448Y2634390D01*
X3270048Y2635323D01*
X3269848Y2636390D01*
Y2637456D01*
X3270048Y2638523D01*
X3270448Y2639456D01*
X3271048Y2640256D01*
X3271748Y2640790D01*
X3272548Y2640923D01*
X3273348Y2640790D01*
X3274048Y2640256D01*
X3274648Y2639456D01*
X3275048Y2638523D01*
X3275248Y2637456D01*
Y2636390D01*
X3275048Y2635323D01*
X3274648Y2634390D01*
X3274048Y2633590D01*
X3273348Y2633056D01*
X3272548Y2632923D01*
G01X3278548Y2640923D02*
Y2632923D01*
X3282548D01*
G01X3286548Y2640923D02*
Y2632923D01*
X3290548D01*
G01X3296548D02*
X3295748Y2633056D01*
X3295048Y2633590D01*
X3294448Y2634390D01*
X3294048Y2635323D01*
X3293848Y2636390D01*
Y2637456D01*
X3294048Y2638523D01*
X3294448Y2639456D01*
X3295048Y2640256D01*
X3295748Y2640790D01*
X3296548Y2640923D01*
X3297348Y2640790D01*
X3298048Y2640256D01*
X3298648Y2639456D01*
X3299048Y2638523D01*
X3299248Y2637456D01*
Y2636390D01*
X3299048Y2635323D01*
X3298648Y2634390D01*
X3298048Y2633590D01*
X3297348Y2633056D01*
X3296548Y2632923D01*
G01X3301548Y2640923D02*
X3302948Y2632923D01*
X3304548Y2640923D01*
X3306148Y2632923D01*
X3307548Y2640923D01*
G01X3321148Y2636923D02*
X3323148D01*
Y2634523D01*
X3322548Y2633723D01*
X3321848Y2633190D01*
X3320848Y2632923D01*
X3319848Y2633190D01*
X3319148Y2633723D01*
X3318548Y2634523D01*
X3318148Y2635456D01*
X3317948Y2636523D01*
Y2637456D01*
X3318148Y2638256D01*
X3318548Y2639190D01*
X3319148Y2639990D01*
X3319748Y2640523D01*
X3320548Y2640923D01*
X3321248D01*
X3322048Y2640656D01*
X3322648Y2640123D01*
G01X3330548Y2632923D02*
X3326548D01*
Y2640923D01*
X3330548D01*
G01X3328948Y2637056D02*
X3326548D01*
G01X3334548Y2632923D02*
Y2640923D01*
X3337048D01*
X3337848Y2640523D01*
X3338348Y2639990D01*
X3338548Y2638923D01*
X3338348Y2637856D01*
X3337748Y2637190D01*
X3337048Y2636790D01*
X3334548D01*
G01X3337048D02*
X3338548Y2632923D01*
G01X3345348Y2637190D02*
X3345748Y2637590D01*
X3346048Y2638256D01*
X3346248Y2639190D01*
X3346048Y2639990D01*
X3345648Y2640523D01*
X3344948Y2640923D01*
X3342248D01*
Y2632923D01*
X3345548D01*
X3346248Y2633456D01*
X3346648Y2634256D01*
X3346848Y2635190D01*
X3346648Y2636123D01*
X3346048Y2636923D01*
X3345348Y2637190D01*
X3342248D01*
G01X3354548Y2632923D02*
X3350548D01*
Y2640923D01*
X3354548D01*
G01X3352948Y2637056D02*
X3350548D01*
G01X3358548Y2632923D02*
Y2640923D01*
X3361048D01*
X3361848Y2640523D01*
X3362348Y2639990D01*
X3362548Y2638923D01*
X3362348Y2637856D01*
X3361748Y2637190D01*
X3361048Y2636790D01*
X3358548D01*
G01X3361048D02*
X3362548Y2632923D01*
G01X3374648D02*
Y2640923D01*
X3378448D01*
G01X3377048Y2637056D02*
X3374648D01*
G01X3383348Y2640923D02*
X3385748D01*
G01X3384548D02*
Y2632923D01*
G01X3383348D02*
X3385748D01*
G01X3390548Y2640923D02*
Y2632923D01*
X3394548D01*
G01X3402548D02*
X3398548D01*
Y2640923D01*
X3402548D01*
G01X3400948Y2637056D02*
X3398548D01*
G01X3407848Y2630523D02*
X3409248Y2632390D01*
Y2634256D01*
X3407848D01*
Y2632390D01*
X3409248D01*
G01Y2635590D02*
Y2637456D01*
X3407848D01*
Y2635590D01*
X3409248D01*
G01X3421548Y2640923D02*
X3422948Y2632923D01*
X3424548Y2640923D01*
X3426148Y2632923D01*
X3427548Y2640923D01*
G01X3431348D02*
X3433748D01*
G01X3432548D02*
Y2632923D01*
G01X3431348D02*
X3433748D01*
G01X3440548Y2640923D02*
Y2632923D01*
G01X3438248Y2640923D02*
X3442848D01*
G01X3446448Y2632923D02*
Y2640923D01*
G01X3450648D02*
Y2632923D01*
G01Y2636923D02*
X3446448D01*
G01X3464548Y2640923D02*
Y2632923D01*
G01X3462248Y2640923D02*
X3466848D01*
G01X3472548Y2632923D02*
X3471748Y2633056D01*
X3471048Y2633590D01*
X3470448Y2634390D01*
X3470048Y2635323D01*
X3469848Y2636390D01*
Y2637456D01*
X3470048Y2638523D01*
X3470448Y2639456D01*
X3471048Y2640256D01*
X3471748Y2640790D01*
X3472548Y2640923D01*
X3473348Y2640790D01*
X3474048Y2640256D01*
X3474648Y2639456D01*
X3475048Y2638523D01*
X3475248Y2637456D01*
Y2636390D01*
X3475048Y2635323D01*
X3474648Y2634390D01*
X3474048Y2633590D01*
X3473348Y2633056D01*
X3472548Y2632923D01*
G01X3478548Y2640923D02*
Y2632923D01*
X3482548D01*
G01X3490548D02*
X3486548D01*
Y2640923D01*
X3490548D01*
G01X3488948Y2637056D02*
X3486548D01*
G01X3494548Y2632923D02*
Y2640923D01*
X3497048D01*
X3497848Y2640523D01*
X3498348Y2639990D01*
X3498548Y2638923D01*
X3498348Y2637856D01*
X3497748Y2637190D01*
X3497048Y2636790D01*
X3494548D01*
G01X3497048D02*
X3498548Y2632923D01*
G01X3502048D02*
X3504548Y2640923D01*
X3507048Y2632923D01*
G01X3506148Y2635723D02*
X3502948D01*
G01X3510248Y2632923D02*
Y2640923D01*
X3514848Y2632923D01*
Y2640923D01*
G01X3522748Y2640256D02*
X3522148Y2640656D01*
X3521448Y2640923D01*
X3520648D01*
X3519748Y2640523D01*
X3519048Y2639856D01*
X3518548Y2639056D01*
X3518148Y2637723D01*
X3518048Y2636523D01*
X3518248Y2635323D01*
X3518548Y2634523D01*
X3519148Y2633723D01*
X3519848Y2633190D01*
X3520548Y2632923D01*
X3521248D01*
X3521948Y2633190D01*
X3522548Y2633590D01*
X3523048Y2634123D01*
G01X3530548Y2632923D02*
X3526548D01*
Y2640923D01*
X3530548D01*
G01X3528948Y2637056D02*
X3526548D01*
G01X3543248Y2634390D02*
X3545848D01*
G01Y2636790D02*
X3543248D01*
G01X3551448Y2635590D02*
X3553848D01*
G01X3552548Y2637323D02*
Y2633856D01*
G01X3558748Y2632656D02*
X3562348Y2640923D01*
G01X3567248Y2635590D02*
X3569848D01*
G01X3576548Y2640923D02*
X3575748Y2640656D01*
X3575148Y2639990D01*
X3574748Y2639190D01*
X3574448Y2638123D01*
X3574348Y2636923D01*
X3574448Y2635723D01*
X3574748Y2634656D01*
X3575148Y2633856D01*
X3575748Y2633190D01*
X3576548Y2632923D01*
X3577348Y2633190D01*
X3577948Y2633856D01*
X3578348Y2634656D01*
X3578648Y2635723D01*
X3578748Y2636923D01*
X3578648Y2638123D01*
X3578348Y2639190D01*
X3577948Y2639990D01*
X3577348Y2640656D01*
X3576548Y2640923D01*
G01X3584548Y2632656D02*
X3584348Y2632790D01*
Y2633056D01*
X3584548Y2633190D01*
X3584748Y2633056D01*
Y2632790D01*
X3584548Y2632656D01*
G01X3592548Y2632923D02*
Y2640923D01*
X3591348Y2639323D01*
G01Y2632923D02*
X3593748D01*
G01X3598348Y2634123D02*
X3598948Y2633456D01*
X3599648Y2633056D01*
X3600548Y2632923D01*
X3601448Y2633190D01*
X3602148Y2633723D01*
X3602648Y2634656D01*
X3602748Y2635723D01*
X3602548Y2636790D01*
X3602048Y2637456D01*
X3601348Y2637990D01*
X3600648Y2638123D01*
X3599948Y2637990D01*
X3599048Y2637456D01*
X3599348Y2640923D01*
X3602048D01*
G01X3605948Y2632923D02*
Y2640923D01*
X3608548Y2634256D01*
X3611148Y2640923D01*
Y2632923D01*
G01X3613948D02*
Y2640923D01*
X3616548Y2634256D01*
X3619148Y2640923D01*
Y2632923D01*
G01X3142248Y2647923D02*
Y2655923D01*
X3146848Y2647923D01*
Y2655923D01*
G01X3152548Y2647923D02*
X3151748Y2648056D01*
X3151048Y2648590D01*
X3150448Y2649390D01*
X3150048Y2650323D01*
X3149848Y2651390D01*
Y2652456D01*
X3150048Y2653523D01*
X3150448Y2654456D01*
X3151048Y2655256D01*
X3151748Y2655790D01*
X3152548Y2655923D01*
X3153348Y2655790D01*
X3154048Y2655256D01*
X3154648Y2654456D01*
X3155048Y2653523D01*
X3155248Y2652456D01*
Y2651390D01*
X3155048Y2650323D01*
X3154648Y2649390D01*
X3154048Y2648590D01*
X3153348Y2648056D01*
X3152548Y2647923D01*
G01X3160548Y2655923D02*
Y2647923D01*
G01X3158248Y2655923D02*
X3162848D01*
G01X3170548Y2647923D02*
X3166548D01*
Y2655923D01*
X3170548D01*
G01X3168948Y2652056D02*
X3166548D01*
G01X3174448Y2648989D02*
X3175248Y2648323D01*
X3176148Y2647923D01*
X3176948D01*
X3177748Y2648323D01*
X3178348Y2648989D01*
X3178648Y2649923D01*
X3178448Y2650856D01*
X3177948Y2651656D01*
X3177048Y2652190D01*
X3175848Y2652456D01*
X3175148Y2652990D01*
X3174848Y2653923D01*
X3175048Y2654856D01*
X3175548Y2655523D01*
X3176248Y2655923D01*
X3176948D01*
X3177648Y2655656D01*
X3178248Y2654990D01*
G01X3184548Y2647656D02*
X3184348Y2647790D01*
Y2648056D01*
X3184548Y2648190D01*
X3184748Y2648056D01*
Y2647790D01*
X3184548Y2647656D01*
G01Y2651256D02*
X3184348Y2651390D01*
Y2651656D01*
X3184548Y2651790D01*
X3184748Y2651656D01*
Y2651390D01*
X3184548Y2651256D01*
G01X3200048Y2645256D02*
X3199048Y2646590D01*
X3198548Y2647923D01*
Y2653256D01*
X3199048Y2654590D01*
X3200048Y2655923D01*
G01X3206348D02*
Y2650190D01*
X3206748Y2648989D01*
X3207548Y2648190D01*
X3208548Y2647923D01*
X3209548Y2648190D01*
X3210348Y2648989D01*
X3210748Y2650190D01*
Y2655923D01*
G01X3214248Y2647923D02*
Y2655923D01*
X3218848Y2647923D01*
Y2655923D01*
G01X3222548D02*
Y2647923D01*
X3226548D01*
G01X3234548D02*
X3230548D01*
Y2655923D01*
X3234548D01*
G01X3232948Y2652056D02*
X3230548D01*
G01X3238448Y2648989D02*
X3239248Y2648323D01*
X3240148Y2647923D01*
X3240948D01*
X3241748Y2648323D01*
X3242348Y2648989D01*
X3242648Y2649923D01*
X3242448Y2650856D01*
X3241948Y2651656D01*
X3241048Y2652190D01*
X3239848Y2652456D01*
X3239148Y2652990D01*
X3238848Y2653923D01*
X3239048Y2654856D01*
X3239548Y2655523D01*
X3240248Y2655923D01*
X3240948D01*
X3241648Y2655656D01*
X3242248Y2654990D01*
G01X3246448Y2648989D02*
X3247248Y2648323D01*
X3248148Y2647923D01*
X3248948D01*
X3249748Y2648323D01*
X3250348Y2648989D01*
X3250648Y2649923D01*
X3250448Y2650856D01*
X3249948Y2651656D01*
X3249048Y2652190D01*
X3247848Y2652456D01*
X3247148Y2652990D01*
X3246848Y2653923D01*
X3247048Y2654856D01*
X3247548Y2655523D01*
X3248248Y2655923D01*
X3248948D01*
X3249648Y2655656D01*
X3250248Y2654990D01*
G01X3264548Y2647923D02*
X3263748Y2648056D01*
X3263048Y2648590D01*
X3262448Y2649390D01*
X3262048Y2650323D01*
X3261848Y2651390D01*
Y2652456D01*
X3262048Y2653523D01*
X3262448Y2654456D01*
X3263048Y2655256D01*
X3263748Y2655790D01*
X3264548Y2655923D01*
X3265348Y2655790D01*
X3266048Y2655256D01*
X3266648Y2654456D01*
X3267048Y2653523D01*
X3267248Y2652456D01*
Y2651390D01*
X3267048Y2650323D01*
X3266648Y2649390D01*
X3266048Y2648590D01*
X3265348Y2648056D01*
X3264548Y2647923D01*
G01X3272548Y2655923D02*
Y2647923D01*
G01X3270248Y2655923D02*
X3274848D01*
G01X3278448Y2647923D02*
Y2655923D01*
G01X3282648D02*
Y2647923D01*
G01Y2651923D02*
X3278448D01*
G01X3290548Y2647923D02*
X3286548D01*
Y2655923D01*
X3290548D01*
G01X3288948Y2652056D02*
X3286548D01*
G01X3294548Y2647923D02*
Y2655923D01*
X3297048D01*
X3297848Y2655523D01*
X3298348Y2654990D01*
X3298548Y2653923D01*
X3298348Y2652856D01*
X3297748Y2652190D01*
X3297048Y2651790D01*
X3294548D01*
G01X3297048D02*
X3298548Y2647923D01*
G01X3301548Y2655923D02*
X3302948Y2647923D01*
X3304548Y2655923D01*
X3306148Y2647923D01*
X3307548Y2655923D01*
G01X3311348D02*
X3313748D01*
G01X3312548D02*
Y2647923D01*
G01X3311348D02*
X3313748D01*
G01X3318448Y2648989D02*
X3319248Y2648323D01*
X3320148Y2647923D01*
X3320948D01*
X3321748Y2648323D01*
X3322348Y2648989D01*
X3322648Y2649923D01*
X3322448Y2650856D01*
X3321948Y2651656D01*
X3321048Y2652190D01*
X3319848Y2652456D01*
X3319148Y2652990D01*
X3318848Y2653923D01*
X3319048Y2654856D01*
X3319548Y2655523D01*
X3320248Y2655923D01*
X3320948D01*
X3321648Y2655656D01*
X3322248Y2654990D01*
G01X3330548Y2647923D02*
X3326548D01*
Y2655923D01*
X3330548D01*
G01X3328948Y2652056D02*
X3326548D01*
G01X3342448Y2648989D02*
X3343248Y2648323D01*
X3344148Y2647923D01*
X3344948D01*
X3345748Y2648323D01*
X3346348Y2648989D01*
X3346648Y2649923D01*
X3346448Y2650856D01*
X3345948Y2651656D01*
X3345048Y2652190D01*
X3343848Y2652456D01*
X3343148Y2652990D01*
X3342848Y2653923D01*
X3343048Y2654856D01*
X3343548Y2655523D01*
X3344248Y2655923D01*
X3344948D01*
X3345648Y2655656D01*
X3346248Y2654990D01*
G01X3350548Y2647923D02*
Y2655923D01*
X3352948D01*
X3353748Y2655523D01*
X3354348Y2654590D01*
X3354548Y2653523D01*
X3354348Y2652456D01*
X3353848Y2651656D01*
X3352948Y2651256D01*
X3350548D01*
G01X3362548Y2647923D02*
X3358548D01*
Y2655923D01*
X3362548D01*
G01X3360948Y2652056D02*
X3358548D01*
G01X3370748Y2655256D02*
X3370148Y2655656D01*
X3369448Y2655923D01*
X3368648D01*
X3367748Y2655523D01*
X3367048Y2654856D01*
X3366548Y2654056D01*
X3366148Y2652723D01*
X3366048Y2651523D01*
X3366248Y2650323D01*
X3366548Y2649523D01*
X3367148Y2648723D01*
X3367848Y2648190D01*
X3368548Y2647923D01*
X3369248D01*
X3369948Y2648190D01*
X3370548Y2648590D01*
X3371048Y2649123D01*
G01X3375348Y2655923D02*
X3377748D01*
G01X3376548D02*
Y2647923D01*
G01X3375348D02*
X3377748D01*
G01X3382648D02*
Y2655923D01*
X3386448D01*
G01X3385048Y2652056D02*
X3382648D01*
G01X3391348Y2655923D02*
X3393748D01*
G01X3392548D02*
Y2647923D01*
G01X3391348D02*
X3393748D01*
G01X3402548D02*
X3398548D01*
Y2655923D01*
X3402548D01*
G01X3400948Y2652056D02*
X3398548D01*
G01X3406348Y2647923D02*
Y2655923D01*
X3408348D01*
X3409148Y2655523D01*
X3409748Y2654990D01*
X3410248Y2654190D01*
X3410648Y2653256D01*
X3410748Y2651923D01*
X3410648Y2650590D01*
X3410248Y2649656D01*
X3409748Y2648856D01*
X3409148Y2648323D01*
X3408348Y2647923D01*
X3406348D01*
G01X3423348Y2655923D02*
X3425748D01*
G01X3424548D02*
Y2647923D01*
G01X3423348D02*
X3425748D01*
G01X3430248D02*
Y2655923D01*
X3434848Y2647923D01*
Y2655923D01*
G01X3446548Y2647923D02*
Y2655923D01*
X3448948D01*
X3449748Y2655523D01*
X3450348Y2654590D01*
X3450548Y2653523D01*
X3450348Y2652456D01*
X3449848Y2651656D01*
X3448948Y2651256D01*
X3446548D01*
G01X3458748Y2655256D02*
X3458148Y2655656D01*
X3457448Y2655923D01*
X3456648D01*
X3455748Y2655523D01*
X3455048Y2654856D01*
X3454548Y2654056D01*
X3454148Y2652723D01*
X3454048Y2651523D01*
X3454248Y2650323D01*
X3454548Y2649523D01*
X3455148Y2648723D01*
X3455848Y2648190D01*
X3456548Y2647923D01*
X3457248D01*
X3457948Y2648190D01*
X3458548Y2648590D01*
X3459048Y2649123D01*
G01X3465348Y2652190D02*
X3465748Y2652590D01*
X3466048Y2653256D01*
X3466248Y2654190D01*
X3466048Y2654990D01*
X3465648Y2655523D01*
X3464948Y2655923D01*
X3462248D01*
Y2647923D01*
X3465548D01*
X3466248Y2648456D01*
X3466648Y2649256D01*
X3466848Y2650190D01*
X3466648Y2651123D01*
X3466048Y2651923D01*
X3465348Y2652190D01*
X3462248D01*
G01X3478448Y2648989D02*
X3479248Y2648323D01*
X3480148Y2647923D01*
X3480948D01*
X3481748Y2648323D01*
X3482348Y2648989D01*
X3482648Y2649923D01*
X3482448Y2650856D01*
X3481948Y2651656D01*
X3481048Y2652190D01*
X3479848Y2652456D01*
X3479148Y2652990D01*
X3478848Y2653923D01*
X3479048Y2654856D01*
X3479548Y2655523D01*
X3480248Y2655923D01*
X3480948D01*
X3481648Y2655656D01*
X3482248Y2654990D01*
G01X3486548Y2647923D02*
Y2655923D01*
X3488948D01*
X3489748Y2655523D01*
X3490348Y2654590D01*
X3490548Y2653523D01*
X3490348Y2652456D01*
X3489848Y2651656D01*
X3488948Y2651256D01*
X3486548D01*
G01X3498548Y2647923D02*
X3494548D01*
Y2655923D01*
X3498548D01*
G01X3496948Y2652056D02*
X3494548D01*
G01X3506748Y2655256D02*
X3506148Y2655656D01*
X3505448Y2655923D01*
X3504648D01*
X3503748Y2655523D01*
X3503048Y2654856D01*
X3502548Y2654056D01*
X3502148Y2652723D01*
X3502048Y2651523D01*
X3502248Y2650323D01*
X3502548Y2649523D01*
X3503148Y2648723D01*
X3503848Y2648190D01*
X3504548Y2647923D01*
X3505248D01*
X3505948Y2648190D01*
X3506548Y2648590D01*
X3507048Y2649123D01*
G01X3513048Y2645256D02*
X3514048Y2646590D01*
X3514548Y2647923D01*
Y2653256D01*
X3514048Y2654590D01*
X3513048Y2655923D01*
G01X3144548Y2662923D02*
X3143748Y2663056D01*
X3143048Y2663590D01*
X3142448Y2664390D01*
X3142048Y2665323D01*
X3141848Y2666390D01*
Y2667456D01*
X3142048Y2668523D01*
X3142448Y2669456D01*
X3143048Y2670256D01*
X3143748Y2670790D01*
X3144548Y2670923D01*
X3145348Y2670790D01*
X3146048Y2670256D01*
X3146648Y2669456D01*
X3147048Y2668523D01*
X3147248Y2667456D01*
Y2666390D01*
X3147048Y2665323D01*
X3146648Y2664390D01*
X3146048Y2663590D01*
X3145348Y2663056D01*
X3144548Y2662923D01*
G01X3145348Y2665056D02*
X3146548Y2662923D01*
G01X3150848Y2668256D02*
Y2664523D01*
X3151248Y2663590D01*
X3151848Y2663056D01*
X3152548Y2662923D01*
X3153248Y2663056D01*
X3153848Y2663590D01*
X3154248Y2664523D01*
G01Y2662923D02*
Y2668256D01*
G01X3162348Y2662923D02*
Y2668256D01*
G01Y2667323D02*
X3161948Y2667856D01*
X3161348Y2668123D01*
X3160648Y2668256D01*
X3159948Y2667990D01*
X3159348Y2667456D01*
X3158948Y2666656D01*
X3158748Y2665590D01*
X3158948Y2664523D01*
X3159348Y2663723D01*
X3159948Y2663190D01*
X3160648Y2662923D01*
X3161348Y2663056D01*
X3161948Y2663456D01*
X3162348Y2663989D01*
G01X3166848Y2662923D02*
Y2668256D01*
G01Y2666923D02*
X3167248Y2667590D01*
X3167848Y2668123D01*
X3168648Y2668256D01*
X3169348Y2668123D01*
X3169948Y2667590D01*
X3170248Y2666656D01*
Y2662923D01*
G01X3176548Y2670923D02*
Y2662923D01*
G01X3175148Y2668256D02*
X3177948D01*
G01X3186348Y2662923D02*
Y2668256D01*
G01Y2667323D02*
X3185948Y2667856D01*
X3185348Y2668123D01*
X3184648Y2668256D01*
X3183948Y2667990D01*
X3183348Y2667456D01*
X3182948Y2666656D01*
X3182748Y2665590D01*
X3182948Y2664523D01*
X3183348Y2663723D01*
X3183948Y2663190D01*
X3184648Y2662923D01*
X3185348Y2663056D01*
X3185948Y2663456D01*
X3186348Y2663989D01*
G01X3198648Y2662923D02*
Y2670923D01*
X3202448D01*
G01X3201048Y2667056D02*
X3198648D01*
G01X3206048Y2662923D02*
X3208548Y2670923D01*
X3211048Y2662923D01*
G01X3210148Y2665723D02*
X3206948D01*
G01X3217348Y2667190D02*
X3217748Y2667590D01*
X3218048Y2668256D01*
X3218248Y2669190D01*
X3218048Y2669990D01*
X3217648Y2670523D01*
X3216948Y2670923D01*
X3214248D01*
Y2662923D01*
X3217548D01*
X3218248Y2663456D01*
X3218648Y2664256D01*
X3218848Y2665190D01*
X3218648Y2666123D01*
X3218048Y2666923D01*
X3217348Y2667190D01*
X3214248D01*
G01X3230248Y2662923D02*
Y2670923D01*
X3234848Y2662923D01*
Y2670923D01*
G01X3240548Y2662923D02*
X3239748Y2663056D01*
X3239048Y2663590D01*
X3238448Y2664390D01*
X3238048Y2665323D01*
X3237848Y2666390D01*
Y2667456D01*
X3238048Y2668523D01*
X3238448Y2669456D01*
X3239048Y2670256D01*
X3239748Y2670790D01*
X3240548Y2670923D01*
X3241348Y2670790D01*
X3242048Y2670256D01*
X3242648Y2669456D01*
X3243048Y2668523D01*
X3243248Y2667456D01*
Y2666390D01*
X3243048Y2665323D01*
X3242648Y2664390D01*
X3242048Y2663590D01*
X3241348Y2663056D01*
X3240548Y2662923D01*
G01X3248548Y2670923D02*
Y2662923D01*
G01X3246248Y2670923D02*
X3250848D01*
G01X3258548Y2662923D02*
X3254548D01*
Y2670923D01*
X3258548D01*
G01X3256948Y2667056D02*
X3254548D01*
G01X3270548Y2662923D02*
Y2670923D01*
X3273048D01*
X3273848Y2670523D01*
X3274348Y2669990D01*
X3274548Y2668923D01*
X3274348Y2667856D01*
X3273748Y2667190D01*
X3273048Y2666790D01*
X3270548D01*
G01X3273048D02*
X3274548Y2662923D01*
G01X3282548D02*
X3278548D01*
Y2670923D01*
X3282548D01*
G01X3280948Y2667056D02*
X3278548D01*
G01X3286048Y2670923D02*
X3288548Y2662923D01*
X3291048Y2670923D01*
G01X3296548Y2662656D02*
X3296348Y2662790D01*
Y2663056D01*
X3296548Y2663190D01*
X3296748Y2663056D01*
Y2662790D01*
X3296548Y2662656D01*
G01Y2666256D02*
X3296348Y2666390D01*
Y2666656D01*
X3296548Y2666790D01*
X3296748Y2666656D01*
Y2666390D01*
X3296548Y2666256D01*
G01X3302648Y2662923D02*
Y2670923D01*
X3306448D01*
G01X3305048Y2667056D02*
X3302648D01*
G01X3155178Y2022375D02*
Y1990879D01*
G01D02*
Y2042060D01*
G01Y2093241D02*
Y2042060D01*
G01Y2061745D02*
Y2093241D01*
G01X3179848Y2108983D02*
X3167348D01*
X3176306Y2103248D01*
Y2110998D01*
G01X3179848Y2115493D02*
X3167348D01*
X3177765Y2119523D01*
X3167348Y2123553D01*
X3179848D01*
G01Y2127893D02*
X3167348D01*
X3177765Y2131923D01*
X3167348Y2135953D01*
X3179848D01*
G01X3170348Y2247190D02*
X3170748Y2247590D01*
X3171048Y2248256D01*
X3171248Y2249190D01*
X3171048Y2249990D01*
X3170648Y2250523D01*
X3169948Y2250923D01*
X3167248D01*
Y2242923D01*
X3170548D01*
X3171248Y2243456D01*
X3171648Y2244256D01*
X3171848Y2245190D01*
X3171648Y2246123D01*
X3171048Y2246923D01*
X3170348Y2247190D01*
X3167248D01*
G01X3177548Y2242656D02*
X3177348Y2242790D01*
Y2243056D01*
X3177548Y2243190D01*
X3177748Y2243056D01*
Y2242790D01*
X3177548Y2242656D01*
G01X3184348Y2250923D02*
X3186748D01*
G01X3185548D02*
Y2242923D01*
G01X3184348D02*
X3186748D01*
G01X3191648D02*
Y2250923D01*
X3195448D01*
G01X3194048Y2247056D02*
X3191648D01*
G01X3209548Y2250923D02*
Y2242923D01*
G01X3207248Y2250923D02*
X3211848D01*
G01X3215448Y2242923D02*
Y2250923D01*
G01X3219648D02*
Y2242923D01*
G01Y2246923D02*
X3215448D01*
G01X3227548Y2242923D02*
X3223548D01*
Y2250923D01*
X3227548D01*
G01X3225948Y2247056D02*
X3223548D01*
G01X3239548Y2242923D02*
Y2250923D01*
X3241948D01*
X3242748Y2250523D01*
X3243348Y2249590D01*
X3243548Y2248523D01*
X3243348Y2247456D01*
X3242848Y2246656D01*
X3241948Y2246256D01*
X3239548D01*
G01X3249548Y2250923D02*
Y2242923D01*
G01X3247248Y2250923D02*
X3251848D01*
G01X3255448Y2242923D02*
Y2250923D01*
G01X3259648D02*
Y2242923D01*
G01Y2246923D02*
X3255448D01*
G01X3273548Y2250923D02*
Y2242923D01*
G01X3271248Y2250923D02*
X3275848D01*
G01X3281548Y2242923D02*
X3280748Y2243056D01*
X3280048Y2243590D01*
X3279448Y2244390D01*
X3279048Y2245323D01*
X3278848Y2246390D01*
Y2247456D01*
X3279048Y2248523D01*
X3279448Y2249456D01*
X3280048Y2250256D01*
X3280748Y2250790D01*
X3281548Y2250923D01*
X3282348Y2250790D01*
X3283048Y2250256D01*
X3283648Y2249456D01*
X3284048Y2248523D01*
X3284248Y2247456D01*
Y2246390D01*
X3284048Y2245323D01*
X3283648Y2244390D01*
X3283048Y2243590D01*
X3282348Y2243056D01*
X3281548Y2242923D01*
G01X3289548D02*
X3288748Y2243056D01*
X3288048Y2243590D01*
X3287448Y2244390D01*
X3287048Y2245323D01*
X3286848Y2246390D01*
Y2247456D01*
X3287048Y2248523D01*
X3287448Y2249456D01*
X3288048Y2250256D01*
X3288748Y2250790D01*
X3289548Y2250923D01*
X3290348Y2250790D01*
X3291048Y2250256D01*
X3291648Y2249456D01*
X3292048Y2248523D01*
X3292248Y2247456D01*
Y2246390D01*
X3292048Y2245323D01*
X3291648Y2244390D01*
X3291048Y2243590D01*
X3290348Y2243056D01*
X3289548Y2242923D01*
G01X3295548Y2250923D02*
Y2242923D01*
X3299548D01*
G01X3304348Y2250923D02*
X3306748D01*
G01X3305548D02*
Y2242923D01*
G01X3304348D02*
X3306748D01*
G01X3311248D02*
Y2250923D01*
X3315848Y2242923D01*
Y2250923D01*
G01X3322148Y2246923D02*
X3324148D01*
Y2244523D01*
X3323548Y2243723D01*
X3322848Y2243190D01*
X3321848Y2242923D01*
X3320848Y2243190D01*
X3320148Y2243723D01*
X3319548Y2244523D01*
X3319148Y2245456D01*
X3318948Y2246523D01*
Y2247456D01*
X3319148Y2248256D01*
X3319548Y2249190D01*
X3320148Y2249990D01*
X3320748Y2250523D01*
X3321548Y2250923D01*
X3322248D01*
X3323048Y2250656D01*
X3323648Y2250123D01*
G01X3335448Y2242923D02*
Y2250923D01*
G01X3339648D02*
Y2242923D01*
G01Y2246923D02*
X3335448D01*
G01X3345548Y2242923D02*
X3344748Y2243056D01*
X3344048Y2243590D01*
X3343448Y2244390D01*
X3343048Y2245323D01*
X3342848Y2246390D01*
Y2247456D01*
X3343048Y2248523D01*
X3343448Y2249456D01*
X3344048Y2250256D01*
X3344748Y2250790D01*
X3345548Y2250923D01*
X3346348Y2250790D01*
X3347048Y2250256D01*
X3347648Y2249456D01*
X3348048Y2248523D01*
X3348248Y2247456D01*
Y2246390D01*
X3348048Y2245323D01*
X3347648Y2244390D01*
X3347048Y2243590D01*
X3346348Y2243056D01*
X3345548Y2242923D01*
G01X3351548Y2250923D02*
Y2242923D01*
X3355548D01*
G01X3363548D02*
X3359548D01*
Y2250923D01*
X3363548D01*
G01X3361948Y2247056D02*
X3359548D01*
G01X3376348Y2250923D02*
X3378748D01*
G01X3377548D02*
Y2242923D01*
G01X3376348D02*
X3378748D01*
G01X3383448Y2243989D02*
X3384248Y2243323D01*
X3385148Y2242923D01*
X3385948D01*
X3386748Y2243323D01*
X3387348Y2243989D01*
X3387648Y2244923D01*
X3387448Y2245856D01*
X3386948Y2246656D01*
X3386048Y2247190D01*
X3384848Y2247456D01*
X3384148Y2247990D01*
X3383848Y2248923D01*
X3384048Y2249856D01*
X3384548Y2250523D01*
X3385248Y2250923D01*
X3385948D01*
X3386648Y2250656D01*
X3387248Y2249990D01*
G01X3398948Y2242923D02*
Y2250923D01*
X3401548Y2244256D01*
X3404148Y2250923D01*
Y2242923D01*
G01X3407048D02*
X3409548Y2250923D01*
X3412048Y2242923D01*
G01X3411148Y2245723D02*
X3407948D01*
G01X3415348Y2242923D02*
Y2250923D01*
X3417348D01*
X3418148Y2250523D01*
X3418748Y2249990D01*
X3419248Y2249190D01*
X3419648Y2248256D01*
X3419748Y2246923D01*
X3419648Y2245590D01*
X3419248Y2244656D01*
X3418748Y2243856D01*
X3418148Y2243323D01*
X3417348Y2242923D01*
X3415348D01*
G01X3427548D02*
X3423548D01*
Y2250923D01*
X3427548D01*
G01X3425948Y2247056D02*
X3423548D01*
G01X3442348Y2247190D02*
X3442748Y2247590D01*
X3443048Y2248256D01*
X3443248Y2249190D01*
X3443048Y2249990D01*
X3442648Y2250523D01*
X3441948Y2250923D01*
X3439248D01*
Y2242923D01*
X3442548D01*
X3443248Y2243456D01*
X3443648Y2244256D01*
X3443848Y2245190D01*
X3443648Y2246123D01*
X3443048Y2246923D01*
X3442348Y2247190D01*
X3439248D01*
G01X3449548Y2242923D02*
Y2246523D01*
X3447548Y2250923D01*
G01X3451548D02*
X3449548Y2246523D01*
G01X3463548Y2242923D02*
Y2250923D01*
X3466048D01*
X3466848Y2250523D01*
X3467348Y2249990D01*
X3467548Y2248923D01*
X3467348Y2247856D01*
X3466748Y2247190D01*
X3466048Y2246790D01*
X3463548D01*
G01X3466048D02*
X3467548Y2242923D01*
G01X3473548D02*
X3472748Y2243056D01*
X3472048Y2243590D01*
X3471448Y2244390D01*
X3471048Y2245323D01*
X3470848Y2246390D01*
Y2247456D01*
X3471048Y2248523D01*
X3471448Y2249456D01*
X3472048Y2250256D01*
X3472748Y2250790D01*
X3473548Y2250923D01*
X3474348Y2250790D01*
X3475048Y2250256D01*
X3475648Y2249456D01*
X3476048Y2248523D01*
X3476248Y2247456D01*
Y2246390D01*
X3476048Y2245323D01*
X3475648Y2244390D01*
X3475048Y2243590D01*
X3474348Y2243056D01*
X3473548Y2242923D01*
G01X3479348Y2250923D02*
Y2245190D01*
X3479748Y2243989D01*
X3480548Y2243190D01*
X3481548Y2242923D01*
X3482548Y2243190D01*
X3483348Y2243989D01*
X3483748Y2245190D01*
Y2250923D01*
G01X3489548D02*
Y2242923D01*
G01X3487248Y2250923D02*
X3491848D01*
G01X3496348D02*
X3498748D01*
G01X3497548D02*
Y2242923D01*
G01X3496348D02*
X3498748D01*
G01X3503248D02*
Y2250923D01*
X3507848Y2242923D01*
Y2250923D01*
G01X3514148Y2246923D02*
X3516148D01*
Y2244523D01*
X3515548Y2243723D01*
X3514848Y2243190D01*
X3513848Y2242923D01*
X3512848Y2243190D01*
X3512148Y2243723D01*
X3511548Y2244523D01*
X3511148Y2245456D01*
X3510948Y2246523D01*
Y2247456D01*
X3511148Y2248256D01*
X3511548Y2249190D01*
X3512148Y2249990D01*
X3512748Y2250523D01*
X3513548Y2250923D01*
X3514248D01*
X3515048Y2250656D01*
X3515648Y2250123D01*
G01X3521348Y2241456D02*
X3521748Y2243190D01*
G01X3535248Y2242923D02*
Y2250923D01*
X3539848Y2242923D01*
Y2250923D01*
G01X3545548Y2242923D02*
X3544748Y2243056D01*
X3544048Y2243590D01*
X3543448Y2244390D01*
X3543048Y2245323D01*
X3542848Y2246390D01*
Y2247456D01*
X3543048Y2248523D01*
X3543448Y2249456D01*
X3544048Y2250256D01*
X3544748Y2250790D01*
X3545548Y2250923D01*
X3546348Y2250790D01*
X3547048Y2250256D01*
X3547648Y2249456D01*
X3548048Y2248523D01*
X3548248Y2247456D01*
Y2246390D01*
X3548048Y2245323D01*
X3547648Y2244390D01*
X3547048Y2243590D01*
X3546348Y2243056D01*
X3545548Y2242923D01*
G01X3551248D02*
Y2250923D01*
X3555848Y2242923D01*
Y2250923D01*
G01X3560248Y2245590D02*
X3562848D01*
G01X3567648Y2242923D02*
Y2250923D01*
X3571448D01*
G01X3570048Y2247056D02*
X3567648D01*
G01X3575348Y2250923D02*
Y2245190D01*
X3575748Y2243989D01*
X3576548Y2243190D01*
X3577548Y2242923D01*
X3578548Y2243190D01*
X3579348Y2243989D01*
X3579748Y2245190D01*
Y2250923D01*
G01X3583248Y2242923D02*
Y2250923D01*
X3587848Y2242923D01*
Y2250923D01*
G01X3595748Y2250256D02*
X3595148Y2250656D01*
X3594448Y2250923D01*
X3593648D01*
X3592748Y2250523D01*
X3592048Y2249856D01*
X3591548Y2249056D01*
X3591148Y2247723D01*
X3591048Y2246523D01*
X3591248Y2245323D01*
X3591548Y2244523D01*
X3592148Y2243723D01*
X3592848Y2243190D01*
X3593548Y2242923D01*
X3594248D01*
X3594948Y2243190D01*
X3595548Y2243590D01*
X3596048Y2244123D01*
G01X3601548Y2250923D02*
Y2242923D01*
G01X3599248Y2250923D02*
X3603848D01*
G01X3608348D02*
X3610748D01*
G01X3609548D02*
Y2242923D01*
G01X3608348D02*
X3610748D01*
G01X3617548D02*
X3616748Y2243056D01*
X3616048Y2243590D01*
X3615448Y2244390D01*
X3615048Y2245323D01*
X3614848Y2246390D01*
Y2247456D01*
X3615048Y2248523D01*
X3615448Y2249456D01*
X3616048Y2250256D01*
X3616748Y2250790D01*
X3617548Y2250923D01*
X3618348Y2250790D01*
X3619048Y2250256D01*
X3619648Y2249456D01*
X3620048Y2248523D01*
X3620248Y2247456D01*
Y2246390D01*
X3620048Y2245323D01*
X3619648Y2244390D01*
X3619048Y2243590D01*
X3618348Y2243056D01*
X3617548Y2242923D01*
G01X3623248D02*
Y2250923D01*
X3627848Y2242923D01*
Y2250923D01*
G01X3631048Y2242923D02*
X3633548Y2250923D01*
X3636048Y2242923D01*
G01X3635148Y2245723D02*
X3631948D01*
G01X3639548Y2250923D02*
Y2242923D01*
X3643548D01*
G01X3655548D02*
Y2250923D01*
X3657948D01*
X3658748Y2250523D01*
X3659348Y2249590D01*
X3659548Y2248523D01*
X3659348Y2247456D01*
X3658848Y2246656D01*
X3657948Y2246256D01*
X3655548D01*
G01X3663048Y2242923D02*
X3665548Y2250923D01*
X3668048Y2242923D01*
G01X3667148Y2245723D02*
X3663948D01*
G01X3671348Y2242923D02*
Y2250923D01*
X3673348D01*
X3674148Y2250523D01*
X3674748Y2249990D01*
X3675248Y2249190D01*
X3675648Y2248256D01*
X3675748Y2246923D01*
X3675648Y2245590D01*
X3675248Y2244656D01*
X3674748Y2243856D01*
X3674148Y2243323D01*
X3673348Y2242923D01*
X3671348D01*
G01X3687448Y2243989D02*
X3688248Y2243323D01*
X3689148Y2242923D01*
X3689948D01*
X3690748Y2243323D01*
X3691348Y2243989D01*
X3691648Y2244923D01*
X3691448Y2245856D01*
X3690948Y2246656D01*
X3690048Y2247190D01*
X3688848Y2247456D01*
X3688148Y2247990D01*
X3687848Y2248923D01*
X3688048Y2249856D01*
X3688548Y2250523D01*
X3689248Y2250923D01*
X3689948D01*
X3690648Y2250656D01*
X3691248Y2249990D01*
G01X3696348Y2250923D02*
X3698748D01*
G01X3697548D02*
Y2242923D01*
G01X3696348D02*
X3698748D01*
G01X3703648Y2250923D02*
X3707448D01*
X3703648Y2242923D01*
X3707448D01*
G01X3715548D02*
X3711548D01*
Y2250923D01*
X3715548D01*
G01X3713948Y2247056D02*
X3711548D01*
G01X3728348Y2250923D02*
X3730748D01*
G01X3729548D02*
Y2242923D01*
G01X3728348D02*
X3730748D01*
G01X3735448Y2243989D02*
X3736248Y2243323D01*
X3737148Y2242923D01*
X3737948D01*
X3738748Y2243323D01*
X3739348Y2243989D01*
X3739648Y2244923D01*
X3739448Y2245856D01*
X3738948Y2246656D01*
X3738048Y2247190D01*
X3736848Y2247456D01*
X3736148Y2247990D01*
X3735848Y2248923D01*
X3736048Y2249856D01*
X3736548Y2250523D01*
X3737248Y2250923D01*
X3737948D01*
X3738648Y2250656D01*
X3739248Y2249990D01*
G01X3753548Y2250923D02*
Y2242923D01*
G01X3751248Y2250923D02*
X3755848D01*
G01X3759448Y2242923D02*
Y2250923D01*
G01X3763648D02*
Y2242923D01*
G01Y2246923D02*
X3759448D01*
G01X3771548Y2242923D02*
X3767548D01*
Y2250923D01*
X3771548D01*
G01X3769948Y2247056D02*
X3767548D01*
G01X3783548Y2242923D02*
Y2250923D01*
X3785948D01*
X3786748Y2250523D01*
X3787348Y2249590D01*
X3787548Y2248523D01*
X3787348Y2247456D01*
X3786848Y2246656D01*
X3785948Y2246256D01*
X3783548D01*
G01X3791548Y2242923D02*
Y2250923D01*
X3794048D01*
X3794848Y2250523D01*
X3795348Y2249990D01*
X3795548Y2248923D01*
X3795348Y2247856D01*
X3794748Y2247190D01*
X3794048Y2246790D01*
X3791548D01*
G01X3794048D02*
X3795548Y2242923D01*
G01X3801548D02*
X3800748Y2243056D01*
X3800048Y2243590D01*
X3799448Y2244390D01*
X3799048Y2245323D01*
X3798848Y2246390D01*
Y2247456D01*
X3799048Y2248523D01*
X3799448Y2249456D01*
X3800048Y2250256D01*
X3800748Y2250790D01*
X3801548Y2250923D01*
X3802348Y2250790D01*
X3803048Y2250256D01*
X3803648Y2249456D01*
X3804048Y2248523D01*
X3804248Y2247456D01*
Y2246390D01*
X3804048Y2245323D01*
X3803648Y2244390D01*
X3803048Y2243590D01*
X3802348Y2243056D01*
X3801548Y2242923D01*
G01X3807648D02*
Y2250923D01*
X3811448D01*
G01X3810048Y2247056D02*
X3807648D01*
G01X3816348Y2250923D02*
X3818748D01*
G01X3817548D02*
Y2242923D01*
G01X3816348D02*
X3818748D01*
G01X3823548Y2250923D02*
Y2242923D01*
X3827548D01*
G01X3835548D02*
X3831548D01*
Y2250923D01*
X3835548D01*
G01X3833948Y2247056D02*
X3831548D01*
G01X3847448Y2243989D02*
X3848248Y2243323D01*
X3849148Y2242923D01*
X3849948D01*
X3850748Y2243323D01*
X3851348Y2243989D01*
X3851648Y2244923D01*
X3851448Y2245856D01*
X3850948Y2246656D01*
X3850048Y2247190D01*
X3848848Y2247456D01*
X3848148Y2247990D01*
X3847848Y2248923D01*
X3848048Y2249856D01*
X3848548Y2250523D01*
X3849248Y2250923D01*
X3849948D01*
X3850648Y2250656D01*
X3851248Y2249990D01*
G01X3856348Y2250923D02*
X3858748D01*
G01X3857548D02*
Y2242923D01*
G01X3856348D02*
X3858748D01*
G01X3863648Y2250923D02*
X3867448D01*
X3863648Y2242923D01*
X3867448D01*
G01X3875548D02*
X3871548D01*
Y2250923D01*
X3875548D01*
G01X3873948Y2247056D02*
X3871548D01*
G01X3888448Y2245590D02*
X3890848D01*
G01X3889548Y2247323D02*
Y2243856D01*
G01X3903648Y2249590D02*
X3904248Y2250390D01*
X3904948Y2250790D01*
X3905748Y2250923D01*
X3906748Y2250656D01*
X3907448Y2249990D01*
X3907648Y2249190D01*
X3907548Y2248389D01*
X3907148Y2247723D01*
X3905148Y2246390D01*
X3904248Y2245456D01*
X3903648Y2244123D01*
X3903448Y2242923D01*
X3907648D01*
G01X3913548Y2250923D02*
X3912748Y2250656D01*
X3912148Y2249990D01*
X3911748Y2249190D01*
X3911448Y2248123D01*
X3911348Y2246923D01*
X3911448Y2245723D01*
X3911748Y2244656D01*
X3912148Y2243856D01*
X3912748Y2243190D01*
X3913548Y2242923D01*
X3914348Y2243190D01*
X3914948Y2243856D01*
X3915348Y2244656D01*
X3915648Y2245723D01*
X3915748Y2246923D01*
X3915648Y2248123D01*
X3915348Y2249190D01*
X3914948Y2249990D01*
X3914348Y2250656D01*
X3913548Y2250923D01*
G01X3918948Y2242923D02*
Y2250923D01*
X3921548Y2244256D01*
X3924148Y2250923D01*
Y2242923D01*
G01X3928348Y2250923D02*
X3930748D01*
G01X3929548D02*
Y2242923D01*
G01X3928348D02*
X3930748D01*
G01X3935548Y2250923D02*
Y2242923D01*
X3939548D01*
G01X3167048Y2257923D02*
X3169548Y2265923D01*
X3172048Y2257923D01*
G01X3171148Y2260723D02*
X3167948D01*
G01X3177548Y2257656D02*
X3177348Y2257790D01*
Y2258056D01*
X3177548Y2258190D01*
X3177748Y2258056D01*
Y2257790D01*
X3177548Y2257656D01*
G01X3184348Y2265923D02*
X3186748D01*
G01X3185548D02*
Y2257923D01*
G01X3184348D02*
X3186748D01*
G01X3191648D02*
Y2265923D01*
X3195448D01*
G01X3194048Y2262056D02*
X3191648D01*
G01X3209548Y2265923D02*
Y2257923D01*
G01X3207248Y2265923D02*
X3211848D01*
G01X3215448Y2257923D02*
Y2265923D01*
G01X3219648D02*
Y2257923D01*
G01Y2261923D02*
X3215448D01*
G01X3227548Y2257923D02*
X3223548D01*
Y2265923D01*
X3227548D01*
G01X3225948Y2262056D02*
X3223548D01*
G01X3239548Y2257923D02*
Y2265923D01*
X3241948D01*
X3242748Y2265523D01*
X3243348Y2264590D01*
X3243548Y2263523D01*
X3243348Y2262456D01*
X3242848Y2261656D01*
X3241948Y2261256D01*
X3239548D01*
G01X3249548Y2265923D02*
Y2257923D01*
G01X3247248Y2265923D02*
X3251848D01*
G01X3255448Y2257923D02*
Y2265923D01*
G01X3259648D02*
Y2257923D01*
G01Y2261923D02*
X3255448D01*
G01X3273548Y2265923D02*
Y2257923D01*
G01X3271248Y2265923D02*
X3275848D01*
G01X3281548Y2257923D02*
X3280748Y2258056D01*
X3280048Y2258590D01*
X3279448Y2259390D01*
X3279048Y2260323D01*
X3278848Y2261390D01*
Y2262456D01*
X3279048Y2263523D01*
X3279448Y2264456D01*
X3280048Y2265256D01*
X3280748Y2265790D01*
X3281548Y2265923D01*
X3282348Y2265790D01*
X3283048Y2265256D01*
X3283648Y2264456D01*
X3284048Y2263523D01*
X3284248Y2262456D01*
Y2261390D01*
X3284048Y2260323D01*
X3283648Y2259390D01*
X3283048Y2258590D01*
X3282348Y2258056D01*
X3281548Y2257923D01*
G01X3289548D02*
X3288748Y2258056D01*
X3288048Y2258590D01*
X3287448Y2259390D01*
X3287048Y2260323D01*
X3286848Y2261390D01*
Y2262456D01*
X3287048Y2263523D01*
X3287448Y2264456D01*
X3288048Y2265256D01*
X3288748Y2265790D01*
X3289548Y2265923D01*
X3290348Y2265790D01*
X3291048Y2265256D01*
X3291648Y2264456D01*
X3292048Y2263523D01*
X3292248Y2262456D01*
Y2261390D01*
X3292048Y2260323D01*
X3291648Y2259390D01*
X3291048Y2258590D01*
X3290348Y2258056D01*
X3289548Y2257923D01*
G01X3295548Y2265923D02*
Y2257923D01*
X3299548D01*
G01X3304348Y2265923D02*
X3306748D01*
G01X3305548D02*
Y2257923D01*
G01X3304348D02*
X3306748D01*
G01X3311248D02*
Y2265923D01*
X3315848Y2257923D01*
Y2265923D01*
G01X3322148Y2261923D02*
X3324148D01*
Y2259523D01*
X3323548Y2258723D01*
X3322848Y2258190D01*
X3321848Y2257923D01*
X3320848Y2258190D01*
X3320148Y2258723D01*
X3319548Y2259523D01*
X3319148Y2260456D01*
X3318948Y2261523D01*
Y2262456D01*
X3319148Y2263256D01*
X3319548Y2264190D01*
X3320148Y2264990D01*
X3320748Y2265523D01*
X3321548Y2265923D01*
X3322248D01*
X3323048Y2265656D01*
X3323648Y2265123D01*
G01X3335448Y2257923D02*
Y2265923D01*
G01X3339648D02*
Y2257923D01*
G01Y2261923D02*
X3335448D01*
G01X3345548Y2257923D02*
X3344748Y2258056D01*
X3344048Y2258590D01*
X3343448Y2259390D01*
X3343048Y2260323D01*
X3342848Y2261390D01*
Y2262456D01*
X3343048Y2263523D01*
X3343448Y2264456D01*
X3344048Y2265256D01*
X3344748Y2265790D01*
X3345548Y2265923D01*
X3346348Y2265790D01*
X3347048Y2265256D01*
X3347648Y2264456D01*
X3348048Y2263523D01*
X3348248Y2262456D01*
Y2261390D01*
X3348048Y2260323D01*
X3347648Y2259390D01*
X3347048Y2258590D01*
X3346348Y2258056D01*
X3345548Y2257923D01*
G01X3351548Y2265923D02*
Y2257923D01*
X3355548D01*
G01X3363548D02*
X3359548D01*
Y2265923D01*
X3363548D01*
G01X3361948Y2262056D02*
X3359548D01*
G01X3376348Y2265923D02*
X3378748D01*
G01X3377548D02*
Y2257923D01*
G01X3376348D02*
X3378748D01*
G01X3383448Y2258989D02*
X3384248Y2258323D01*
X3385148Y2257923D01*
X3385948D01*
X3386748Y2258323D01*
X3387348Y2258989D01*
X3387648Y2259923D01*
X3387448Y2260856D01*
X3386948Y2261656D01*
X3386048Y2262190D01*
X3384848Y2262456D01*
X3384148Y2262990D01*
X3383848Y2263923D01*
X3384048Y2264856D01*
X3384548Y2265523D01*
X3385248Y2265923D01*
X3385948D01*
X3386648Y2265656D01*
X3387248Y2264990D01*
G01X3398948Y2257923D02*
Y2265923D01*
X3401548Y2259256D01*
X3404148Y2265923D01*
Y2257923D01*
G01X3407048D02*
X3409548Y2265923D01*
X3412048Y2257923D01*
G01X3411148Y2260723D02*
X3407948D01*
G01X3415348Y2257923D02*
Y2265923D01*
X3417348D01*
X3418148Y2265523D01*
X3418748Y2264990D01*
X3419248Y2264190D01*
X3419648Y2263256D01*
X3419748Y2261923D01*
X3419648Y2260590D01*
X3419248Y2259656D01*
X3418748Y2258856D01*
X3418148Y2258323D01*
X3417348Y2257923D01*
X3415348D01*
G01X3427548D02*
X3423548D01*
Y2265923D01*
X3427548D01*
G01X3425948Y2262056D02*
X3423548D01*
G01X3442348Y2262190D02*
X3442748Y2262590D01*
X3443048Y2263256D01*
X3443248Y2264190D01*
X3443048Y2264990D01*
X3442648Y2265523D01*
X3441948Y2265923D01*
X3439248D01*
Y2257923D01*
X3442548D01*
X3443248Y2258456D01*
X3443648Y2259256D01*
X3443848Y2260190D01*
X3443648Y2261123D01*
X3443048Y2261923D01*
X3442348Y2262190D01*
X3439248D01*
G01X3449548Y2257923D02*
Y2261523D01*
X3447548Y2265923D01*
G01X3451548D02*
X3449548Y2261523D01*
G01X3463348Y2257923D02*
Y2265923D01*
X3465348D01*
X3466148Y2265523D01*
X3466748Y2264990D01*
X3467248Y2264190D01*
X3467648Y2263256D01*
X3467748Y2261923D01*
X3467648Y2260590D01*
X3467248Y2259656D01*
X3466748Y2258856D01*
X3466148Y2258323D01*
X3465348Y2257923D01*
X3463348D01*
G01X3471548D02*
Y2265923D01*
X3474048D01*
X3474848Y2265523D01*
X3475348Y2264990D01*
X3475548Y2263923D01*
X3475348Y2262856D01*
X3474748Y2262190D01*
X3474048Y2261790D01*
X3471548D01*
G01X3474048D02*
X3475548Y2257923D01*
G01X3480348Y2265923D02*
X3482748D01*
G01X3481548D02*
Y2257923D01*
G01X3480348D02*
X3482748D01*
G01X3487548Y2265923D02*
Y2257923D01*
X3491548D01*
G01X3495548Y2265923D02*
Y2257923D01*
X3499548D01*
G01X3504348Y2265923D02*
X3506748D01*
G01X3505548D02*
Y2257923D01*
G01X3504348D02*
X3506748D01*
G01X3511248D02*
Y2265923D01*
X3515848Y2257923D01*
Y2265923D01*
G01X3522148Y2261923D02*
X3524148D01*
Y2259523D01*
X3523548Y2258723D01*
X3522848Y2258190D01*
X3521848Y2257923D01*
X3520848Y2258190D01*
X3520148Y2258723D01*
X3519548Y2259523D01*
X3519148Y2260456D01*
X3518948Y2261523D01*
Y2262456D01*
X3519148Y2263256D01*
X3519548Y2264190D01*
X3520148Y2264990D01*
X3520748Y2265523D01*
X3521548Y2265923D01*
X3522248D01*
X3523048Y2265656D01*
X3523648Y2265123D01*
G01X3529348Y2256456D02*
X3529748Y2258190D01*
G01X3543248Y2257923D02*
Y2265923D01*
X3547848Y2257923D01*
Y2265923D01*
G01X3553548Y2257923D02*
X3552748Y2258056D01*
X3552048Y2258590D01*
X3551448Y2259390D01*
X3551048Y2260323D01*
X3550848Y2261390D01*
Y2262456D01*
X3551048Y2263523D01*
X3551448Y2264456D01*
X3552048Y2265256D01*
X3552748Y2265790D01*
X3553548Y2265923D01*
X3554348Y2265790D01*
X3555048Y2265256D01*
X3555648Y2264456D01*
X3556048Y2263523D01*
X3556248Y2262456D01*
Y2261390D01*
X3556048Y2260323D01*
X3555648Y2259390D01*
X3555048Y2258590D01*
X3554348Y2258056D01*
X3553548Y2257923D01*
G01X3559248D02*
Y2265923D01*
X3563848Y2257923D01*
Y2265923D01*
G01X3568248Y2260590D02*
X3570848D01*
G01X3575648Y2257923D02*
Y2265923D01*
X3579448D01*
G01X3578048Y2262056D02*
X3575648D01*
G01X3583348Y2265923D02*
Y2260190D01*
X3583748Y2258989D01*
X3584548Y2258190D01*
X3585548Y2257923D01*
X3586548Y2258190D01*
X3587348Y2258989D01*
X3587748Y2260190D01*
Y2265923D01*
G01X3591248Y2257923D02*
Y2265923D01*
X3595848Y2257923D01*
Y2265923D01*
G01X3603748Y2265256D02*
X3603148Y2265656D01*
X3602448Y2265923D01*
X3601648D01*
X3600748Y2265523D01*
X3600048Y2264856D01*
X3599548Y2264056D01*
X3599148Y2262723D01*
X3599048Y2261523D01*
X3599248Y2260323D01*
X3599548Y2259523D01*
X3600148Y2258723D01*
X3600848Y2258190D01*
X3601548Y2257923D01*
X3602248D01*
X3602948Y2258190D01*
X3603548Y2258590D01*
X3604048Y2259123D01*
G01X3609548Y2265923D02*
Y2257923D01*
G01X3607248Y2265923D02*
X3611848D01*
G01X3616348D02*
X3618748D01*
G01X3617548D02*
Y2257923D01*
G01X3616348D02*
X3618748D01*
G01X3625548D02*
X3624748Y2258056D01*
X3624048Y2258590D01*
X3623448Y2259390D01*
X3623048Y2260323D01*
X3622848Y2261390D01*
Y2262456D01*
X3623048Y2263523D01*
X3623448Y2264456D01*
X3624048Y2265256D01*
X3624748Y2265790D01*
X3625548Y2265923D01*
X3626348Y2265790D01*
X3627048Y2265256D01*
X3627648Y2264456D01*
X3628048Y2263523D01*
X3628248Y2262456D01*
Y2261390D01*
X3628048Y2260323D01*
X3627648Y2259390D01*
X3627048Y2258590D01*
X3626348Y2258056D01*
X3625548Y2257923D01*
G01X3631248D02*
Y2265923D01*
X3635848Y2257923D01*
Y2265923D01*
G01X3639048Y2257923D02*
X3641548Y2265923D01*
X3644048Y2257923D01*
G01X3643148Y2260723D02*
X3639948D01*
G01X3647548Y2265923D02*
Y2257923D01*
X3651548D01*
G01X3663548D02*
Y2265923D01*
X3665948D01*
X3666748Y2265523D01*
X3667348Y2264590D01*
X3667548Y2263523D01*
X3667348Y2262456D01*
X3666848Y2261656D01*
X3665948Y2261256D01*
X3663548D01*
G01X3671048Y2257923D02*
X3673548Y2265923D01*
X3676048Y2257923D01*
G01X3675148Y2260723D02*
X3671948D01*
G01X3679348Y2257923D02*
Y2265923D01*
X3681348D01*
X3682148Y2265523D01*
X3682748Y2264990D01*
X3683248Y2264190D01*
X3683648Y2263256D01*
X3683748Y2261923D01*
X3683648Y2260590D01*
X3683248Y2259656D01*
X3682748Y2258856D01*
X3682148Y2258323D01*
X3681348Y2257923D01*
X3679348D01*
G01X3695448Y2258989D02*
X3696248Y2258323D01*
X3697148Y2257923D01*
X3697948D01*
X3698748Y2258323D01*
X3699348Y2258989D01*
X3699648Y2259923D01*
X3699448Y2260856D01*
X3698948Y2261656D01*
X3698048Y2262190D01*
X3696848Y2262456D01*
X3696148Y2262990D01*
X3695848Y2263923D01*
X3696048Y2264856D01*
X3696548Y2265523D01*
X3697248Y2265923D01*
X3697948D01*
X3698648Y2265656D01*
X3699248Y2264990D01*
G01X3704348Y2265923D02*
X3706748D01*
G01X3705548D02*
Y2257923D01*
G01X3704348D02*
X3706748D01*
G01X3711648Y2265923D02*
X3715448D01*
X3711648Y2257923D01*
X3715448D01*
G01X3723548D02*
X3719548D01*
Y2265923D01*
X3723548D01*
G01X3721948Y2262056D02*
X3719548D01*
G01X3736348Y2265923D02*
X3738748D01*
G01X3737548D02*
Y2257923D01*
G01X3736348D02*
X3738748D01*
G01X3743448Y2258989D02*
X3744248Y2258323D01*
X3745148Y2257923D01*
X3745948D01*
X3746748Y2258323D01*
X3747348Y2258989D01*
X3747648Y2259923D01*
X3747448Y2260856D01*
X3746948Y2261656D01*
X3746048Y2262190D01*
X3744848Y2262456D01*
X3744148Y2262990D01*
X3743848Y2263923D01*
X3744048Y2264856D01*
X3744548Y2265523D01*
X3745248Y2265923D01*
X3745948D01*
X3746648Y2265656D01*
X3747248Y2264990D01*
G01X3761548Y2265923D02*
Y2257923D01*
G01X3759248Y2265923D02*
X3763848D01*
G01X3767448Y2257923D02*
Y2265923D01*
G01X3771648D02*
Y2257923D01*
G01Y2261923D02*
X3767448D01*
G01X3779548Y2257923D02*
X3775548D01*
Y2265923D01*
X3779548D01*
G01X3777948Y2262056D02*
X3775548D01*
G01X3791348Y2257923D02*
Y2265923D01*
X3793348D01*
X3794148Y2265523D01*
X3794748Y2264990D01*
X3795248Y2264190D01*
X3795648Y2263256D01*
X3795748Y2261923D01*
X3795648Y2260590D01*
X3795248Y2259656D01*
X3794748Y2258856D01*
X3794148Y2258323D01*
X3793348Y2257923D01*
X3791348D01*
G01X3799548D02*
Y2265923D01*
X3802048D01*
X3802848Y2265523D01*
X3803348Y2264990D01*
X3803548Y2263923D01*
X3803348Y2262856D01*
X3802748Y2262190D01*
X3802048Y2261790D01*
X3799548D01*
G01X3802048D02*
X3803548Y2257923D01*
G01X3808348Y2265923D02*
X3810748D01*
G01X3809548D02*
Y2257923D01*
G01X3808348D02*
X3810748D01*
G01X3815548Y2265923D02*
Y2257923D01*
X3819548D01*
G01X3823548Y2265923D02*
Y2257923D01*
X3827548D01*
G01X3839448Y2258989D02*
X3840248Y2258323D01*
X3841148Y2257923D01*
X3841948D01*
X3842748Y2258323D01*
X3843348Y2258989D01*
X3843648Y2259923D01*
X3843448Y2260856D01*
X3842948Y2261656D01*
X3842048Y2262190D01*
X3840848Y2262456D01*
X3840148Y2262990D01*
X3839848Y2263923D01*
X3840048Y2264856D01*
X3840548Y2265523D01*
X3841248Y2265923D01*
X3841948D01*
X3842648Y2265656D01*
X3843248Y2264990D01*
G01X3848348Y2265923D02*
X3850748D01*
G01X3849548D02*
Y2257923D01*
G01X3848348D02*
X3850748D01*
G01X3855648Y2265923D02*
X3859448D01*
X3855648Y2257923D01*
X3859448D01*
G01X3867548D02*
X3863548D01*
Y2265923D01*
X3867548D01*
G01X3865948Y2262056D02*
X3863548D01*
G01X3880448Y2260590D02*
X3882848D01*
G01X3881548Y2262323D02*
Y2258856D01*
G01X3897548Y2257923D02*
Y2265923D01*
X3896348Y2264323D01*
G01Y2257923D02*
X3898748D01*
G01X3905548Y2265923D02*
X3904748Y2265656D01*
X3904148Y2264990D01*
X3903748Y2264190D01*
X3903448Y2263123D01*
X3903348Y2261923D01*
X3903448Y2260723D01*
X3903748Y2259656D01*
X3904148Y2258856D01*
X3904748Y2258190D01*
X3905548Y2257923D01*
X3906348Y2258190D01*
X3906948Y2258856D01*
X3907348Y2259656D01*
X3907648Y2260723D01*
X3907748Y2261923D01*
X3907648Y2263123D01*
X3907348Y2264190D01*
X3906948Y2264990D01*
X3906348Y2265656D01*
X3905548Y2265923D01*
G01X3910948Y2257923D02*
Y2265923D01*
X3913548Y2259256D01*
X3916148Y2265923D01*
Y2257923D01*
G01X3920348Y2265923D02*
X3922748D01*
G01X3921548D02*
Y2257923D01*
G01X3920348D02*
X3922748D01*
G01X3927548Y2265923D02*
Y2257923D01*
X3931548D01*
G01X3160148Y2366923D02*
X3162148D01*
Y2364523D01*
X3161548Y2363723D01*
X3160848Y2363190D01*
X3159848Y2362923D01*
X3158848Y2363190D01*
X3158148Y2363723D01*
X3157548Y2364523D01*
X3157148Y2365456D01*
X3156948Y2366523D01*
Y2367456D01*
X3157148Y2368256D01*
X3157548Y2369190D01*
X3158148Y2369990D01*
X3158748Y2370523D01*
X3159548Y2370923D01*
X3160248D01*
X3161048Y2370656D01*
X3161648Y2370123D01*
G01X3165548Y2362923D02*
Y2370923D01*
X3168048D01*
X3168848Y2370523D01*
X3169348Y2369990D01*
X3169548Y2368923D01*
X3169348Y2367856D01*
X3168748Y2367190D01*
X3168048Y2366790D01*
X3165548D01*
G01X3168048D02*
X3169548Y2362923D01*
G01X3175548D02*
X3174748Y2363056D01*
X3174048Y2363590D01*
X3173448Y2364390D01*
X3173048Y2365323D01*
X3172848Y2366390D01*
Y2367456D01*
X3173048Y2368523D01*
X3173448Y2369456D01*
X3174048Y2370256D01*
X3174748Y2370790D01*
X3175548Y2370923D01*
X3176348Y2370790D01*
X3177048Y2370256D01*
X3177648Y2369456D01*
X3178048Y2368523D01*
X3178248Y2367456D01*
Y2366390D01*
X3178048Y2365323D01*
X3177648Y2364390D01*
X3177048Y2363590D01*
X3176348Y2363056D01*
X3175548Y2362923D01*
G01X3181348Y2370923D02*
Y2365190D01*
X3181748Y2363989D01*
X3182548Y2363190D01*
X3183548Y2362923D01*
X3184548Y2363190D01*
X3185348Y2363989D01*
X3185748Y2365190D01*
Y2370923D01*
G01X3189548Y2362923D02*
Y2370923D01*
X3191948D01*
X3192748Y2370523D01*
X3193348Y2369590D01*
X3193548Y2368523D01*
X3193348Y2367456D01*
X3192848Y2366656D01*
X3191948Y2366256D01*
X3189548D01*
G01X3197448Y2363989D02*
X3198248Y2363323D01*
X3199148Y2362923D01*
X3199948D01*
X3200748Y2363323D01*
X3201348Y2363989D01*
X3201648Y2364923D01*
X3201448Y2365856D01*
X3200948Y2366656D01*
X3200048Y2367190D01*
X3198848Y2367456D01*
X3198148Y2367990D01*
X3197848Y2368923D01*
X3198048Y2369856D01*
X3198548Y2370523D01*
X3199248Y2370923D01*
X3199948D01*
X3200648Y2370656D01*
X3201248Y2369990D01*
G01X3213048Y2362923D02*
X3215548Y2370923D01*
X3218048Y2362923D01*
G01X3217148Y2365723D02*
X3213948D01*
G01X3229048Y2362923D02*
X3231548Y2370923D01*
X3234048Y2362923D01*
G01X3233148Y2365723D02*
X3229948D01*
G01X3237248Y2362923D02*
Y2370923D01*
X3241848Y2362923D01*
Y2370923D01*
G01X3245348Y2362923D02*
Y2370923D01*
X3247348D01*
X3248148Y2370523D01*
X3248748Y2369990D01*
X3249248Y2369190D01*
X3249648Y2368256D01*
X3249748Y2366923D01*
X3249648Y2365590D01*
X3249248Y2364656D01*
X3248748Y2363856D01*
X3248148Y2363323D01*
X3247348Y2362923D01*
X3245348D01*
G01X3264348Y2367190D02*
X3264748Y2367590D01*
X3265048Y2368256D01*
X3265248Y2369190D01*
X3265048Y2369990D01*
X3264648Y2370523D01*
X3263948Y2370923D01*
X3261248D01*
Y2362923D01*
X3264548D01*
X3265248Y2363456D01*
X3265648Y2364256D01*
X3265848Y2365190D01*
X3265648Y2366123D01*
X3265048Y2366923D01*
X3264348Y2367190D01*
X3261248D01*
G01X3271348Y2361456D02*
X3271748Y2363190D01*
G01X3279548Y2370923D02*
Y2362923D01*
G01X3277248Y2370923D02*
X3281848D01*
G01X3285448Y2362923D02*
Y2370923D01*
G01X3289648D02*
Y2362923D01*
G01Y2366923D02*
X3285448D01*
G01X3297548Y2362923D02*
X3293548D01*
Y2370923D01*
X3297548D01*
G01X3295948Y2367056D02*
X3293548D01*
G01X3301248Y2362923D02*
Y2370923D01*
X3305848Y2362923D01*
Y2370923D01*
G01X3320148Y2366923D02*
X3322148D01*
Y2364523D01*
X3321548Y2363723D01*
X3320848Y2363190D01*
X3319848Y2362923D01*
X3318848Y2363190D01*
X3318148Y2363723D01*
X3317548Y2364523D01*
X3317148Y2365456D01*
X3316948Y2366523D01*
Y2367456D01*
X3317148Y2368256D01*
X3317548Y2369190D01*
X3318148Y2369990D01*
X3318748Y2370523D01*
X3319548Y2370923D01*
X3320248D01*
X3321048Y2370656D01*
X3321648Y2370123D01*
G01X3325548Y2362923D02*
Y2370923D01*
X3328048D01*
X3328848Y2370523D01*
X3329348Y2369990D01*
X3329548Y2368923D01*
X3329348Y2367856D01*
X3328748Y2367190D01*
X3328048Y2366790D01*
X3325548D01*
G01X3328048D02*
X3329548Y2362923D01*
G01X3335548D02*
X3334748Y2363056D01*
X3334048Y2363590D01*
X3333448Y2364390D01*
X3333048Y2365323D01*
X3332848Y2366390D01*
Y2367456D01*
X3333048Y2368523D01*
X3333448Y2369456D01*
X3334048Y2370256D01*
X3334748Y2370790D01*
X3335548Y2370923D01*
X3336348Y2370790D01*
X3337048Y2370256D01*
X3337648Y2369456D01*
X3338048Y2368523D01*
X3338248Y2367456D01*
Y2366390D01*
X3338048Y2365323D01*
X3337648Y2364390D01*
X3337048Y2363590D01*
X3336348Y2363056D01*
X3335548Y2362923D01*
G01X3341348Y2370923D02*
Y2365190D01*
X3341748Y2363989D01*
X3342548Y2363190D01*
X3343548Y2362923D01*
X3344548Y2363190D01*
X3345348Y2363989D01*
X3345748Y2365190D01*
Y2370923D01*
G01X3349548Y2362923D02*
Y2370923D01*
X3351948D01*
X3352748Y2370523D01*
X3353348Y2369590D01*
X3353548Y2368523D01*
X3353348Y2367456D01*
X3352848Y2366656D01*
X3351948Y2366256D01*
X3349548D01*
G01X3365048Y2362923D02*
X3367548Y2370923D01*
X3370048Y2362923D01*
G01X3369148Y2365723D02*
X3365948D01*
G01X3385748Y2370256D02*
X3385148Y2370656D01*
X3384448Y2370923D01*
X3383648D01*
X3382748Y2370523D01*
X3382048Y2369856D01*
X3381548Y2369056D01*
X3381148Y2367723D01*
X3381048Y2366523D01*
X3381248Y2365323D01*
X3381548Y2364523D01*
X3382148Y2363723D01*
X3382848Y2363190D01*
X3383548Y2362923D01*
X3384248D01*
X3384948Y2363190D01*
X3385548Y2363590D01*
X3386048Y2364123D01*
G01X3389048Y2362923D02*
X3391548Y2370923D01*
X3394048Y2362923D01*
G01X3393148Y2365723D02*
X3389948D01*
G01X3397248Y2362923D02*
Y2370923D01*
X3401848Y2362923D01*
Y2370923D01*
G01X3416348Y2367190D02*
X3416748Y2367590D01*
X3417048Y2368256D01*
X3417248Y2369190D01*
X3417048Y2369990D01*
X3416648Y2370523D01*
X3415948Y2370923D01*
X3413248D01*
Y2362923D01*
X3416548D01*
X3417248Y2363456D01*
X3417648Y2364256D01*
X3417848Y2365190D01*
X3417648Y2366123D01*
X3417048Y2366923D01*
X3416348Y2367190D01*
X3413248D01*
G01X3425548Y2362923D02*
X3421548D01*
Y2370923D01*
X3425548D01*
G01X3423948Y2367056D02*
X3421548D01*
G01X3437548Y2362923D02*
Y2370923D01*
X3439948D01*
X3440748Y2370523D01*
X3441348Y2369590D01*
X3441548Y2368523D01*
X3441348Y2367456D01*
X3440848Y2366656D01*
X3439948Y2366256D01*
X3437548D01*
G01X3445548Y2370923D02*
Y2362923D01*
X3449548D01*
G01X3453048D02*
X3455548Y2370923D01*
X3458048Y2362923D01*
G01X3457148Y2365723D02*
X3453948D01*
G01X3465748Y2370256D02*
X3465148Y2370656D01*
X3464448Y2370923D01*
X3463648D01*
X3462748Y2370523D01*
X3462048Y2369856D01*
X3461548Y2369056D01*
X3461148Y2367723D01*
X3461048Y2366523D01*
X3461248Y2365323D01*
X3461548Y2364523D01*
X3462148Y2363723D01*
X3462848Y2363190D01*
X3463548Y2362923D01*
X3464248D01*
X3464948Y2363190D01*
X3465548Y2363590D01*
X3466048Y2364123D01*
G01X3473548Y2362923D02*
X3469548D01*
Y2370923D01*
X3473548D01*
G01X3471948Y2367056D02*
X3469548D01*
G01X3477348Y2362923D02*
Y2370923D01*
X3479348D01*
X3480148Y2370523D01*
X3480748Y2369990D01*
X3481248Y2369190D01*
X3481648Y2368256D01*
X3481748Y2366923D01*
X3481648Y2365590D01*
X3481248Y2364656D01*
X3480748Y2363856D01*
X3480148Y2363323D01*
X3479348Y2362923D01*
X3477348D01*
G01X3493448Y2363989D02*
X3494248Y2363323D01*
X3495148Y2362923D01*
X3495948D01*
X3496748Y2363323D01*
X3497348Y2363989D01*
X3497648Y2364923D01*
X3497448Y2365856D01*
X3496948Y2366656D01*
X3496048Y2367190D01*
X3494848Y2367456D01*
X3494148Y2367990D01*
X3493848Y2368923D01*
X3494048Y2369856D01*
X3494548Y2370523D01*
X3495248Y2370923D01*
X3495948D01*
X3496648Y2370656D01*
X3497248Y2369990D01*
G01X3505548Y2362923D02*
X3501548D01*
Y2370923D01*
X3505548D01*
G01X3503948Y2367056D02*
X3501548D01*
G01X3509548Y2362923D02*
Y2370923D01*
X3511948D01*
X3512748Y2370523D01*
X3513348Y2369590D01*
X3513548Y2368523D01*
X3513348Y2367456D01*
X3512848Y2366656D01*
X3511948Y2366256D01*
X3509548D01*
G01X3517048Y2362923D02*
X3519548Y2370923D01*
X3522048Y2362923D01*
G01X3521148Y2365723D02*
X3517948D01*
G01X3525548Y2362923D02*
Y2370923D01*
X3528048D01*
X3528848Y2370523D01*
X3529348Y2369990D01*
X3529548Y2368923D01*
X3529348Y2367856D01*
X3528748Y2367190D01*
X3528048Y2366790D01*
X3525548D01*
G01X3528048D02*
X3529548Y2362923D01*
G01X3533048D02*
X3535548Y2370923D01*
X3538048Y2362923D01*
G01X3537148Y2365723D02*
X3533948D01*
G01X3543548Y2370923D02*
Y2362923D01*
G01X3541248Y2370923D02*
X3545848D01*
G01X3553548Y2362923D02*
X3549548D01*
Y2370923D01*
X3553548D01*
G01X3551948Y2367056D02*
X3549548D01*
G01X3557548Y2370923D02*
Y2362923D01*
X3561548D01*
G01X3567548D02*
Y2366523D01*
X3565548Y2370923D01*
G01X3569548D02*
X3567548Y2366523D01*
G01X3581648Y2362923D02*
Y2370923D01*
X3585448D01*
G01X3584048Y2367056D02*
X3581648D01*
G01X3589548Y2362923D02*
Y2370923D01*
X3592048D01*
X3592848Y2370523D01*
X3593348Y2369990D01*
X3593548Y2368923D01*
X3593348Y2367856D01*
X3592748Y2367190D01*
X3592048Y2366790D01*
X3589548D01*
G01X3592048D02*
X3593548Y2362923D01*
G01X3599548D02*
X3598748Y2363056D01*
X3598048Y2363590D01*
X3597448Y2364390D01*
X3597048Y2365323D01*
X3596848Y2366390D01*
Y2367456D01*
X3597048Y2368523D01*
X3597448Y2369456D01*
X3598048Y2370256D01*
X3598748Y2370790D01*
X3599548Y2370923D01*
X3600348Y2370790D01*
X3601048Y2370256D01*
X3601648Y2369456D01*
X3602048Y2368523D01*
X3602248Y2367456D01*
Y2366390D01*
X3602048Y2365323D01*
X3601648Y2364390D01*
X3601048Y2363590D01*
X3600348Y2363056D01*
X3599548Y2362923D01*
G01X3604948D02*
Y2370923D01*
X3607548Y2364256D01*
X3610148Y2370923D01*
Y2362923D01*
G01X3624148Y2366923D02*
X3626148D01*
Y2364523D01*
X3625548Y2363723D01*
X3624848Y2363190D01*
X3623848Y2362923D01*
X3622848Y2363190D01*
X3622148Y2363723D01*
X3621548Y2364523D01*
X3621148Y2365456D01*
X3620948Y2366523D01*
Y2367456D01*
X3621148Y2368256D01*
X3621548Y2369190D01*
X3622148Y2369990D01*
X3622748Y2370523D01*
X3623548Y2370923D01*
X3624248D01*
X3625048Y2370656D01*
X3625648Y2370123D01*
G01X3629548Y2362923D02*
Y2370923D01*
X3632048D01*
X3632848Y2370523D01*
X3633348Y2369990D01*
X3633548Y2368923D01*
X3633348Y2367856D01*
X3632748Y2367190D01*
X3632048Y2366790D01*
X3629548D01*
G01X3632048D02*
X3633548Y2362923D01*
G01X3639548D02*
X3638748Y2363056D01*
X3638048Y2363590D01*
X3637448Y2364390D01*
X3637048Y2365323D01*
X3636848Y2366390D01*
Y2367456D01*
X3637048Y2368523D01*
X3637448Y2369456D01*
X3638048Y2370256D01*
X3638748Y2370790D01*
X3639548Y2370923D01*
X3640348Y2370790D01*
X3641048Y2370256D01*
X3641648Y2369456D01*
X3642048Y2368523D01*
X3642248Y2367456D01*
Y2366390D01*
X3642048Y2365323D01*
X3641648Y2364390D01*
X3641048Y2363590D01*
X3640348Y2363056D01*
X3639548Y2362923D01*
G01X3645348Y2370923D02*
Y2365190D01*
X3645748Y2363989D01*
X3646548Y2363190D01*
X3647548Y2362923D01*
X3648548Y2363190D01*
X3649348Y2363989D01*
X3649748Y2365190D01*
Y2370923D01*
G01X3653548Y2362923D02*
Y2370923D01*
X3655948D01*
X3656748Y2370523D01*
X3657348Y2369590D01*
X3657548Y2368523D01*
X3657348Y2367456D01*
X3656848Y2366656D01*
X3655948Y2366256D01*
X3653548D01*
G01X3672348Y2367190D02*
X3672748Y2367590D01*
X3673048Y2368256D01*
X3673248Y2369190D01*
X3673048Y2369990D01*
X3672648Y2370523D01*
X3671948Y2370923D01*
X3669248D01*
Y2362923D01*
X3672548D01*
X3673248Y2363456D01*
X3673648Y2364256D01*
X3673848Y2365190D01*
X3673648Y2366123D01*
X3673048Y2366923D01*
X3672348Y2367190D01*
X3669248D01*
G01X3679548Y2362656D02*
X3679348Y2362790D01*
Y2363056D01*
X3679548Y2363190D01*
X3679748Y2363056D01*
Y2362790D01*
X3679548Y2362656D01*
G01X3159548Y2385923D02*
Y2377923D01*
G01X3157248Y2385923D02*
X3161848D01*
G01X3167548Y2377923D02*
X3166748Y2378056D01*
X3166048Y2378590D01*
X3165448Y2379390D01*
X3165048Y2380323D01*
X3164848Y2381390D01*
Y2382456D01*
X3165048Y2383523D01*
X3165448Y2384456D01*
X3166048Y2385256D01*
X3166748Y2385790D01*
X3167548Y2385923D01*
X3168348Y2385790D01*
X3169048Y2385256D01*
X3169648Y2384456D01*
X3170048Y2383523D01*
X3170248Y2382456D01*
Y2381390D01*
X3170048Y2380323D01*
X3169648Y2379390D01*
X3169048Y2378590D01*
X3168348Y2378056D01*
X3167548Y2377923D01*
G01X3183548Y2385923D02*
Y2377923D01*
G01X3181248Y2385923D02*
X3185848D01*
G01X3189448Y2377923D02*
Y2385923D01*
G01X3193648D02*
Y2377923D01*
G01Y2381923D02*
X3189448D01*
G01X3201548Y2377923D02*
X3197548D01*
Y2385923D01*
X3201548D01*
G01X3199948Y2382056D02*
X3197548D01*
G01X3216348Y2382190D02*
X3216748Y2382590D01*
X3217048Y2383256D01*
X3217248Y2384190D01*
X3217048Y2384990D01*
X3216648Y2385523D01*
X3215948Y2385923D01*
X3213248D01*
Y2377923D01*
X3216548D01*
X3217248Y2378456D01*
X3217648Y2379256D01*
X3217848Y2380190D01*
X3217648Y2381123D01*
X3217048Y2381923D01*
X3216348Y2382190D01*
X3213248D01*
G01X3223548Y2377923D02*
X3222748Y2378056D01*
X3222048Y2378590D01*
X3221448Y2379390D01*
X3221048Y2380323D01*
X3220848Y2381390D01*
Y2382456D01*
X3221048Y2383523D01*
X3221448Y2384456D01*
X3222048Y2385256D01*
X3222748Y2385790D01*
X3223548Y2385923D01*
X3224348Y2385790D01*
X3225048Y2385256D01*
X3225648Y2384456D01*
X3226048Y2383523D01*
X3226248Y2382456D01*
Y2381390D01*
X3226048Y2380323D01*
X3225648Y2379390D01*
X3225048Y2378590D01*
X3224348Y2378056D01*
X3223548Y2377923D01*
G01X3229048D02*
X3231548Y2385923D01*
X3234048Y2377923D01*
G01X3233148Y2380723D02*
X3229948D01*
G01X3237548Y2377923D02*
Y2385923D01*
X3240048D01*
X3240848Y2385523D01*
X3241348Y2384990D01*
X3241548Y2383923D01*
X3241348Y2382856D01*
X3240748Y2382190D01*
X3240048Y2381790D01*
X3237548D01*
G01X3240048D02*
X3241548Y2377923D01*
G01X3245348D02*
Y2385923D01*
X3247348D01*
X3248148Y2385523D01*
X3248748Y2384990D01*
X3249248Y2384190D01*
X3249648Y2383256D01*
X3249748Y2381923D01*
X3249648Y2380590D01*
X3249248Y2379656D01*
X3248748Y2378856D01*
X3248148Y2378323D01*
X3247348Y2377923D01*
X3245348D01*
G01X3265748Y2385256D02*
X3265148Y2385656D01*
X3264448Y2385923D01*
X3263648D01*
X3262748Y2385523D01*
X3262048Y2384856D01*
X3261548Y2384056D01*
X3261148Y2382723D01*
X3261048Y2381523D01*
X3261248Y2380323D01*
X3261548Y2379523D01*
X3262148Y2378723D01*
X3262848Y2378190D01*
X3263548Y2377923D01*
X3264248D01*
X3264948Y2378190D01*
X3265548Y2378590D01*
X3266048Y2379123D01*
G01X3271548Y2377923D02*
X3270748Y2378056D01*
X3270048Y2378590D01*
X3269448Y2379390D01*
X3269048Y2380323D01*
X3268848Y2381390D01*
Y2382456D01*
X3269048Y2383523D01*
X3269448Y2384456D01*
X3270048Y2385256D01*
X3270748Y2385790D01*
X3271548Y2385923D01*
X3272348Y2385790D01*
X3273048Y2385256D01*
X3273648Y2384456D01*
X3274048Y2383523D01*
X3274248Y2382456D01*
Y2381390D01*
X3274048Y2380323D01*
X3273648Y2379390D01*
X3273048Y2378590D01*
X3272348Y2378056D01*
X3271548Y2377923D01*
G01X3277348Y2385923D02*
Y2380190D01*
X3277748Y2378989D01*
X3278548Y2378190D01*
X3279548Y2377923D01*
X3280548Y2378190D01*
X3281348Y2378989D01*
X3281748Y2380190D01*
Y2385923D01*
G01X3285548Y2377923D02*
Y2385923D01*
X3287948D01*
X3288748Y2385523D01*
X3289348Y2384590D01*
X3289548Y2383523D01*
X3289348Y2382456D01*
X3288848Y2381656D01*
X3287948Y2381256D01*
X3285548D01*
G01X3295548Y2377923D02*
X3294748Y2378056D01*
X3294048Y2378590D01*
X3293448Y2379390D01*
X3293048Y2380323D01*
X3292848Y2381390D01*
Y2382456D01*
X3293048Y2383523D01*
X3293448Y2384456D01*
X3294048Y2385256D01*
X3294748Y2385790D01*
X3295548Y2385923D01*
X3296348Y2385790D01*
X3297048Y2385256D01*
X3297648Y2384456D01*
X3298048Y2383523D01*
X3298248Y2382456D01*
Y2381390D01*
X3298048Y2380323D01*
X3297648Y2379390D01*
X3297048Y2378590D01*
X3296348Y2378056D01*
X3295548Y2377923D01*
G01X3301248D02*
Y2385923D01*
X3305848Y2377923D01*
Y2385923D01*
G01X3309448Y2378989D02*
X3310248Y2378323D01*
X3311148Y2377923D01*
X3311948D01*
X3312748Y2378323D01*
X3313348Y2378989D01*
X3313648Y2379923D01*
X3313448Y2380856D01*
X3312948Y2381656D01*
X3312048Y2382190D01*
X3310848Y2382456D01*
X3310148Y2382990D01*
X3309848Y2383923D01*
X3310048Y2384856D01*
X3310548Y2385523D01*
X3311248Y2385923D01*
X3311948D01*
X3312648Y2385656D01*
X3313248Y2384990D01*
G01X3319548Y2377656D02*
X3319348Y2377790D01*
Y2378056D01*
X3319548Y2378190D01*
X3319748Y2378056D01*
Y2377790D01*
X3319548Y2377656D01*
G01X3326348Y2385923D02*
X3328748D01*
G01X3327548D02*
Y2377923D01*
G01X3326348D02*
X3328748D01*
G01X3333648D02*
Y2385923D01*
X3337448D01*
G01X3336048Y2382056D02*
X3333648D01*
G01X3350348Y2385923D02*
X3352748D01*
G01X3351548D02*
Y2377923D01*
G01X3350348D02*
X3352748D01*
G01X3359548Y2385923D02*
Y2377923D01*
G01X3357248Y2385923D02*
X3361848D01*
G01X3374348D02*
X3376748D01*
G01X3375548D02*
Y2377923D01*
G01X3374348D02*
X3376748D01*
G01X3381448Y2378989D02*
X3382248Y2378323D01*
X3383148Y2377923D01*
X3383948D01*
X3384748Y2378323D01*
X3385348Y2378989D01*
X3385648Y2379923D01*
X3385448Y2380856D01*
X3384948Y2381656D01*
X3384048Y2382190D01*
X3382848Y2382456D01*
X3382148Y2382990D01*
X3381848Y2383923D01*
X3382048Y2384856D01*
X3382548Y2385523D01*
X3383248Y2385923D01*
X3383948D01*
X3384648Y2385656D01*
X3385248Y2384990D01*
G01X3397248Y2377923D02*
Y2385923D01*
X3401848Y2377923D01*
Y2385923D01*
G01X3407548Y2377923D02*
X3406748Y2378056D01*
X3406048Y2378590D01*
X3405448Y2379390D01*
X3405048Y2380323D01*
X3404848Y2381390D01*
Y2382456D01*
X3405048Y2383523D01*
X3405448Y2384456D01*
X3406048Y2385256D01*
X3406748Y2385790D01*
X3407548Y2385923D01*
X3408348Y2385790D01*
X3409048Y2385256D01*
X3409648Y2384456D01*
X3410048Y2383523D01*
X3410248Y2382456D01*
Y2381390D01*
X3410048Y2380323D01*
X3409648Y2379390D01*
X3409048Y2378590D01*
X3408348Y2378056D01*
X3407548Y2377923D01*
G01X3415548Y2385923D02*
Y2377923D01*
G01X3413248Y2385923D02*
X3417848D01*
G01X3429548Y2377923D02*
Y2385923D01*
X3431948D01*
X3432748Y2385523D01*
X3433348Y2384590D01*
X3433548Y2383523D01*
X3433348Y2382456D01*
X3432848Y2381656D01*
X3431948Y2381256D01*
X3429548D01*
G01X3439548Y2377923D02*
X3438748Y2378056D01*
X3438048Y2378590D01*
X3437448Y2379390D01*
X3437048Y2380323D01*
X3436848Y2381390D01*
Y2382456D01*
X3437048Y2383523D01*
X3437448Y2384456D01*
X3438048Y2385256D01*
X3438748Y2385790D01*
X3439548Y2385923D01*
X3440348Y2385790D01*
X3441048Y2385256D01*
X3441648Y2384456D01*
X3442048Y2383523D01*
X3442248Y2382456D01*
Y2381390D01*
X3442048Y2380323D01*
X3441648Y2379390D01*
X3441048Y2378590D01*
X3440348Y2378056D01*
X3439548Y2377923D01*
G01X3445448Y2378989D02*
X3446248Y2378323D01*
X3447148Y2377923D01*
X3447948D01*
X3448748Y2378323D01*
X3449348Y2378989D01*
X3449648Y2379923D01*
X3449448Y2380856D01*
X3448948Y2381656D01*
X3448048Y2382190D01*
X3446848Y2382456D01*
X3446148Y2382990D01*
X3445848Y2383923D01*
X3446048Y2384856D01*
X3446548Y2385523D01*
X3447248Y2385923D01*
X3447948D01*
X3448648Y2385656D01*
X3449248Y2384990D01*
G01X3453448Y2378989D02*
X3454248Y2378323D01*
X3455148Y2377923D01*
X3455948D01*
X3456748Y2378323D01*
X3457348Y2378989D01*
X3457648Y2379923D01*
X3457448Y2380856D01*
X3456948Y2381656D01*
X3456048Y2382190D01*
X3454848Y2382456D01*
X3454148Y2382990D01*
X3453848Y2383923D01*
X3454048Y2384856D01*
X3454548Y2385523D01*
X3455248Y2385923D01*
X3455948D01*
X3456648Y2385656D01*
X3457248Y2384990D01*
G01X3462348Y2385923D02*
X3464748D01*
G01X3463548D02*
Y2377923D01*
G01X3462348D02*
X3464748D01*
G01X3472348Y2382190D02*
X3472748Y2382590D01*
X3473048Y2383256D01*
X3473248Y2384190D01*
X3473048Y2384990D01*
X3472648Y2385523D01*
X3471948Y2385923D01*
X3469248D01*
Y2377923D01*
X3472548D01*
X3473248Y2378456D01*
X3473648Y2379256D01*
X3473848Y2380190D01*
X3473648Y2381123D01*
X3473048Y2381923D01*
X3472348Y2382190D01*
X3469248D01*
G01X3477548Y2385923D02*
Y2377923D01*
X3481548D01*
G01X3489548D02*
X3485548D01*
Y2385923D01*
X3489548D01*
G01X3487948Y2382056D02*
X3485548D01*
G01X3503548Y2385923D02*
Y2377923D01*
G01X3501248Y2385923D02*
X3505848D01*
G01X3511548Y2377923D02*
X3510748Y2378056D01*
X3510048Y2378590D01*
X3509448Y2379390D01*
X3509048Y2380323D01*
X3508848Y2381390D01*
Y2382456D01*
X3509048Y2383523D01*
X3509448Y2384456D01*
X3510048Y2385256D01*
X3510748Y2385790D01*
X3511548Y2385923D01*
X3512348Y2385790D01*
X3513048Y2385256D01*
X3513648Y2384456D01*
X3514048Y2383523D01*
X3514248Y2382456D01*
Y2381390D01*
X3514048Y2380323D01*
X3513648Y2379390D01*
X3513048Y2378590D01*
X3512348Y2378056D01*
X3511548Y2377923D01*
G01X3525648D02*
Y2385923D01*
X3529448D01*
G01X3528048Y2382056D02*
X3525648D01*
G01X3534348Y2385923D02*
X3536748D01*
G01X3535548D02*
Y2377923D01*
G01X3534348D02*
X3536748D01*
G01X3543548Y2385923D02*
Y2377923D01*
G01X3541248Y2385923D02*
X3545848D01*
G01X3558348D02*
X3560748D01*
G01X3559548D02*
Y2377923D01*
G01X3558348D02*
X3560748D01*
G01X3565248D02*
Y2385923D01*
X3569848Y2377923D01*
Y2385923D01*
G01X3583548D02*
Y2377923D01*
G01X3581248Y2385923D02*
X3585848D01*
G01X3589448Y2377923D02*
Y2385923D01*
G01X3593648D02*
Y2377923D01*
G01Y2381923D02*
X3589448D01*
G01X3601548Y2377923D02*
X3597548D01*
Y2385923D01*
X3601548D01*
G01X3599948Y2382056D02*
X3597548D01*
G01X3613548Y2385923D02*
Y2377923D01*
X3617548D01*
G01X3623548D02*
X3622748Y2378056D01*
X3622048Y2378590D01*
X3621448Y2379390D01*
X3621048Y2380323D01*
X3620848Y2381390D01*
Y2382456D01*
X3621048Y2383523D01*
X3621448Y2384456D01*
X3622048Y2385256D01*
X3622748Y2385790D01*
X3623548Y2385923D01*
X3624348Y2385790D01*
X3625048Y2385256D01*
X3625648Y2384456D01*
X3626048Y2383523D01*
X3626248Y2382456D01*
Y2381390D01*
X3626048Y2380323D01*
X3625648Y2379390D01*
X3625048Y2378590D01*
X3624348Y2378056D01*
X3623548Y2377923D01*
G01X3633748Y2385256D02*
X3633148Y2385656D01*
X3632448Y2385923D01*
X3631648D01*
X3630748Y2385523D01*
X3630048Y2384856D01*
X3629548Y2384056D01*
X3629148Y2382723D01*
X3629048Y2381523D01*
X3629248Y2380323D01*
X3629548Y2379523D01*
X3630148Y2378723D01*
X3630848Y2378190D01*
X3631548Y2377923D01*
X3632248D01*
X3632948Y2378190D01*
X3633548Y2378590D01*
X3634048Y2379123D01*
G01X3637048Y2377923D02*
X3639548Y2385923D01*
X3642048Y2377923D01*
G01X3641148Y2380723D02*
X3637948D01*
G01X3647548Y2385923D02*
Y2377923D01*
G01X3645248Y2385923D02*
X3649848D01*
G01X3654348D02*
X3656748D01*
G01X3655548D02*
Y2377923D01*
G01X3654348D02*
X3656748D01*
G01X3663548D02*
X3662748Y2378056D01*
X3662048Y2378590D01*
X3661448Y2379390D01*
X3661048Y2380323D01*
X3660848Y2381390D01*
Y2382456D01*
X3661048Y2383523D01*
X3661448Y2384456D01*
X3662048Y2385256D01*
X3662748Y2385790D01*
X3663548Y2385923D01*
X3664348Y2385790D01*
X3665048Y2385256D01*
X3665648Y2384456D01*
X3666048Y2383523D01*
X3666248Y2382456D01*
Y2381390D01*
X3666048Y2380323D01*
X3665648Y2379390D01*
X3665048Y2378590D01*
X3664348Y2378056D01*
X3663548Y2377923D01*
G01X3669248D02*
Y2385923D01*
X3673848Y2377923D01*
Y2385923D01*
G01X3677448Y2378989D02*
X3678248Y2378323D01*
X3679148Y2377923D01*
X3679948D01*
X3680748Y2378323D01*
X3681348Y2378989D01*
X3681648Y2379923D01*
X3681448Y2380856D01*
X3680948Y2381656D01*
X3680048Y2382190D01*
X3678848Y2382456D01*
X3678148Y2382990D01*
X3677848Y2383923D01*
X3678048Y2384856D01*
X3678548Y2385523D01*
X3679248Y2385923D01*
X3679948D01*
X3680648Y2385656D01*
X3681248Y2384990D01*
G01X3693648Y2377923D02*
Y2385923D01*
X3697448D01*
G01X3696048Y2382056D02*
X3693648D01*
G01X3703548Y2377923D02*
X3702748Y2378056D01*
X3702048Y2378590D01*
X3701448Y2379390D01*
X3701048Y2380323D01*
X3700848Y2381390D01*
Y2382456D01*
X3701048Y2383523D01*
X3701448Y2384456D01*
X3702048Y2385256D01*
X3702748Y2385790D01*
X3703548Y2385923D01*
X3704348Y2385790D01*
X3705048Y2385256D01*
X3705648Y2384456D01*
X3706048Y2383523D01*
X3706248Y2382456D01*
Y2381390D01*
X3706048Y2380323D01*
X3705648Y2379390D01*
X3705048Y2378590D01*
X3704348Y2378056D01*
X3703548Y2377923D01*
G01X3709548D02*
Y2385923D01*
X3712048D01*
X3712848Y2385523D01*
X3713348Y2384990D01*
X3713548Y2383923D01*
X3713348Y2382856D01*
X3712748Y2382190D01*
X3712048Y2381790D01*
X3709548D01*
G01X3712048D02*
X3713548Y2377923D01*
G01X3728348Y2382190D02*
X3728748Y2382590D01*
X3729048Y2383256D01*
X3729248Y2384190D01*
X3729048Y2384990D01*
X3728648Y2385523D01*
X3727948Y2385923D01*
X3725248D01*
Y2377923D01*
X3728548D01*
X3729248Y2378456D01*
X3729648Y2379256D01*
X3729848Y2380190D01*
X3729648Y2381123D01*
X3729048Y2381923D01*
X3728348Y2382190D01*
X3725248D01*
G01X3735548Y2377923D02*
X3734748Y2378056D01*
X3734048Y2378590D01*
X3733448Y2379390D01*
X3733048Y2380323D01*
X3732848Y2381390D01*
Y2382456D01*
X3733048Y2383523D01*
X3733448Y2384456D01*
X3734048Y2385256D01*
X3734748Y2385790D01*
X3735548Y2385923D01*
X3736348Y2385790D01*
X3737048Y2385256D01*
X3737648Y2384456D01*
X3738048Y2383523D01*
X3738248Y2382456D01*
Y2381390D01*
X3738048Y2380323D01*
X3737648Y2379390D01*
X3737048Y2378590D01*
X3736348Y2378056D01*
X3735548Y2377923D01*
G01X3743548Y2385923D02*
Y2377923D01*
G01X3741248Y2385923D02*
X3745848D01*
G01X3749448Y2377923D02*
Y2385923D01*
G01X3753648D02*
Y2377923D01*
G01Y2381923D02*
X3749448D01*
G01X3157548Y2392923D02*
Y2400923D01*
X3159948D01*
X3160748Y2400523D01*
X3161348Y2399590D01*
X3161548Y2398523D01*
X3161348Y2397456D01*
X3160848Y2396656D01*
X3159948Y2396256D01*
X3157548D01*
G01X3165548Y2400923D02*
Y2392923D01*
X3169548D01*
G01X3177548D02*
X3173548D01*
Y2400923D01*
X3177548D01*
G01X3175948Y2397056D02*
X3173548D01*
G01X3181048Y2392923D02*
X3183548Y2400923D01*
X3186048Y2392923D01*
G01X3185148Y2395723D02*
X3181948D01*
G01X3189448Y2393989D02*
X3190248Y2393323D01*
X3191148Y2392923D01*
X3191948D01*
X3192748Y2393323D01*
X3193348Y2393989D01*
X3193648Y2394923D01*
X3193448Y2395856D01*
X3192948Y2396656D01*
X3192048Y2397190D01*
X3190848Y2397456D01*
X3190148Y2397990D01*
X3189848Y2398923D01*
X3190048Y2399856D01*
X3190548Y2400523D01*
X3191248Y2400923D01*
X3191948D01*
X3192648Y2400656D01*
X3193248Y2399990D01*
G01X3201548Y2392923D02*
X3197548D01*
Y2400923D01*
X3201548D01*
G01X3199948Y2397056D02*
X3197548D01*
G01X3213648Y2392923D02*
Y2400923D01*
X3217448D01*
G01X3216048Y2397056D02*
X3213648D01*
G01X3223548Y2392923D02*
X3222748Y2393056D01*
X3222048Y2393590D01*
X3221448Y2394390D01*
X3221048Y2395323D01*
X3220848Y2396390D01*
Y2397456D01*
X3221048Y2398523D01*
X3221448Y2399456D01*
X3222048Y2400256D01*
X3222748Y2400790D01*
X3223548Y2400923D01*
X3224348Y2400790D01*
X3225048Y2400256D01*
X3225648Y2399456D01*
X3226048Y2398523D01*
X3226248Y2397456D01*
Y2396390D01*
X3226048Y2395323D01*
X3225648Y2394390D01*
X3225048Y2393590D01*
X3224348Y2393056D01*
X3223548Y2392923D01*
G01X3229548Y2400923D02*
Y2392923D01*
X3233548D01*
G01X3237548Y2400923D02*
Y2392923D01*
X3241548D01*
G01X3247548D02*
X3246748Y2393056D01*
X3246048Y2393590D01*
X3245448Y2394390D01*
X3245048Y2395323D01*
X3244848Y2396390D01*
Y2397456D01*
X3245048Y2398523D01*
X3245448Y2399456D01*
X3246048Y2400256D01*
X3246748Y2400790D01*
X3247548Y2400923D01*
X3248348Y2400790D01*
X3249048Y2400256D01*
X3249648Y2399456D01*
X3250048Y2398523D01*
X3250248Y2397456D01*
Y2396390D01*
X3250048Y2395323D01*
X3249648Y2394390D01*
X3249048Y2393590D01*
X3248348Y2393056D01*
X3247548Y2392923D01*
G01X3252548Y2400923D02*
X3253948Y2392923D01*
X3255548Y2400923D01*
X3257148Y2392923D01*
X3258548Y2400923D01*
G01X3271548D02*
Y2392923D01*
G01X3269248Y2400923D02*
X3273848D01*
G01X3277448Y2392923D02*
Y2400923D01*
G01X3281648D02*
Y2392923D01*
G01Y2396923D02*
X3277448D01*
G01X3289548Y2392923D02*
X3285548D01*
Y2400923D01*
X3289548D01*
G01X3287948Y2397056D02*
X3285548D01*
G01X3301448Y2393989D02*
X3302248Y2393323D01*
X3303148Y2392923D01*
X3303948D01*
X3304748Y2393323D01*
X3305348Y2393989D01*
X3305648Y2394923D01*
X3305448Y2395856D01*
X3304948Y2396656D01*
X3304048Y2397190D01*
X3302848Y2397456D01*
X3302148Y2397990D01*
X3301848Y2398923D01*
X3302048Y2399856D01*
X3302548Y2400523D01*
X3303248Y2400923D01*
X3303948D01*
X3304648Y2400656D01*
X3305248Y2399990D01*
G01X3309548Y2400923D02*
Y2392923D01*
X3313548D01*
G01X3318348Y2400923D02*
X3320748D01*
G01X3319548D02*
Y2392923D01*
G01X3318348D02*
X3320748D01*
G01X3325348D02*
Y2400923D01*
X3327348D01*
X3328148Y2400523D01*
X3328748Y2399990D01*
X3329248Y2399190D01*
X3329648Y2398256D01*
X3329748Y2396923D01*
X3329648Y2395590D01*
X3329248Y2394656D01*
X3328748Y2393856D01*
X3328148Y2393323D01*
X3327348Y2392923D01*
X3325348D01*
G01X3337548D02*
X3333548D01*
Y2400923D01*
X3337548D01*
G01X3335948Y2397056D02*
X3333548D01*
G01X3341448Y2393989D02*
X3342248Y2393323D01*
X3343148Y2392923D01*
X3343948D01*
X3344748Y2393323D01*
X3345348Y2393989D01*
X3345648Y2394923D01*
X3345448Y2395856D01*
X3344948Y2396656D01*
X3344048Y2397190D01*
X3342848Y2397456D01*
X3342148Y2397990D01*
X3341848Y2398923D01*
X3342048Y2399856D01*
X3342548Y2400523D01*
X3343248Y2400923D01*
X3343948D01*
X3344648Y2400656D01*
X3345248Y2399990D01*
G01X3359548Y2400923D02*
Y2392923D01*
G01X3357248Y2400923D02*
X3361848D01*
G01X3367548Y2392923D02*
X3366748Y2393056D01*
X3366048Y2393590D01*
X3365448Y2394390D01*
X3365048Y2395323D01*
X3364848Y2396390D01*
Y2397456D01*
X3365048Y2398523D01*
X3365448Y2399456D01*
X3366048Y2400256D01*
X3366748Y2400790D01*
X3367548Y2400923D01*
X3368348Y2400790D01*
X3369048Y2400256D01*
X3369648Y2399456D01*
X3370048Y2398523D01*
X3370248Y2397456D01*
Y2396390D01*
X3370048Y2395323D01*
X3369648Y2394390D01*
X3369048Y2393590D01*
X3368348Y2393056D01*
X3367548Y2392923D01*
G01X3384148Y2396923D02*
X3386148D01*
Y2394523D01*
X3385548Y2393723D01*
X3384848Y2393190D01*
X3383848Y2392923D01*
X3382848Y2393190D01*
X3382148Y2393723D01*
X3381548Y2394523D01*
X3381148Y2395456D01*
X3380948Y2396523D01*
Y2397456D01*
X3381148Y2398256D01*
X3381548Y2399190D01*
X3382148Y2399990D01*
X3382748Y2400523D01*
X3383548Y2400923D01*
X3384248D01*
X3385048Y2400656D01*
X3385648Y2400123D01*
G01X3393548Y2392923D02*
X3389548D01*
Y2400923D01*
X3393548D01*
G01X3391948Y2397056D02*
X3389548D01*
G01X3397248Y2392923D02*
Y2400923D01*
X3401848Y2392923D01*
Y2400923D01*
G01X3409548Y2392923D02*
X3405548D01*
Y2400923D01*
X3409548D01*
G01X3407948Y2397056D02*
X3405548D01*
G01X3413548Y2392923D02*
Y2400923D01*
X3416048D01*
X3416848Y2400523D01*
X3417348Y2399990D01*
X3417548Y2398923D01*
X3417348Y2397856D01*
X3416748Y2397190D01*
X3416048Y2396790D01*
X3413548D01*
G01X3416048D02*
X3417548Y2392923D01*
G01X3421048D02*
X3423548Y2400923D01*
X3426048Y2392923D01*
G01X3425148Y2395723D02*
X3421948D01*
G01X3431548Y2400923D02*
Y2392923D01*
G01X3429248Y2400923D02*
X3433848D01*
G01X3441548Y2392923D02*
X3437548D01*
Y2400923D01*
X3441548D01*
G01X3439948Y2397056D02*
X3437548D01*
G01X3455548Y2400923D02*
Y2392923D01*
G01X3453248Y2400923D02*
X3457848D01*
G01X3461448Y2392923D02*
Y2400923D01*
G01X3465648D02*
Y2392923D01*
G01Y2396923D02*
X3461448D01*
G01X3473548Y2392923D02*
X3469548D01*
Y2400923D01*
X3473548D01*
G01X3471948Y2397056D02*
X3469548D01*
G01X3485548Y2392923D02*
Y2400923D01*
X3487948D01*
X3488748Y2400523D01*
X3489348Y2399590D01*
X3489548Y2398523D01*
X3489348Y2397456D01*
X3488848Y2396656D01*
X3487948Y2396256D01*
X3485548D01*
G01X3493048Y2392923D02*
X3495548Y2400923D01*
X3498048Y2392923D01*
G01X3497148Y2395723D02*
X3493948D01*
G01X3501348Y2392923D02*
Y2400923D01*
X3503348D01*
X3504148Y2400523D01*
X3504748Y2399990D01*
X3505248Y2399190D01*
X3505648Y2398256D01*
X3505748Y2396923D01*
X3505648Y2395590D01*
X3505248Y2394656D01*
X3504748Y2393856D01*
X3504148Y2393323D01*
X3503348Y2392923D01*
X3501348D01*
G01X3509448Y2393989D02*
X3510248Y2393323D01*
X3511148Y2392923D01*
X3511948D01*
X3512748Y2393323D01*
X3513348Y2393989D01*
X3513648Y2394923D01*
X3513448Y2395856D01*
X3512948Y2396656D01*
X3512048Y2397190D01*
X3510848Y2397456D01*
X3510148Y2397990D01*
X3509848Y2398923D01*
X3510048Y2399856D01*
X3510548Y2400523D01*
X3511248Y2400923D01*
X3511948D01*
X3512648Y2400656D01*
X3513248Y2399990D01*
G01X3525048Y2392923D02*
X3527548Y2400923D01*
X3530048Y2392923D01*
G01X3529148Y2395723D02*
X3525948D01*
G01X3533248Y2392923D02*
Y2400923D01*
X3537848Y2392923D01*
Y2400923D01*
G01X3541348Y2392923D02*
Y2400923D01*
X3543348D01*
X3544148Y2400523D01*
X3544748Y2399990D01*
X3545248Y2399190D01*
X3545648Y2398256D01*
X3545748Y2396923D01*
X3545648Y2395590D01*
X3545248Y2394656D01*
X3544748Y2393856D01*
X3544148Y2393323D01*
X3543348Y2392923D01*
X3541348D01*
G01X3556948D02*
Y2400923D01*
X3559548Y2394256D01*
X3562148Y2400923D01*
Y2392923D01*
G01X3565048D02*
X3567548Y2400923D01*
X3570048Y2392923D01*
G01X3569148Y2395723D02*
X3565948D01*
G01X3573448Y2393989D02*
X3574248Y2393323D01*
X3575148Y2392923D01*
X3575948D01*
X3576748Y2393323D01*
X3577348Y2393989D01*
X3577648Y2394923D01*
X3577448Y2395856D01*
X3576948Y2396656D01*
X3576048Y2397190D01*
X3574848Y2397456D01*
X3574148Y2397990D01*
X3573848Y2398923D01*
X3574048Y2399856D01*
X3574548Y2400523D01*
X3575248Y2400923D01*
X3575948D01*
X3576648Y2400656D01*
X3577248Y2399990D01*
G01X3581348Y2392923D02*
Y2400923D01*
G01X3585148D02*
X3581348Y2395989D01*
G01X3585748Y2392923D02*
X3583048Y2398256D01*
G01X3597048Y2392923D02*
X3599548Y2400923D01*
X3602048Y2392923D01*
G01X3601148Y2395723D02*
X3597948D01*
G01X3605248Y2392923D02*
Y2400923D01*
X3609848Y2392923D01*
Y2400923D01*
G01X3613348Y2392923D02*
Y2400923D01*
X3615348D01*
X3616148Y2400523D01*
X3616748Y2399990D01*
X3617248Y2399190D01*
X3617648Y2398256D01*
X3617748Y2396923D01*
X3617648Y2395590D01*
X3617248Y2394656D01*
X3616748Y2393856D01*
X3616148Y2393323D01*
X3615348Y2392923D01*
X3613348D01*
G01X3629048D02*
X3631548Y2400923D01*
X3634048Y2392923D01*
G01X3633148Y2395723D02*
X3629948D01*
G01X3637348Y2392923D02*
Y2400923D01*
X3639348D01*
X3640148Y2400523D01*
X3640748Y2399990D01*
X3641248Y2399190D01*
X3641648Y2398256D01*
X3641748Y2396923D01*
X3641648Y2395590D01*
X3641248Y2394656D01*
X3640748Y2393856D01*
X3640148Y2393323D01*
X3639348Y2392923D01*
X3637348D01*
G01X3645348D02*
Y2400923D01*
X3647348D01*
X3648148Y2400523D01*
X3648748Y2399990D01*
X3649248Y2399190D01*
X3649648Y2398256D01*
X3649748Y2396923D01*
X3649648Y2395590D01*
X3649248Y2394656D01*
X3648748Y2393856D01*
X3648148Y2393323D01*
X3647348Y2392923D01*
X3645348D01*
G01X3663548Y2400923D02*
Y2392923D01*
G01X3661248Y2400923D02*
X3665848D01*
G01X3669448Y2392923D02*
Y2400923D01*
G01X3673648D02*
Y2392923D01*
G01Y2396923D02*
X3669448D01*
G01X3681548Y2392923D02*
X3677548D01*
Y2400923D01*
X3681548D01*
G01X3679948Y2397056D02*
X3677548D01*
G01X3695548Y2400923D02*
Y2392923D01*
G01X3693248Y2400923D02*
X3697848D01*
G01X3705548Y2392923D02*
X3701548D01*
Y2400923D01*
X3705548D01*
G01X3703948Y2397056D02*
X3701548D01*
G01X3709448Y2393989D02*
X3710248Y2393323D01*
X3711148Y2392923D01*
X3711948D01*
X3712748Y2393323D01*
X3713348Y2393989D01*
X3713648Y2394923D01*
X3713448Y2395856D01*
X3712948Y2396656D01*
X3712048Y2397190D01*
X3710848Y2397456D01*
X3710148Y2397990D01*
X3709848Y2398923D01*
X3710048Y2399856D01*
X3710548Y2400523D01*
X3711248Y2400923D01*
X3711948D01*
X3712648Y2400656D01*
X3713248Y2399990D01*
G01X3719548Y2400923D02*
Y2392923D01*
G01X3717248Y2400923D02*
X3721848D01*
G01X3733548Y2392923D02*
Y2400923D01*
X3735948D01*
X3736748Y2400523D01*
X3737348Y2399590D01*
X3737548Y2398523D01*
X3737348Y2397456D01*
X3736848Y2396656D01*
X3735948Y2396256D01*
X3733548D01*
G01X3741048Y2392923D02*
X3743548Y2400923D01*
X3746048Y2392923D01*
G01X3745148Y2395723D02*
X3741948D01*
G01X3749348Y2392923D02*
Y2400923D01*
X3751348D01*
X3752148Y2400523D01*
X3752748Y2399990D01*
X3753248Y2399190D01*
X3753648Y2398256D01*
X3753748Y2396923D01*
X3753648Y2395590D01*
X3753248Y2394656D01*
X3752748Y2393856D01*
X3752148Y2393323D01*
X3751348Y2392923D01*
X3749348D01*
G01X3757448Y2393989D02*
X3758248Y2393323D01*
X3759148Y2392923D01*
X3759948D01*
X3760748Y2393323D01*
X3761348Y2393989D01*
X3761648Y2394923D01*
X3761448Y2395856D01*
X3760948Y2396656D01*
X3760048Y2397190D01*
X3758848Y2397456D01*
X3758148Y2397990D01*
X3757848Y2398923D01*
X3758048Y2399856D01*
X3758548Y2400523D01*
X3759248Y2400923D01*
X3759948D01*
X3760648Y2400656D01*
X3761248Y2399990D01*
G01X3157048Y2422923D02*
X3159548Y2430923D01*
X3162048Y2422923D01*
G01X3161148Y2425723D02*
X3157948D01*
G01X3165248Y2422923D02*
Y2430923D01*
X3169848Y2422923D01*
Y2430923D01*
G01X3175548Y2422923D02*
Y2426523D01*
X3173548Y2430923D01*
G01X3177548D02*
X3175548Y2426523D01*
G01X3189548Y2422923D02*
Y2430923D01*
X3191948D01*
X3192748Y2430523D01*
X3193348Y2429590D01*
X3193548Y2428523D01*
X3193348Y2427456D01*
X3192848Y2426656D01*
X3191948Y2426256D01*
X3189548D01*
G01X3197548Y2422923D02*
Y2430923D01*
X3200048D01*
X3200848Y2430523D01*
X3201348Y2429990D01*
X3201548Y2428923D01*
X3201348Y2427856D01*
X3200748Y2427190D01*
X3200048Y2426790D01*
X3197548D01*
G01X3200048D02*
X3201548Y2422923D01*
G01X3207548D02*
X3206748Y2423056D01*
X3206048Y2423590D01*
X3205448Y2424390D01*
X3205048Y2425323D01*
X3204848Y2426390D01*
Y2427456D01*
X3205048Y2428523D01*
X3205448Y2429456D01*
X3206048Y2430256D01*
X3206748Y2430790D01*
X3207548Y2430923D01*
X3208348Y2430790D01*
X3209048Y2430256D01*
X3209648Y2429456D01*
X3210048Y2428523D01*
X3210248Y2427456D01*
Y2426390D01*
X3210048Y2425323D01*
X3209648Y2424390D01*
X3209048Y2423590D01*
X3208348Y2423056D01*
X3207548Y2422923D01*
G01X3213548D02*
Y2430923D01*
X3215948D01*
X3216748Y2430523D01*
X3217348Y2429590D01*
X3217548Y2428523D01*
X3217348Y2427456D01*
X3216848Y2426656D01*
X3215948Y2426256D01*
X3213548D01*
G01X3223548Y2422923D02*
X3222748Y2423056D01*
X3222048Y2423590D01*
X3221448Y2424390D01*
X3221048Y2425323D01*
X3220848Y2426390D01*
Y2427456D01*
X3221048Y2428523D01*
X3221448Y2429456D01*
X3222048Y2430256D01*
X3222748Y2430790D01*
X3223548Y2430923D01*
X3224348Y2430790D01*
X3225048Y2430256D01*
X3225648Y2429456D01*
X3226048Y2428523D01*
X3226248Y2427456D01*
Y2426390D01*
X3226048Y2425323D01*
X3225648Y2424390D01*
X3225048Y2423590D01*
X3224348Y2423056D01*
X3223548Y2422923D01*
G01X3229448Y2423989D02*
X3230248Y2423323D01*
X3231148Y2422923D01*
X3231948D01*
X3232748Y2423323D01*
X3233348Y2423989D01*
X3233648Y2424923D01*
X3233448Y2425856D01*
X3232948Y2426656D01*
X3232048Y2427190D01*
X3230848Y2427456D01*
X3230148Y2427990D01*
X3229848Y2428923D01*
X3230048Y2429856D01*
X3230548Y2430523D01*
X3231248Y2430923D01*
X3231948D01*
X3232648Y2430656D01*
X3233248Y2429990D01*
G01X3241548Y2422923D02*
X3237548D01*
Y2430923D01*
X3241548D01*
G01X3239948Y2427056D02*
X3237548D01*
G01X3245348Y2422923D02*
Y2430923D01*
X3247348D01*
X3248148Y2430523D01*
X3248748Y2429990D01*
X3249248Y2429190D01*
X3249648Y2428256D01*
X3249748Y2426923D01*
X3249648Y2425590D01*
X3249248Y2424656D01*
X3248748Y2423856D01*
X3248148Y2423323D01*
X3247348Y2422923D01*
X3245348D01*
G01X3265748Y2430256D02*
X3265148Y2430656D01*
X3264448Y2430923D01*
X3263648D01*
X3262748Y2430523D01*
X3262048Y2429856D01*
X3261548Y2429056D01*
X3261148Y2427723D01*
X3261048Y2426523D01*
X3261248Y2425323D01*
X3261548Y2424523D01*
X3262148Y2423723D01*
X3262848Y2423190D01*
X3263548Y2422923D01*
X3264248D01*
X3264948Y2423190D01*
X3265548Y2423590D01*
X3266048Y2424123D01*
G01X3269448Y2422923D02*
Y2430923D01*
G01X3273648D02*
Y2422923D01*
G01Y2426923D02*
X3269448D01*
G01X3277048Y2422923D02*
X3279548Y2430923D01*
X3282048Y2422923D01*
G01X3281148Y2425723D02*
X3277948D01*
G01X3285248Y2422923D02*
Y2430923D01*
X3289848Y2422923D01*
Y2430923D01*
G01X3296148Y2426923D02*
X3298148D01*
Y2424523D01*
X3297548Y2423723D01*
X3296848Y2423190D01*
X3295848Y2422923D01*
X3294848Y2423190D01*
X3294148Y2423723D01*
X3293548Y2424523D01*
X3293148Y2425456D01*
X3292948Y2426523D01*
Y2427456D01*
X3293148Y2428256D01*
X3293548Y2429190D01*
X3294148Y2429990D01*
X3294748Y2430523D01*
X3295548Y2430923D01*
X3296248D01*
X3297048Y2430656D01*
X3297648Y2430123D01*
G01X3305548Y2422923D02*
X3301548D01*
Y2430923D01*
X3305548D01*
G01X3303948Y2427056D02*
X3301548D01*
G01X3317548Y2422923D02*
Y2430923D01*
X3320048D01*
X3320848Y2430523D01*
X3321348Y2429990D01*
X3321548Y2428923D01*
X3321348Y2427856D01*
X3320748Y2427190D01*
X3320048Y2426790D01*
X3317548D01*
G01X3320048D02*
X3321548Y2422923D01*
G01X3329548D02*
X3325548D01*
Y2430923D01*
X3329548D01*
G01X3327948Y2427056D02*
X3325548D01*
G01X3335548Y2422923D02*
X3334748Y2423056D01*
X3334048Y2423590D01*
X3333448Y2424390D01*
X3333048Y2425323D01*
X3332848Y2426390D01*
Y2427456D01*
X3333048Y2428523D01*
X3333448Y2429456D01*
X3334048Y2430256D01*
X3334748Y2430790D01*
X3335548Y2430923D01*
X3336348Y2430790D01*
X3337048Y2430256D01*
X3337648Y2429456D01*
X3338048Y2428523D01*
X3338248Y2427456D01*
Y2426390D01*
X3338048Y2425323D01*
X3337648Y2424390D01*
X3337048Y2423590D01*
X3336348Y2423056D01*
X3335548Y2422923D01*
G01X3336348Y2425056D02*
X3337548Y2422923D01*
G01X3341348Y2430923D02*
Y2425190D01*
X3341748Y2423989D01*
X3342548Y2423190D01*
X3343548Y2422923D01*
X3344548Y2423190D01*
X3345348Y2423989D01*
X3345748Y2425190D01*
Y2430923D01*
G01X3353548Y2422923D02*
X3349548D01*
Y2430923D01*
X3353548D01*
G01X3351948Y2427056D02*
X3349548D01*
G01X3357448Y2423989D02*
X3358248Y2423323D01*
X3359148Y2422923D01*
X3359948D01*
X3360748Y2423323D01*
X3361348Y2423989D01*
X3361648Y2424923D01*
X3361448Y2425856D01*
X3360948Y2426656D01*
X3360048Y2427190D01*
X3358848Y2427456D01*
X3358148Y2427990D01*
X3357848Y2428923D01*
X3358048Y2429856D01*
X3358548Y2430523D01*
X3359248Y2430923D01*
X3359948D01*
X3360648Y2430656D01*
X3361248Y2429990D01*
G01X3367548Y2430923D02*
Y2422923D01*
G01X3365248Y2430923D02*
X3369848D01*
G01X3380948Y2422923D02*
Y2430923D01*
X3383548Y2424256D01*
X3386148Y2430923D01*
Y2422923D01*
G01X3389348Y2430923D02*
Y2425190D01*
X3389748Y2423989D01*
X3390548Y2423190D01*
X3391548Y2422923D01*
X3392548Y2423190D01*
X3393348Y2423989D01*
X3393748Y2425190D01*
Y2430923D01*
G01X3397448Y2423989D02*
X3398248Y2423323D01*
X3399148Y2422923D01*
X3399948D01*
X3400748Y2423323D01*
X3401348Y2423989D01*
X3401648Y2424923D01*
X3401448Y2425856D01*
X3400948Y2426656D01*
X3400048Y2427190D01*
X3398848Y2427456D01*
X3398148Y2427990D01*
X3397848Y2428923D01*
X3398048Y2429856D01*
X3398548Y2430523D01*
X3399248Y2430923D01*
X3399948D01*
X3400648Y2430656D01*
X3401248Y2429990D01*
G01X3407548Y2430923D02*
Y2422923D01*
G01X3405248Y2430923D02*
X3409848D01*
G01X3424348Y2427190D02*
X3424748Y2427590D01*
X3425048Y2428256D01*
X3425248Y2429190D01*
X3425048Y2429990D01*
X3424648Y2430523D01*
X3423948Y2430923D01*
X3421248D01*
Y2422923D01*
X3424548D01*
X3425248Y2423456D01*
X3425648Y2424256D01*
X3425848Y2425190D01*
X3425648Y2426123D01*
X3425048Y2426923D01*
X3424348Y2427190D01*
X3421248D01*
G01X3433548Y2422923D02*
X3429548D01*
Y2430923D01*
X3433548D01*
G01X3431948Y2427056D02*
X3429548D01*
G01X3445048Y2422923D02*
X3447548Y2430923D01*
X3450048Y2422923D01*
G01X3449148Y2425723D02*
X3445948D01*
G01X3453548Y2422923D02*
Y2430923D01*
X3455948D01*
X3456748Y2430523D01*
X3457348Y2429590D01*
X3457548Y2428523D01*
X3457348Y2427456D01*
X3456848Y2426656D01*
X3455948Y2426256D01*
X3453548D01*
G01X3461548Y2422923D02*
Y2430923D01*
X3463948D01*
X3464748Y2430523D01*
X3465348Y2429590D01*
X3465548Y2428523D01*
X3465348Y2427456D01*
X3464848Y2426656D01*
X3463948Y2426256D01*
X3461548D01*
G01X3469548Y2422923D02*
Y2430923D01*
X3472048D01*
X3472848Y2430523D01*
X3473348Y2429990D01*
X3473548Y2428923D01*
X3473348Y2427856D01*
X3472748Y2427190D01*
X3472048Y2426790D01*
X3469548D01*
G01X3472048D02*
X3473548Y2422923D01*
G01X3479548D02*
X3478748Y2423056D01*
X3478048Y2423590D01*
X3477448Y2424390D01*
X3477048Y2425323D01*
X3476848Y2426390D01*
Y2427456D01*
X3477048Y2428523D01*
X3477448Y2429456D01*
X3478048Y2430256D01*
X3478748Y2430790D01*
X3479548Y2430923D01*
X3480348Y2430790D01*
X3481048Y2430256D01*
X3481648Y2429456D01*
X3482048Y2428523D01*
X3482248Y2427456D01*
Y2426390D01*
X3482048Y2425323D01*
X3481648Y2424390D01*
X3481048Y2423590D01*
X3480348Y2423056D01*
X3479548Y2422923D01*
G01X3485048Y2430923D02*
X3487548Y2422923D01*
X3490048Y2430923D01*
G01X3497548Y2422923D02*
X3493548D01*
Y2430923D01*
X3497548D01*
G01X3495948Y2427056D02*
X3493548D01*
G01X3501348Y2422923D02*
Y2430923D01*
X3503348D01*
X3504148Y2430523D01*
X3504748Y2429990D01*
X3505248Y2429190D01*
X3505648Y2428256D01*
X3505748Y2426923D01*
X3505648Y2425590D01*
X3505248Y2424656D01*
X3504748Y2423856D01*
X3504148Y2423323D01*
X3503348Y2422923D01*
X3501348D01*
G01X3520348Y2427190D02*
X3520748Y2427590D01*
X3521048Y2428256D01*
X3521248Y2429190D01*
X3521048Y2429990D01*
X3520648Y2430523D01*
X3519948Y2430923D01*
X3517248D01*
Y2422923D01*
X3520548D01*
X3521248Y2423456D01*
X3521648Y2424256D01*
X3521848Y2425190D01*
X3521648Y2426123D01*
X3521048Y2426923D01*
X3520348Y2427190D01*
X3517248D01*
G01X3527548Y2422923D02*
Y2426523D01*
X3525548Y2430923D01*
G01X3529548D02*
X3527548Y2426523D01*
G01X3543548Y2422923D02*
X3542748Y2423056D01*
X3542048Y2423590D01*
X3541448Y2424390D01*
X3541048Y2425323D01*
X3540848Y2426390D01*
Y2427456D01*
X3541048Y2428523D01*
X3541448Y2429456D01*
X3542048Y2430256D01*
X3542748Y2430790D01*
X3543548Y2430923D01*
X3544348Y2430790D01*
X3545048Y2430256D01*
X3545648Y2429456D01*
X3546048Y2428523D01*
X3546248Y2427456D01*
Y2426390D01*
X3546048Y2425323D01*
X3545648Y2424390D01*
X3545048Y2423590D01*
X3544348Y2423056D01*
X3543548Y2422923D01*
G01X3544348Y2425056D02*
X3545548Y2422923D01*
G01X3549348Y2430923D02*
Y2425190D01*
X3549748Y2423989D01*
X3550548Y2423190D01*
X3551548Y2422923D01*
X3552548Y2423190D01*
X3553348Y2423989D01*
X3553748Y2425190D01*
Y2430923D01*
G01X3557048Y2422923D02*
X3559548Y2430923D01*
X3562048Y2422923D01*
G01X3561148Y2425723D02*
X3557948D01*
G01X3565248Y2422923D02*
Y2430923D01*
X3569848Y2422923D01*
Y2430923D01*
G01X3575548D02*
Y2422923D01*
G01X3573248Y2430923D02*
X3577848D01*
G01X3581048Y2422923D02*
X3583548Y2430923D01*
X3586048Y2422923D01*
G01X3585148Y2425723D02*
X3581948D01*
G01X3597548Y2422923D02*
Y2430923D01*
X3599948D01*
X3600748Y2430523D01*
X3601348Y2429590D01*
X3601548Y2428523D01*
X3601348Y2427456D01*
X3600848Y2426656D01*
X3599948Y2426256D01*
X3597548D01*
G01X3605548Y2422923D02*
Y2430923D01*
X3608048D01*
X3608848Y2430523D01*
X3609348Y2429990D01*
X3609548Y2428923D01*
X3609348Y2427856D01*
X3608748Y2427190D01*
X3608048Y2426790D01*
X3605548D01*
G01X3608048D02*
X3609548Y2422923D01*
G01X3614348Y2430923D02*
X3616748D01*
G01X3615548D02*
Y2422923D01*
G01X3614348D02*
X3616748D01*
G01X3623548D02*
X3622748Y2423056D01*
X3622048Y2423590D01*
X3621448Y2424390D01*
X3621048Y2425323D01*
X3620848Y2426390D01*
Y2427456D01*
X3621048Y2428523D01*
X3621448Y2429456D01*
X3622048Y2430256D01*
X3622748Y2430790D01*
X3623548Y2430923D01*
X3624348Y2430790D01*
X3625048Y2430256D01*
X3625648Y2429456D01*
X3626048Y2428523D01*
X3626248Y2427456D01*
Y2426390D01*
X3626048Y2425323D01*
X3625648Y2424390D01*
X3625048Y2423590D01*
X3624348Y2423056D01*
X3623548Y2422923D01*
G01X3629548D02*
Y2430923D01*
X3632048D01*
X3632848Y2430523D01*
X3633348Y2429990D01*
X3633548Y2428923D01*
X3633348Y2427856D01*
X3632748Y2427190D01*
X3632048Y2426790D01*
X3629548D01*
G01X3632048D02*
X3633548Y2422923D01*
G01X3647548Y2430923D02*
Y2422923D01*
G01X3645248Y2430923D02*
X3649848D01*
G01X3655548Y2422923D02*
X3654748Y2423056D01*
X3654048Y2423590D01*
X3653448Y2424390D01*
X3653048Y2425323D01*
X3652848Y2426390D01*
Y2427456D01*
X3653048Y2428523D01*
X3653448Y2429456D01*
X3654048Y2430256D01*
X3654748Y2430790D01*
X3655548Y2430923D01*
X3656348Y2430790D01*
X3657048Y2430256D01*
X3657648Y2429456D01*
X3658048Y2428523D01*
X3658248Y2427456D01*
Y2426390D01*
X3658048Y2425323D01*
X3657648Y2424390D01*
X3657048Y2423590D01*
X3656348Y2423056D01*
X3655548Y2422923D01*
G01X3670348Y2430923D02*
X3672748D01*
G01X3671548D02*
Y2422923D01*
G01X3670348D02*
X3672748D01*
G01X3679548Y2430923D02*
Y2422923D01*
G01X3677248Y2430923D02*
X3681848D01*
G01X3685448Y2423989D02*
X3686248Y2423323D01*
X3687148Y2422923D01*
X3687948D01*
X3688748Y2423323D01*
X3689348Y2423989D01*
X3689648Y2424923D01*
X3689448Y2425856D01*
X3688948Y2426656D01*
X3688048Y2427190D01*
X3686848Y2427456D01*
X3686148Y2427990D01*
X3685848Y2428923D01*
X3686048Y2429856D01*
X3686548Y2430523D01*
X3687248Y2430923D01*
X3687948D01*
X3688648Y2430656D01*
X3689248Y2429990D01*
G01X3702348Y2430923D02*
X3704748D01*
G01X3703548D02*
Y2422923D01*
G01X3702348D02*
X3704748D01*
G01X3708948D02*
Y2430923D01*
X3711548Y2424256D01*
X3714148Y2430923D01*
Y2422923D01*
G01X3717548D02*
Y2430923D01*
X3719948D01*
X3720748Y2430523D01*
X3721348Y2429590D01*
X3721548Y2428523D01*
X3721348Y2427456D01*
X3720848Y2426656D01*
X3719948Y2426256D01*
X3717548D01*
G01X3725548Y2430923D02*
Y2422923D01*
X3729548D01*
G01X3737548D02*
X3733548D01*
Y2430923D01*
X3737548D01*
G01X3735948Y2427056D02*
X3733548D01*
G01X3740948Y2422923D02*
Y2430923D01*
X3743548Y2424256D01*
X3746148Y2430923D01*
Y2422923D01*
G01X3753548D02*
X3749548D01*
Y2430923D01*
X3753548D01*
G01X3751948Y2427056D02*
X3749548D01*
G01X3757248Y2422923D02*
Y2430923D01*
X3761848Y2422923D01*
Y2430923D01*
G01X3767548D02*
Y2422923D01*
G01X3765248Y2430923D02*
X3769848D01*
G01X3773048Y2422923D02*
X3775548Y2430923D01*
X3778048Y2422923D01*
G01X3777148Y2425723D02*
X3773948D01*
G01X3783548Y2430923D02*
Y2422923D01*
G01X3781248Y2430923D02*
X3785848D01*
G01X3790348D02*
X3792748D01*
G01X3791548D02*
Y2422923D01*
G01X3790348D02*
X3792748D01*
G01X3799548D02*
X3798748Y2423056D01*
X3798048Y2423590D01*
X3797448Y2424390D01*
X3797048Y2425323D01*
X3796848Y2426390D01*
Y2427456D01*
X3797048Y2428523D01*
X3797448Y2429456D01*
X3798048Y2430256D01*
X3798748Y2430790D01*
X3799548Y2430923D01*
X3800348Y2430790D01*
X3801048Y2430256D01*
X3801648Y2429456D01*
X3802048Y2428523D01*
X3802248Y2427456D01*
Y2426390D01*
X3802048Y2425323D01*
X3801648Y2424390D01*
X3801048Y2423590D01*
X3800348Y2423056D01*
X3799548Y2422923D01*
G01X3805248D02*
Y2430923D01*
X3809848Y2422923D01*
Y2430923D01*
G01X3815548Y2422656D02*
X3815348Y2422790D01*
Y2423056D01*
X3815548Y2423190D01*
X3815748Y2423056D01*
Y2422790D01*
X3815548Y2422656D01*
G01X3158348Y2445923D02*
X3160748D01*
G01X3159548D02*
Y2437923D01*
G01X3158348D02*
X3160748D01*
G01X3164948D02*
Y2445923D01*
X3167548Y2439256D01*
X3170148Y2445923D01*
Y2437923D01*
G01X3173548D02*
Y2445923D01*
X3175948D01*
X3176748Y2445523D01*
X3177348Y2444590D01*
X3177548Y2443523D01*
X3177348Y2442456D01*
X3176848Y2441656D01*
X3175948Y2441256D01*
X3173548D01*
G01X3185548Y2437923D02*
X3181548D01*
Y2445923D01*
X3185548D01*
G01X3183948Y2442056D02*
X3181548D01*
G01X3189348Y2437923D02*
Y2445923D01*
X3191348D01*
X3192148Y2445523D01*
X3192748Y2444990D01*
X3193248Y2444190D01*
X3193648Y2443256D01*
X3193748Y2441923D01*
X3193648Y2440590D01*
X3193248Y2439656D01*
X3192748Y2438856D01*
X3192148Y2438323D01*
X3191348Y2437923D01*
X3189348D01*
G01X3197048D02*
X3199548Y2445923D01*
X3202048Y2437923D01*
G01X3201148Y2440723D02*
X3197948D01*
G01X3205248Y2437923D02*
Y2445923D01*
X3209848Y2437923D01*
Y2445923D01*
G01X3217748Y2445256D02*
X3217148Y2445656D01*
X3216448Y2445923D01*
X3215648D01*
X3214748Y2445523D01*
X3214048Y2444856D01*
X3213548Y2444056D01*
X3213148Y2442723D01*
X3213048Y2441523D01*
X3213248Y2440323D01*
X3213548Y2439523D01*
X3214148Y2438723D01*
X3214848Y2438190D01*
X3215548Y2437923D01*
X3216248D01*
X3216948Y2438190D01*
X3217548Y2438590D01*
X3218048Y2439123D01*
G01X3225548Y2437923D02*
X3221548D01*
Y2445923D01*
X3225548D01*
G01X3223948Y2442056D02*
X3221548D01*
G01X3229448Y2438989D02*
X3230248Y2438323D01*
X3231148Y2437923D01*
X3231948D01*
X3232748Y2438323D01*
X3233348Y2438989D01*
X3233648Y2439923D01*
X3233448Y2440856D01*
X3232948Y2441656D01*
X3232048Y2442190D01*
X3230848Y2442456D01*
X3230148Y2442990D01*
X3229848Y2443923D01*
X3230048Y2444856D01*
X3230548Y2445523D01*
X3231248Y2445923D01*
X3231948D01*
X3232648Y2445656D01*
X3233248Y2444990D01*
G01X3245048Y2437923D02*
X3247548Y2445923D01*
X3250048Y2437923D01*
G01X3249148Y2440723D02*
X3245948D01*
G01X3253248Y2437923D02*
Y2445923D01*
X3257848Y2437923D01*
Y2445923D01*
G01X3261348Y2437923D02*
Y2445923D01*
X3263348D01*
X3264148Y2445523D01*
X3264748Y2444990D01*
X3265248Y2444190D01*
X3265648Y2443256D01*
X3265748Y2441923D01*
X3265648Y2440590D01*
X3265248Y2439656D01*
X3264748Y2438856D01*
X3264148Y2438323D01*
X3263348Y2437923D01*
X3261348D01*
G01X3280348Y2442190D02*
X3280748Y2442590D01*
X3281048Y2443256D01*
X3281248Y2444190D01*
X3281048Y2444990D01*
X3280648Y2445523D01*
X3279948Y2445923D01*
X3277248D01*
Y2437923D01*
X3280548D01*
X3281248Y2438456D01*
X3281648Y2439256D01*
X3281848Y2440190D01*
X3281648Y2441123D01*
X3281048Y2441923D01*
X3280348Y2442190D01*
X3277248D01*
G01X3287548Y2437923D02*
X3286748Y2438056D01*
X3286048Y2438590D01*
X3285448Y2439390D01*
X3285048Y2440323D01*
X3284848Y2441390D01*
Y2442456D01*
X3285048Y2443523D01*
X3285448Y2444456D01*
X3286048Y2445256D01*
X3286748Y2445790D01*
X3287548Y2445923D01*
X3288348Y2445790D01*
X3289048Y2445256D01*
X3289648Y2444456D01*
X3290048Y2443523D01*
X3290248Y2442456D01*
Y2441390D01*
X3290048Y2440323D01*
X3289648Y2439390D01*
X3289048Y2438590D01*
X3288348Y2438056D01*
X3287548Y2437923D01*
G01X3293048D02*
X3295548Y2445923D01*
X3298048Y2437923D01*
G01X3297148Y2440723D02*
X3293948D01*
G01X3301548Y2437923D02*
Y2445923D01*
X3304048D01*
X3304848Y2445523D01*
X3305348Y2444990D01*
X3305548Y2443923D01*
X3305348Y2442856D01*
X3304748Y2442190D01*
X3304048Y2441790D01*
X3301548D01*
G01X3304048D02*
X3305548Y2437923D01*
G01X3309348D02*
Y2445923D01*
X3311348D01*
X3312148Y2445523D01*
X3312748Y2444990D01*
X3313248Y2444190D01*
X3313648Y2443256D01*
X3313748Y2441923D01*
X3313648Y2440590D01*
X3313248Y2439656D01*
X3312748Y2438856D01*
X3312148Y2438323D01*
X3311348Y2437923D01*
X3309348D01*
G01X3327548Y2445923D02*
Y2437923D01*
G01X3325248Y2445923D02*
X3329848D01*
G01X3333448Y2437923D02*
Y2445923D01*
G01X3337648D02*
Y2437923D01*
G01Y2441923D02*
X3333448D01*
G01X3342348Y2445923D02*
X3344748D01*
G01X3343548D02*
Y2437923D01*
G01X3342348D02*
X3344748D01*
G01X3353748Y2445256D02*
X3353148Y2445656D01*
X3352448Y2445923D01*
X3351648D01*
X3350748Y2445523D01*
X3350048Y2444856D01*
X3349548Y2444056D01*
X3349148Y2442723D01*
X3349048Y2441523D01*
X3349248Y2440323D01*
X3349548Y2439523D01*
X3350148Y2438723D01*
X3350848Y2438190D01*
X3351548Y2437923D01*
X3352248D01*
X3352948Y2438190D01*
X3353548Y2438590D01*
X3354048Y2439123D01*
G01X3357348Y2437923D02*
Y2445923D01*
G01X3361148D02*
X3357348Y2440989D01*
G01X3361748Y2437923D02*
X3359048Y2443256D01*
G01X3365248Y2437923D02*
Y2445923D01*
X3369848Y2437923D01*
Y2445923D01*
G01X3377548Y2437923D02*
X3373548D01*
Y2445923D01*
X3377548D01*
G01X3375948Y2442056D02*
X3373548D01*
G01X3381448Y2438989D02*
X3382248Y2438323D01*
X3383148Y2437923D01*
X3383948D01*
X3384748Y2438323D01*
X3385348Y2438989D01*
X3385648Y2439923D01*
X3385448Y2440856D01*
X3384948Y2441656D01*
X3384048Y2442190D01*
X3382848Y2442456D01*
X3382148Y2442990D01*
X3381848Y2443923D01*
X3382048Y2444856D01*
X3382548Y2445523D01*
X3383248Y2445923D01*
X3383948D01*
X3384648Y2445656D01*
X3385248Y2444990D01*
G01X3389448Y2438989D02*
X3390248Y2438323D01*
X3391148Y2437923D01*
X3391948D01*
X3392748Y2438323D01*
X3393348Y2438989D01*
X3393648Y2439923D01*
X3393448Y2440856D01*
X3392948Y2441656D01*
X3392048Y2442190D01*
X3390848Y2442456D01*
X3390148Y2442990D01*
X3389848Y2443923D01*
X3390048Y2444856D01*
X3390548Y2445523D01*
X3391248Y2445923D01*
X3391948D01*
X3392648Y2445656D01*
X3393248Y2444990D01*
G01X3399548Y2437656D02*
X3399348Y2437790D01*
Y2438056D01*
X3399548Y2438190D01*
X3399748Y2438056D01*
Y2437790D01*
X3399548Y2437656D01*
G01X3157448Y2453989D02*
X3158248Y2453323D01*
X3159148Y2452923D01*
X3159948D01*
X3160748Y2453323D01*
X3161348Y2453989D01*
X3161648Y2454923D01*
X3161448Y2455856D01*
X3160948Y2456656D01*
X3160048Y2457190D01*
X3158848Y2457456D01*
X3158148Y2457990D01*
X3157848Y2458923D01*
X3158048Y2459856D01*
X3158548Y2460523D01*
X3159248Y2460923D01*
X3159948D01*
X3160648Y2460656D01*
X3161248Y2459990D01*
G01X3165548Y2452923D02*
Y2460923D01*
X3167948D01*
X3168748Y2460523D01*
X3169348Y2459590D01*
X3169548Y2458523D01*
X3169348Y2457456D01*
X3168848Y2456656D01*
X3167948Y2456256D01*
X3165548D01*
G01X3173048Y2452923D02*
X3175548Y2460923D01*
X3178048Y2452923D01*
G01X3177148Y2455723D02*
X3173948D01*
G01X3185748Y2460256D02*
X3185148Y2460656D01*
X3184448Y2460923D01*
X3183648D01*
X3182748Y2460523D01*
X3182048Y2459856D01*
X3181548Y2459056D01*
X3181148Y2457723D01*
X3181048Y2456523D01*
X3181248Y2455323D01*
X3181548Y2454523D01*
X3182148Y2453723D01*
X3182848Y2453190D01*
X3183548Y2452923D01*
X3184248D01*
X3184948Y2453190D01*
X3185548Y2453590D01*
X3186048Y2454123D01*
G01X3190348Y2460923D02*
X3192748D01*
G01X3191548D02*
Y2452923D01*
G01X3190348D02*
X3192748D01*
G01X3197248D02*
Y2460923D01*
X3201848Y2452923D01*
Y2460923D01*
G01X3208148Y2456923D02*
X3210148D01*
Y2454523D01*
X3209548Y2453723D01*
X3208848Y2453190D01*
X3207848Y2452923D01*
X3206848Y2453190D01*
X3206148Y2453723D01*
X3205548Y2454523D01*
X3205148Y2455456D01*
X3204948Y2456523D01*
Y2457456D01*
X3205148Y2458256D01*
X3205548Y2459190D01*
X3206148Y2459990D01*
X3206748Y2460523D01*
X3207548Y2460923D01*
X3208248D01*
X3209048Y2460656D01*
X3209648Y2460123D01*
G01X3221048Y2452923D02*
X3223548Y2460923D01*
X3226048Y2452923D01*
G01X3225148Y2455723D02*
X3221948D01*
G01X3229248Y2452923D02*
Y2460923D01*
X3233848Y2452923D01*
Y2460923D01*
G01X3237348Y2452923D02*
Y2460923D01*
X3239348D01*
X3240148Y2460523D01*
X3240748Y2459990D01*
X3241248Y2459190D01*
X3241648Y2458256D01*
X3241748Y2456923D01*
X3241648Y2455590D01*
X3241248Y2454656D01*
X3240748Y2453856D01*
X3240148Y2453323D01*
X3239348Y2452923D01*
X3237348D01*
G01X3252948D02*
Y2460923D01*
X3255548Y2454256D01*
X3258148Y2460923D01*
Y2452923D01*
G01X3261048D02*
X3263548Y2460923D01*
X3266048Y2452923D01*
G01X3265148Y2455723D02*
X3261948D01*
G01X3271548Y2460923D02*
Y2452923D01*
G01X3269248Y2460923D02*
X3273848D01*
G01X3281548Y2452923D02*
X3277548D01*
Y2460923D01*
X3281548D01*
G01X3279948Y2457056D02*
X3277548D01*
G01X3285548Y2452923D02*
Y2460923D01*
X3288048D01*
X3288848Y2460523D01*
X3289348Y2459990D01*
X3289548Y2458923D01*
X3289348Y2457856D01*
X3288748Y2457190D01*
X3288048Y2456790D01*
X3285548D01*
G01X3288048D02*
X3289548Y2452923D01*
G01X3294348Y2460923D02*
X3296748D01*
G01X3295548D02*
Y2452923D01*
G01X3294348D02*
X3296748D01*
G01X3301048D02*
X3303548Y2460923D01*
X3306048Y2452923D01*
G01X3305148Y2455723D02*
X3301948D01*
G01X3309548Y2460923D02*
Y2452923D01*
X3313548D01*
G01X3325348D02*
Y2460923D01*
X3327348D01*
X3328148Y2460523D01*
X3328748Y2459990D01*
X3329248Y2459190D01*
X3329648Y2458256D01*
X3329748Y2456923D01*
X3329648Y2455590D01*
X3329248Y2454656D01*
X3328748Y2453856D01*
X3328148Y2453323D01*
X3327348Y2452923D01*
X3325348D01*
G01X3334348Y2460923D02*
X3336748D01*
G01X3335548D02*
Y2452923D01*
G01X3334348D02*
X3336748D01*
G01X3345548D02*
X3341548D01*
Y2460923D01*
X3345548D01*
G01X3343948Y2457056D02*
X3341548D01*
G01X3349548Y2460923D02*
Y2452923D01*
X3353548D01*
G01X3361548D02*
X3357548D01*
Y2460923D01*
X3361548D01*
G01X3359948Y2457056D02*
X3357548D01*
G01X3369748Y2460256D02*
X3369148Y2460656D01*
X3368448Y2460923D01*
X3367648D01*
X3366748Y2460523D01*
X3366048Y2459856D01*
X3365548Y2459056D01*
X3365148Y2457723D01*
X3365048Y2456523D01*
X3365248Y2455323D01*
X3365548Y2454523D01*
X3366148Y2453723D01*
X3366848Y2453190D01*
X3367548Y2452923D01*
X3368248D01*
X3368948Y2453190D01*
X3369548Y2453590D01*
X3370048Y2454123D01*
G01X3375548Y2460923D02*
Y2452923D01*
G01X3373248Y2460923D02*
X3377848D01*
G01X3381548Y2452923D02*
Y2460923D01*
X3384048D01*
X3384848Y2460523D01*
X3385348Y2459990D01*
X3385548Y2458923D01*
X3385348Y2457856D01*
X3384748Y2457190D01*
X3384048Y2456790D01*
X3381548D01*
G01X3384048D02*
X3385548Y2452923D01*
G01X3390348Y2460923D02*
X3392748D01*
G01X3391548D02*
Y2452923D01*
G01X3390348D02*
X3392748D01*
G01X3401748Y2460256D02*
X3401148Y2460656D01*
X3400448Y2460923D01*
X3399648D01*
X3398748Y2460523D01*
X3398048Y2459856D01*
X3397548Y2459056D01*
X3397148Y2457723D01*
X3397048Y2456523D01*
X3397248Y2455323D01*
X3397548Y2454523D01*
X3398148Y2453723D01*
X3398848Y2453190D01*
X3399548Y2452923D01*
X3400248D01*
X3400948Y2453190D01*
X3401548Y2453590D01*
X3402048Y2454123D01*
G01X3417748Y2460256D02*
X3417148Y2460656D01*
X3416448Y2460923D01*
X3415648D01*
X3414748Y2460523D01*
X3414048Y2459856D01*
X3413548Y2459056D01*
X3413148Y2457723D01*
X3413048Y2456523D01*
X3413248Y2455323D01*
X3413548Y2454523D01*
X3414148Y2453723D01*
X3414848Y2453190D01*
X3415548Y2452923D01*
X3416248D01*
X3416948Y2453190D01*
X3417548Y2453590D01*
X3418048Y2454123D01*
G01X3423548Y2452923D02*
X3422748Y2453056D01*
X3422048Y2453590D01*
X3421448Y2454390D01*
X3421048Y2455323D01*
X3420848Y2456390D01*
Y2457456D01*
X3421048Y2458523D01*
X3421448Y2459456D01*
X3422048Y2460256D01*
X3422748Y2460790D01*
X3423548Y2460923D01*
X3424348Y2460790D01*
X3425048Y2460256D01*
X3425648Y2459456D01*
X3426048Y2458523D01*
X3426248Y2457456D01*
Y2456390D01*
X3426048Y2455323D01*
X3425648Y2454390D01*
X3425048Y2453590D01*
X3424348Y2453056D01*
X3423548Y2452923D01*
G01X3429248D02*
Y2460923D01*
X3433848Y2452923D01*
Y2460923D01*
G01X3437448Y2453989D02*
X3438248Y2453323D01*
X3439148Y2452923D01*
X3439948D01*
X3440748Y2453323D01*
X3441348Y2453989D01*
X3441648Y2454923D01*
X3441448Y2455856D01*
X3440948Y2456656D01*
X3440048Y2457190D01*
X3438848Y2457456D01*
X3438148Y2457990D01*
X3437848Y2458923D01*
X3438048Y2459856D01*
X3438548Y2460523D01*
X3439248Y2460923D01*
X3439948D01*
X3440648Y2460656D01*
X3441248Y2459990D01*
G01X3447548Y2460923D02*
Y2452923D01*
G01X3445248Y2460923D02*
X3449848D01*
G01X3453048Y2452923D02*
X3455548Y2460923D01*
X3458048Y2452923D01*
G01X3457148Y2455723D02*
X3453948D01*
G01X3461248Y2452923D02*
Y2460923D01*
X3465848Y2452923D01*
Y2460923D01*
G01X3471548D02*
Y2452923D01*
G01X3469248Y2460923D02*
X3473848D01*
G01X3487548D02*
Y2452923D01*
G01X3485248Y2460923D02*
X3489848D01*
G01X3495548Y2452923D02*
X3494748Y2453056D01*
X3494048Y2453590D01*
X3493448Y2454390D01*
X3493048Y2455323D01*
X3492848Y2456390D01*
Y2457456D01*
X3493048Y2458523D01*
X3493448Y2459456D01*
X3494048Y2460256D01*
X3494748Y2460790D01*
X3495548Y2460923D01*
X3496348Y2460790D01*
X3497048Y2460256D01*
X3497648Y2459456D01*
X3498048Y2458523D01*
X3498248Y2457456D01*
Y2456390D01*
X3498048Y2455323D01*
X3497648Y2454390D01*
X3497048Y2453590D01*
X3496348Y2453056D01*
X3495548Y2452923D01*
G01X3509048D02*
X3511548Y2460923D01*
X3514048Y2452923D01*
G01X3513148Y2455723D02*
X3509948D01*
G01X3521748Y2460256D02*
X3521148Y2460656D01*
X3520448Y2460923D01*
X3519648D01*
X3518748Y2460523D01*
X3518048Y2459856D01*
X3517548Y2459056D01*
X3517148Y2457723D01*
X3517048Y2456523D01*
X3517248Y2455323D01*
X3517548Y2454523D01*
X3518148Y2453723D01*
X3518848Y2453190D01*
X3519548Y2452923D01*
X3520248D01*
X3520948Y2453190D01*
X3521548Y2453590D01*
X3522048Y2454123D01*
G01X3525448Y2452923D02*
Y2460923D01*
G01X3529648D02*
Y2452923D01*
G01Y2456923D02*
X3525448D01*
G01X3534348Y2460923D02*
X3536748D01*
G01X3535548D02*
Y2452923D01*
G01X3534348D02*
X3536748D01*
G01X3545548D02*
X3541548D01*
Y2460923D01*
X3545548D01*
G01X3543948Y2457056D02*
X3541548D01*
G01X3549048Y2460923D02*
X3551548Y2452923D01*
X3554048Y2460923D01*
G01X3561548Y2452923D02*
X3557548D01*
Y2460923D01*
X3561548D01*
G01X3559948Y2457056D02*
X3557548D01*
G01X3573548Y2452923D02*
Y2460923D01*
X3576048D01*
X3576848Y2460523D01*
X3577348Y2459990D01*
X3577548Y2458923D01*
X3577348Y2457856D01*
X3576748Y2457190D01*
X3576048Y2456790D01*
X3573548D01*
G01X3576048D02*
X3577548Y2452923D01*
G01X3585548D02*
X3581548D01*
Y2460923D01*
X3585548D01*
G01X3583948Y2457056D02*
X3581548D01*
G01X3591548Y2452923D02*
X3590748Y2453056D01*
X3590048Y2453590D01*
X3589448Y2454390D01*
X3589048Y2455323D01*
X3588848Y2456390D01*
Y2457456D01*
X3589048Y2458523D01*
X3589448Y2459456D01*
X3590048Y2460256D01*
X3590748Y2460790D01*
X3591548Y2460923D01*
X3592348Y2460790D01*
X3593048Y2460256D01*
X3593648Y2459456D01*
X3594048Y2458523D01*
X3594248Y2457456D01*
Y2456390D01*
X3594048Y2455323D01*
X3593648Y2454390D01*
X3593048Y2453590D01*
X3592348Y2453056D01*
X3591548Y2452923D01*
G01X3592348Y2455056D02*
X3593548Y2452923D01*
G01X3597348Y2460923D02*
Y2455190D01*
X3597748Y2453989D01*
X3598548Y2453190D01*
X3599548Y2452923D01*
X3600548Y2453190D01*
X3601348Y2453989D01*
X3601748Y2455190D01*
Y2460923D01*
G01X3606348D02*
X3608748D01*
G01X3607548D02*
Y2452923D01*
G01X3606348D02*
X3608748D01*
G01X3613548D02*
Y2460923D01*
X3616048D01*
X3616848Y2460523D01*
X3617348Y2459990D01*
X3617548Y2458923D01*
X3617348Y2457856D01*
X3616748Y2457190D01*
X3616048Y2456790D01*
X3613548D01*
G01X3616048D02*
X3617548Y2452923D01*
G01X3625548D02*
X3621548D01*
Y2460923D01*
X3625548D01*
G01X3623948Y2457056D02*
X3621548D01*
G01X3629348Y2452923D02*
Y2460923D01*
X3631348D01*
X3632148Y2460523D01*
X3632748Y2459990D01*
X3633248Y2459190D01*
X3633648Y2458256D01*
X3633748Y2456923D01*
X3633648Y2455590D01*
X3633248Y2454656D01*
X3632748Y2453856D01*
X3632148Y2453323D01*
X3631348Y2452923D01*
X3629348D01*
G01X3161748Y2475256D02*
X3161148Y2475656D01*
X3160448Y2475923D01*
X3159648D01*
X3158748Y2475523D01*
X3158048Y2474856D01*
X3157548Y2474056D01*
X3157148Y2472723D01*
X3157048Y2471523D01*
X3157248Y2470323D01*
X3157548Y2469523D01*
X3158148Y2468723D01*
X3158848Y2468190D01*
X3159548Y2467923D01*
X3160248D01*
X3160948Y2468190D01*
X3161548Y2468590D01*
X3162048Y2469123D01*
G01X3165448Y2467923D02*
Y2475923D01*
G01X3169648D02*
Y2467923D01*
G01Y2471923D02*
X3165448D01*
G01X3173048Y2467923D02*
X3175548Y2475923D01*
X3178048Y2467923D01*
G01X3177148Y2470723D02*
X3173948D01*
G01X3181548Y2467923D02*
Y2475923D01*
X3184048D01*
X3184848Y2475523D01*
X3185348Y2474990D01*
X3185548Y2473923D01*
X3185348Y2472856D01*
X3184748Y2472190D01*
X3184048Y2471790D01*
X3181548D01*
G01X3184048D02*
X3185548Y2467923D01*
G01X3191548Y2475923D02*
Y2467923D01*
G01X3189248Y2475923D02*
X3193848D01*
G01X3199548Y2467656D02*
X3199348Y2467790D01*
Y2468056D01*
X3199548Y2468190D01*
X3199748Y2468056D01*
Y2467790D01*
X3199548Y2467656D01*
G01X3212948Y2467923D02*
Y2475923D01*
X3215548Y2469256D01*
X3218148Y2475923D01*
Y2467923D01*
G01X3221048D02*
X3223548Y2475923D01*
X3226048Y2467923D01*
G01X3225148Y2470723D02*
X3221948D01*
G01X3229248Y2467923D02*
Y2475923D01*
X3233848Y2467923D01*
Y2475923D01*
G01X3237348D02*
Y2470190D01*
X3237748Y2468989D01*
X3238548Y2468190D01*
X3239548Y2467923D01*
X3240548Y2468190D01*
X3241348Y2468989D01*
X3241748Y2470190D01*
Y2475923D01*
G01X3245648Y2467923D02*
Y2475923D01*
X3249448D01*
G01X3248048Y2472056D02*
X3245648D01*
G01X3253048Y2467923D02*
X3255548Y2475923D01*
X3258048Y2467923D01*
G01X3257148Y2470723D02*
X3253948D01*
G01X3265748Y2475256D02*
X3265148Y2475656D01*
X3264448Y2475923D01*
X3263648D01*
X3262748Y2475523D01*
X3262048Y2474856D01*
X3261548Y2474056D01*
X3261148Y2472723D01*
X3261048Y2471523D01*
X3261248Y2470323D01*
X3261548Y2469523D01*
X3262148Y2468723D01*
X3262848Y2468190D01*
X3263548Y2467923D01*
X3264248D01*
X3264948Y2468190D01*
X3265548Y2468590D01*
X3266048Y2469123D01*
G01X3271548Y2475923D02*
Y2467923D01*
G01X3269248Y2475923D02*
X3273848D01*
G01X3277348D02*
Y2470190D01*
X3277748Y2468989D01*
X3278548Y2468190D01*
X3279548Y2467923D01*
X3280548Y2468190D01*
X3281348Y2468989D01*
X3281748Y2470190D01*
Y2475923D01*
G01X3285548Y2467923D02*
Y2475923D01*
X3288048D01*
X3288848Y2475523D01*
X3289348Y2474990D01*
X3289548Y2473923D01*
X3289348Y2472856D01*
X3288748Y2472190D01*
X3288048Y2471790D01*
X3285548D01*
G01X3288048D02*
X3289548Y2467923D01*
G01X3297548D02*
X3293548D01*
Y2475923D01*
X3297548D01*
G01X3295948Y2472056D02*
X3293548D01*
G01X3301548Y2467923D02*
Y2475923D01*
X3304048D01*
X3304848Y2475523D01*
X3305348Y2474990D01*
X3305548Y2473923D01*
X3305348Y2472856D01*
X3304748Y2472190D01*
X3304048Y2471790D01*
X3301548D01*
G01X3304048D02*
X3305548Y2467923D01*
G01X3318348Y2475923D02*
X3320748D01*
G01X3319548D02*
Y2467923D01*
G01X3318348D02*
X3320748D01*
G01X3325448Y2468989D02*
X3326248Y2468323D01*
X3327148Y2467923D01*
X3327948D01*
X3328748Y2468323D01*
X3329348Y2468989D01*
X3329648Y2469923D01*
X3329448Y2470856D01*
X3328948Y2471656D01*
X3328048Y2472190D01*
X3326848Y2472456D01*
X3326148Y2472990D01*
X3325848Y2473923D01*
X3326048Y2474856D01*
X3326548Y2475523D01*
X3327248Y2475923D01*
X3327948D01*
X3328648Y2475656D01*
X3329248Y2474990D01*
G01X3341648Y2467923D02*
Y2475923D01*
X3345448D01*
G01X3344048Y2472056D02*
X3341648D01*
G01X3349548Y2467923D02*
Y2475923D01*
X3352048D01*
X3352848Y2475523D01*
X3353348Y2474990D01*
X3353548Y2473923D01*
X3353348Y2472856D01*
X3352748Y2472190D01*
X3352048Y2471790D01*
X3349548D01*
G01X3352048D02*
X3353548Y2467923D01*
G01X3361548D02*
X3357548D01*
Y2475923D01*
X3361548D01*
G01X3359948Y2472056D02*
X3357548D01*
G01X3369548Y2467923D02*
X3365548D01*
Y2475923D01*
X3369548D01*
G01X3367948Y2472056D02*
X3365548D01*
G01X3383548Y2475923D02*
Y2467923D01*
G01X3381248Y2475923D02*
X3385848D01*
G01X3391548Y2467923D02*
X3390748Y2468056D01*
X3390048Y2468590D01*
X3389448Y2469390D01*
X3389048Y2470323D01*
X3388848Y2471390D01*
Y2472456D01*
X3389048Y2473523D01*
X3389448Y2474456D01*
X3390048Y2475256D01*
X3390748Y2475790D01*
X3391548Y2475923D01*
X3392348Y2475790D01*
X3393048Y2475256D01*
X3393648Y2474456D01*
X3394048Y2473523D01*
X3394248Y2472456D01*
Y2471390D01*
X3394048Y2470323D01*
X3393648Y2469390D01*
X3393048Y2468590D01*
X3392348Y2468056D01*
X3391548Y2467923D01*
G01X3405048D02*
X3407548Y2475923D01*
X3410048Y2467923D01*
G01X3409148Y2470723D02*
X3405948D01*
G01X3413348Y2467923D02*
Y2475923D01*
X3415348D01*
X3416148Y2475523D01*
X3416748Y2474990D01*
X3417248Y2474190D01*
X3417648Y2473256D01*
X3417748Y2471923D01*
X3417648Y2470590D01*
X3417248Y2469656D01*
X3416748Y2468856D01*
X3416148Y2468323D01*
X3415348Y2467923D01*
X3413348D01*
G01X3421548Y2469523D02*
X3422048Y2468723D01*
X3422648Y2468190D01*
X3423348Y2467923D01*
X3424148Y2468190D01*
X3424748Y2468723D01*
X3425348Y2469523D01*
X3425548Y2470590D01*
Y2475923D01*
G01X3429348D02*
Y2470190D01*
X3429748Y2468989D01*
X3430548Y2468190D01*
X3431548Y2467923D01*
X3432548Y2468190D01*
X3433348Y2468989D01*
X3433748Y2470190D01*
Y2475923D01*
G01X3437448Y2468989D02*
X3438248Y2468323D01*
X3439148Y2467923D01*
X3439948D01*
X3440748Y2468323D01*
X3441348Y2468989D01*
X3441648Y2469923D01*
X3441448Y2470856D01*
X3440948Y2471656D01*
X3440048Y2472190D01*
X3438848Y2472456D01*
X3438148Y2472990D01*
X3437848Y2473923D01*
X3438048Y2474856D01*
X3438548Y2475523D01*
X3439248Y2475923D01*
X3439948D01*
X3440648Y2475656D01*
X3441248Y2474990D01*
G01X3447548Y2475923D02*
Y2467923D01*
G01X3445248Y2475923D02*
X3449848D01*
G01X3463548D02*
Y2467923D01*
G01X3461248Y2475923D02*
X3465848D01*
G01X3469548Y2467923D02*
Y2475923D01*
X3472048D01*
X3472848Y2475523D01*
X3473348Y2474990D01*
X3473548Y2473923D01*
X3473348Y2472856D01*
X3472748Y2472190D01*
X3472048Y2471790D01*
X3469548D01*
G01X3472048D02*
X3473548Y2467923D01*
G01X3477048D02*
X3479548Y2475923D01*
X3482048Y2467923D01*
G01X3481148Y2470723D02*
X3477948D01*
G01X3489748Y2475256D02*
X3489148Y2475656D01*
X3488448Y2475923D01*
X3487648D01*
X3486748Y2475523D01*
X3486048Y2474856D01*
X3485548Y2474056D01*
X3485148Y2472723D01*
X3485048Y2471523D01*
X3485248Y2470323D01*
X3485548Y2469523D01*
X3486148Y2468723D01*
X3486848Y2468190D01*
X3487548Y2467923D01*
X3488248D01*
X3488948Y2468190D01*
X3489548Y2468590D01*
X3490048Y2469123D01*
G01X3497548Y2467923D02*
X3493548D01*
Y2475923D01*
X3497548D01*
G01X3495948Y2472056D02*
X3493548D01*
G01X3508548Y2475923D02*
X3509948Y2467923D01*
X3511548Y2475923D01*
X3513148Y2467923D01*
X3514548Y2475923D01*
G01X3518348D02*
X3520748D01*
G01X3519548D02*
Y2467923D01*
G01X3518348D02*
X3520748D01*
G01X3525348D02*
Y2475923D01*
X3527348D01*
X3528148Y2475523D01*
X3528748Y2474990D01*
X3529248Y2474190D01*
X3529648Y2473256D01*
X3529748Y2471923D01*
X3529648Y2470590D01*
X3529248Y2469656D01*
X3528748Y2468856D01*
X3528148Y2468323D01*
X3527348Y2467923D01*
X3525348D01*
G01X3535548Y2475923D02*
Y2467923D01*
G01X3533248Y2475923D02*
X3537848D01*
G01X3541448Y2467923D02*
Y2475923D01*
G01X3545648D02*
Y2467923D01*
G01Y2471923D02*
X3541448D01*
G01X3549448Y2468989D02*
X3550248Y2468323D01*
X3551148Y2467923D01*
X3551948D01*
X3552748Y2468323D01*
X3553348Y2468989D01*
X3553648Y2469923D01*
X3553448Y2470856D01*
X3552948Y2471656D01*
X3552048Y2472190D01*
X3550848Y2472456D01*
X3550148Y2472990D01*
X3549848Y2473923D01*
X3550048Y2474856D01*
X3550548Y2475523D01*
X3551248Y2475923D01*
X3551948D01*
X3552648Y2475656D01*
X3553248Y2474990D01*
G01X3559348Y2466456D02*
X3559748Y2468190D01*
G01X3581348Y2467923D02*
Y2475923D01*
X3583348D01*
X3584148Y2475523D01*
X3584748Y2474990D01*
X3585248Y2474190D01*
X3585648Y2473256D01*
X3585748Y2471923D01*
X3585648Y2470590D01*
X3585248Y2469656D01*
X3584748Y2468856D01*
X3584148Y2468323D01*
X3583348Y2467923D01*
X3581348D01*
G01X3590348Y2475923D02*
X3592748D01*
G01X3591548D02*
Y2467923D01*
G01X3590348D02*
X3592748D01*
G01X3601548D02*
X3597548D01*
Y2475923D01*
X3601548D01*
G01X3599948Y2472056D02*
X3597548D01*
G01X3605548Y2475923D02*
Y2467923D01*
X3609548D01*
G01X3617548D02*
X3613548D01*
Y2475923D01*
X3617548D01*
G01X3615948Y2472056D02*
X3613548D01*
G01X3625748Y2475256D02*
X3625148Y2475656D01*
X3624448Y2475923D01*
X3623648D01*
X3622748Y2475523D01*
X3622048Y2474856D01*
X3621548Y2474056D01*
X3621148Y2472723D01*
X3621048Y2471523D01*
X3621248Y2470323D01*
X3621548Y2469523D01*
X3622148Y2468723D01*
X3622848Y2468190D01*
X3623548Y2467923D01*
X3624248D01*
X3624948Y2468190D01*
X3625548Y2468590D01*
X3626048Y2469123D01*
G01X3631548Y2475923D02*
Y2467923D01*
G01X3629248Y2475923D02*
X3633848D01*
G01X3637548Y2467923D02*
Y2475923D01*
X3640048D01*
X3640848Y2475523D01*
X3641348Y2474990D01*
X3641548Y2473923D01*
X3641348Y2472856D01*
X3640748Y2472190D01*
X3640048Y2471790D01*
X3637548D01*
G01X3640048D02*
X3641548Y2467923D01*
G01X3646348Y2475923D02*
X3648748D01*
G01X3647548D02*
Y2467923D01*
G01X3646348D02*
X3648748D01*
G01X3657748Y2475256D02*
X3657148Y2475656D01*
X3656448Y2475923D01*
X3655648D01*
X3654748Y2475523D01*
X3654048Y2474856D01*
X3653548Y2474056D01*
X3653148Y2472723D01*
X3653048Y2471523D01*
X3653248Y2470323D01*
X3653548Y2469523D01*
X3654148Y2468723D01*
X3654848Y2468190D01*
X3655548Y2467923D01*
X3656248D01*
X3656948Y2468190D01*
X3657548Y2468590D01*
X3658048Y2469123D01*
G01X3169370Y1568356D02*
Y-643344D01*
G01X3218170Y2081430D02*
X3174863D01*
G01X3218170Y2097179D02*
X3174863D01*
G01X3182737Y2081430D02*
Y2134580D01*
G01X3228012Y1999738D02*
G03I-2953J0D01*
G01Y2019423D02*
G03I-2953J0D01*
G01X3222107Y2061745D02*
X3796910D01*
G01X3222107Y2077493D02*
Y2061745D01*
G01Y2081430D02*
X3796910D01*
G01Y2077493D02*
X3222107D01*
G01Y2097179D02*
Y2081430D01*
G01X3796910Y2097179D02*
X3222107D01*
G01Y2101116D02*
Y2171982D01*
G01Y2164108D02*
X3517382D01*
G01X3267382Y1929856D02*
X3235886D01*
G01D02*
X3277225D01*
G01X3247697Y1999738D02*
G03I-2953J0D01*
G01Y2019423D02*
G03I-2953J0D01*
G01X3259738Y1911098D02*
X3260668Y1910056D01*
X3261753Y1909431D01*
X3263148Y1909223D01*
X3264543Y1909640D01*
X3265628Y1910473D01*
X3266403Y1911931D01*
X3266558Y1913598D01*
X3266248Y1915265D01*
X3265473Y1916306D01*
X3264388Y1917140D01*
X3263303Y1917348D01*
X3262218Y1917140D01*
X3260823Y1916306D01*
X3261288Y1921723D01*
X3265473D01*
G01X3271518Y1909223D02*
Y1921723D01*
X3275548Y1911306D01*
X3279578Y1921723D01*
Y1909223D01*
G01X3283918D02*
Y1921723D01*
X3287948Y1911306D01*
X3291978Y1921723D01*
Y1909223D01*
G01X3267382Y1992236D02*
Y1921982D01*
G01Y1999738D02*
G03I-2952J0D01*
G01Y2019423D02*
G03I-2952J0D01*
G01X3318563Y1929856D02*
X3277225D01*
G01X3318563Y1902297D02*
X3287067D01*
G01D02*
X3328406D01*
G01X3287067Y1992586D02*
Y1921982D01*
G01Y1929856D02*
X3318563D01*
G01X3292973Y1996785D02*
X3287067D01*
G01X3292973Y2002690D02*
Y1996785D01*
G01X3287067D02*
Y2002690D01*
G01D02*
X3292973D01*
G01X3287067Y2022375D02*
X3292973D01*
G01Y2016470D02*
X3287067D01*
G01X3292973Y2022375D02*
Y2016470D01*
G01X3287067D02*
Y2022375D01*
G01X3312738Y1879698D02*
X3313668Y1878656D01*
X3314753Y1878031D01*
X3316148Y1877823D01*
X3317543Y1878240D01*
X3318628Y1879073D01*
X3319403Y1880531D01*
X3319558Y1882198D01*
X3319248Y1883865D01*
X3318473Y1884906D01*
X3317388Y1885740D01*
X3316303Y1885948D01*
X3315218Y1885740D01*
X3313823Y1884906D01*
X3314288Y1890323D01*
X3318473D01*
G01X3324518Y1877823D02*
Y1890323D01*
X3328548Y1879906D01*
X3332578Y1890323D01*
Y1877823D01*
G01X3336918D02*
Y1890323D01*
X3340948Y1879906D01*
X3344978Y1890323D01*
Y1877823D01*
G01X3338248Y1953998D02*
X3306752D01*
G01D02*
X3341201D01*
G01X3318563Y1996785D02*
X3312658D01*
G01D02*
Y2002690D01*
G01D02*
X3318563D01*
G01X3312658Y2022375D02*
X3318563D01*
G01Y2016470D02*
X3312658D01*
G01D02*
Y2022375D01*
G01X3318563Y1992848D02*
Y1894423D01*
G01X3369744Y1902297D02*
X3328406D01*
G01X3318563Y2002690D02*
Y1996785D01*
G01Y2022375D02*
Y2016470D01*
G01X3338248Y1992848D02*
Y1894423D01*
G01Y1902297D02*
X3369744D01*
G01X3344154Y1992163D02*
Y1946124D01*
G01X3338248Y1988664D02*
Y1946124D01*
G01X3344154Y1953998D02*
X3410680D01*
G01D02*
X3341201D01*
G01X3344154Y1996785D02*
X3338248D01*
G01X3344154Y2002690D02*
Y1996785D01*
G01X3338248D02*
Y2002690D01*
G01D02*
X3344154D01*
G01X3338248Y2022375D02*
X3344154D01*
G01Y2016470D02*
X3338248D01*
G01X3344154Y2022375D02*
Y2016470D01*
G01X3338248D02*
Y2022375D01*
G01X3348091Y2016470D02*
X3467821D01*
G01X3348091Y2022375D02*
X3467821D01*
G01X3368163Y1956951D02*
Y1969451D01*
X3366303Y1966951D01*
G01Y1956951D02*
X3370023D01*
G01X3380563Y1956534D02*
X3380253Y1956743D01*
Y1957159D01*
X3380563Y1957368D01*
X3380873Y1957159D01*
Y1956743D01*
X3380563Y1956534D01*
G01X3389553Y1958826D02*
X3390483Y1957784D01*
X3391568Y1957159D01*
X3392963Y1956951D01*
X3394358Y1957368D01*
X3395443Y1958201D01*
X3396218Y1959659D01*
X3396373Y1961326D01*
X3396063Y1962993D01*
X3395288Y1964034D01*
X3394203Y1964868D01*
X3393118Y1965076D01*
X3392033Y1964868D01*
X3390638Y1964034D01*
X3391103Y1969451D01*
X3395288D01*
G01X3401333Y1956951D02*
Y1969451D01*
X3405363Y1959034D01*
X3409393Y1969451D01*
Y1956951D01*
G01X3413733D02*
Y1969451D01*
X3417763Y1959034D01*
X3421793Y1969451D01*
Y1956951D01*
G01X3397448Y2573989D02*
X3398248Y2573323D01*
X3399148Y2572923D01*
X3399948D01*
X3400748Y2573323D01*
X3401348Y2573989D01*
X3401648Y2574923D01*
X3401448Y2575856D01*
X3400948Y2576656D01*
X3400048Y2577190D01*
X3398848Y2577456D01*
X3398148Y2577990D01*
X3397848Y2578923D01*
X3398048Y2579856D01*
X3398548Y2580523D01*
X3399248Y2580923D01*
X3399948D01*
X3400648Y2580656D01*
X3401248Y2579990D01*
G01X3407548Y2572923D02*
X3406748Y2573056D01*
X3406048Y2573590D01*
X3405448Y2574390D01*
X3405048Y2575323D01*
X3404848Y2576390D01*
Y2577456D01*
X3405048Y2578523D01*
X3405448Y2579456D01*
X3406048Y2580256D01*
X3406748Y2580790D01*
X3407548Y2580923D01*
X3408348Y2580790D01*
X3409048Y2580256D01*
X3409648Y2579456D01*
X3410048Y2578523D01*
X3410248Y2577456D01*
Y2576390D01*
X3410048Y2575323D01*
X3409648Y2574390D01*
X3409048Y2573590D01*
X3408348Y2573056D01*
X3407548Y2572923D01*
G01X3413548Y2580923D02*
Y2572923D01*
X3417548D01*
G01X3421348D02*
Y2580923D01*
X3423348D01*
X3424148Y2580523D01*
X3424748Y2579990D01*
X3425248Y2579190D01*
X3425648Y2578256D01*
X3425748Y2576923D01*
X3425648Y2575590D01*
X3425248Y2574656D01*
X3424748Y2573856D01*
X3424148Y2573323D01*
X3423348Y2572923D01*
X3421348D01*
G01X3433548D02*
X3429548D01*
Y2580923D01*
X3433548D01*
G01X3431948Y2577056D02*
X3429548D01*
G01X3437548Y2572923D02*
Y2580923D01*
X3440048D01*
X3440848Y2580523D01*
X3441348Y2579990D01*
X3441548Y2578923D01*
X3441348Y2577856D01*
X3440748Y2577190D01*
X3440048Y2576790D01*
X3437548D01*
G01X3440048D02*
X3441548Y2572923D01*
G01X3444948D02*
Y2580923D01*
X3447548Y2574256D01*
X3450148Y2580923D01*
Y2572923D01*
G01X3453048D02*
X3455548Y2580923D01*
X3458048Y2572923D01*
G01X3457148Y2575723D02*
X3453948D01*
G01X3461448Y2573989D02*
X3462248Y2573323D01*
X3463148Y2572923D01*
X3463948D01*
X3464748Y2573323D01*
X3465348Y2573989D01*
X3465648Y2574923D01*
X3465448Y2575856D01*
X3464948Y2576656D01*
X3464048Y2577190D01*
X3462848Y2577456D01*
X3462148Y2577990D01*
X3461848Y2578923D01*
X3462048Y2579856D01*
X3462548Y2580523D01*
X3463248Y2580923D01*
X3463948D01*
X3464648Y2580656D01*
X3465248Y2579990D01*
G01X3469348Y2572923D02*
Y2580923D01*
G01X3473148D02*
X3469348Y2575989D01*
G01X3473748Y2572923D02*
X3471048Y2578256D01*
G01X3487548Y2572923D02*
X3486748Y2573056D01*
X3486048Y2573590D01*
X3485448Y2574390D01*
X3485048Y2575323D01*
X3484848Y2576390D01*
Y2577456D01*
X3485048Y2578523D01*
X3485448Y2579456D01*
X3486048Y2580256D01*
X3486748Y2580790D01*
X3487548Y2580923D01*
X3488348Y2580790D01*
X3489048Y2580256D01*
X3489648Y2579456D01*
X3490048Y2578523D01*
X3490248Y2577456D01*
Y2576390D01*
X3490048Y2575323D01*
X3489648Y2574390D01*
X3489048Y2573590D01*
X3488348Y2573056D01*
X3487548Y2572923D01*
G01X3493548D02*
Y2580923D01*
X3495948D01*
X3496748Y2580523D01*
X3497348Y2579590D01*
X3497548Y2578523D01*
X3497348Y2577456D01*
X3496848Y2576656D01*
X3495948Y2576256D01*
X3493548D01*
G01X3505548Y2572923D02*
X3501548D01*
Y2580923D01*
X3505548D01*
G01X3503948Y2577056D02*
X3501548D01*
G01X3509248Y2572923D02*
Y2580923D01*
X3513848Y2572923D01*
Y2580923D01*
G01X3527548Y2572923D02*
X3526748Y2573056D01*
X3526048Y2573590D01*
X3525448Y2574390D01*
X3525048Y2575323D01*
X3524848Y2576390D01*
Y2577456D01*
X3525048Y2578523D01*
X3525448Y2579456D01*
X3526048Y2580256D01*
X3526748Y2580790D01*
X3527548Y2580923D01*
X3528348Y2580790D01*
X3529048Y2580256D01*
X3529648Y2579456D01*
X3530048Y2578523D01*
X3530248Y2577456D01*
Y2576390D01*
X3530048Y2575323D01*
X3529648Y2574390D01*
X3529048Y2573590D01*
X3528348Y2573056D01*
X3527548Y2572923D01*
G01X3533248D02*
Y2580923D01*
X3537848Y2572923D01*
Y2580923D01*
G01X3552348Y2577190D02*
X3552748Y2577590D01*
X3553048Y2578256D01*
X3553248Y2579190D01*
X3553048Y2579990D01*
X3552648Y2580523D01*
X3551948Y2580923D01*
X3549248D01*
Y2572923D01*
X3552548D01*
X3553248Y2573456D01*
X3553648Y2574256D01*
X3553848Y2575190D01*
X3553648Y2576123D01*
X3553048Y2576923D01*
X3552348Y2577190D01*
X3549248D01*
G01X3559548Y2572923D02*
X3558748Y2573056D01*
X3558048Y2573590D01*
X3557448Y2574390D01*
X3557048Y2575323D01*
X3556848Y2576390D01*
Y2577456D01*
X3557048Y2578523D01*
X3557448Y2579456D01*
X3558048Y2580256D01*
X3558748Y2580790D01*
X3559548Y2580923D01*
X3560348Y2580790D01*
X3561048Y2580256D01*
X3561648Y2579456D01*
X3562048Y2578523D01*
X3562248Y2577456D01*
Y2576390D01*
X3562048Y2575323D01*
X3561648Y2574390D01*
X3561048Y2573590D01*
X3560348Y2573056D01*
X3559548Y2572923D01*
G01X3567548Y2580923D02*
Y2572923D01*
G01X3565248Y2580923D02*
X3569848D01*
G01X3573448Y2572923D02*
Y2580923D01*
G01X3577648D02*
Y2572923D01*
G01Y2576923D02*
X3573448D01*
G01X3589448Y2573989D02*
X3590248Y2573323D01*
X3591148Y2572923D01*
X3591948D01*
X3592748Y2573323D01*
X3593348Y2573989D01*
X3593648Y2574923D01*
X3593448Y2575856D01*
X3592948Y2576656D01*
X3592048Y2577190D01*
X3590848Y2577456D01*
X3590148Y2577990D01*
X3589848Y2578923D01*
X3590048Y2579856D01*
X3590548Y2580523D01*
X3591248Y2580923D01*
X3591948D01*
X3592648Y2580656D01*
X3593248Y2579990D01*
G01X3598348Y2580923D02*
X3600748D01*
G01X3599548D02*
Y2572923D01*
G01X3598348D02*
X3600748D01*
G01X3605348D02*
Y2580923D01*
X3607348D01*
X3608148Y2580523D01*
X3608748Y2579990D01*
X3609248Y2579190D01*
X3609648Y2578256D01*
X3609748Y2576923D01*
X3609648Y2575590D01*
X3609248Y2574656D01*
X3608748Y2573856D01*
X3608148Y2573323D01*
X3607348Y2572923D01*
X3605348D01*
G01X3617548D02*
X3613548D01*
Y2580923D01*
X3617548D01*
G01X3615948Y2577056D02*
X3613548D01*
G01X3623548Y2572656D02*
X3623348Y2572790D01*
Y2573056D01*
X3623548Y2573190D01*
X3623748Y2573056D01*
Y2572790D01*
X3623548Y2572656D01*
G01X3451089Y1907662D02*
X3438589D01*
X3441089Y1905802D01*
G01X3451089D02*
Y1909522D01*
G01X3451506Y1920062D02*
X3451297Y1919752D01*
X3450881D01*
X3450672Y1920062D01*
X3450881Y1920372D01*
X3451297D01*
X3451506Y1920062D01*
G01X3449214Y1929052D02*
X3450256Y1929982D01*
X3450881Y1931067D01*
X3451089Y1932462D01*
X3450672Y1933857D01*
X3449839Y1934942D01*
X3448381Y1935717D01*
X3446714Y1935872D01*
X3445047Y1935562D01*
X3444006Y1934787D01*
X3443172Y1933702D01*
X3442964Y1932617D01*
X3443172Y1931532D01*
X3444006Y1930137D01*
X3438589Y1930602D01*
Y1934787D01*
G01X3451089Y1940832D02*
X3438589D01*
X3449006Y1944862D01*
X3438589Y1948892D01*
X3451089D01*
G01Y1953232D02*
X3438589D01*
X3449006Y1957262D01*
X3438589Y1961292D01*
X3451089D01*
G01X3459947Y2016470D02*
Y1920651D01*
G01D02*
Y2019423D01*
G01Y2022375D02*
Y2053871D01*
G01D02*
Y2019423D01*
G01X3467782Y2167060D02*
Y2179560D01*
X3465922Y2177060D01*
G01Y2167060D02*
X3469642D01*
G01X3480182Y2179560D02*
X3478942Y2179143D01*
X3478012Y2178102D01*
X3477392Y2176852D01*
X3476927Y2175185D01*
X3476772Y2173310D01*
X3476927Y2171435D01*
X3477392Y2169768D01*
X3478012Y2168518D01*
X3478942Y2167477D01*
X3480182Y2167060D01*
X3481422Y2167477D01*
X3482352Y2168518D01*
X3482972Y2169768D01*
X3483437Y2171435D01*
X3483592Y2173310D01*
X3483437Y2175185D01*
X3482972Y2176852D01*
X3482352Y2178102D01*
X3481422Y2179143D01*
X3480182Y2179560D01*
G01X3492582D02*
X3491342Y2179143D01*
X3490412Y2178102D01*
X3489792Y2176852D01*
X3489327Y2175185D01*
X3489172Y2173310D01*
X3489327Y2171435D01*
X3489792Y2169768D01*
X3490412Y2168518D01*
X3491342Y2167477D01*
X3492582Y2167060D01*
X3493822Y2167477D01*
X3494752Y2168518D01*
X3495372Y2169768D01*
X3495837Y2171435D01*
X3495992Y2173310D01*
X3495837Y2175185D01*
X3495372Y2176852D01*
X3494752Y2178102D01*
X3493822Y2179143D01*
X3492582Y2179560D01*
G01X3502967Y2171227D02*
X3506997D01*
G01X3517382Y2167060D02*
Y2179560D01*
X3515522Y2177060D01*
G01Y2167060D02*
X3519242D01*
G01X3526372Y2168935D02*
X3527302Y2167893D01*
X3528387Y2167268D01*
X3529782Y2167060D01*
X3531177Y2167477D01*
X3532262Y2168310D01*
X3533037Y2169768D01*
X3533192Y2171435D01*
X3532882Y2173102D01*
X3532107Y2174143D01*
X3531022Y2174977D01*
X3529937Y2175185D01*
X3528852Y2174977D01*
X3527457Y2174143D01*
X3527922Y2179560D01*
X3532107D01*
G01X3542182D02*
X3540942Y2179143D01*
X3540012Y2178102D01*
X3539392Y2176852D01*
X3538927Y2175185D01*
X3538772Y2173310D01*
X3538927Y2171435D01*
X3539392Y2169768D01*
X3540012Y2168518D01*
X3540942Y2167477D01*
X3542182Y2167060D01*
X3543422Y2167477D01*
X3544352Y2168518D01*
X3544972Y2169768D01*
X3545437Y2171435D01*
X3545592Y2173310D01*
X3545437Y2175185D01*
X3544972Y2176852D01*
X3544352Y2178102D01*
X3543422Y2179143D01*
X3542182Y2179560D01*
G01X3550552Y2167060D02*
Y2179560D01*
X3554582Y2169143D01*
X3558612Y2179560D01*
Y2167060D01*
G01X3562952D02*
Y2179560D01*
X3566982Y2169143D01*
X3571012Y2179560D01*
Y2167060D01*
G01X3520548Y2009723D02*
X3522548D01*
Y2007323D01*
X3521948Y2006523D01*
X3521248Y2005990D01*
X3520248Y2005723D01*
X3519248Y2005990D01*
X3518548Y2006523D01*
X3517948Y2007323D01*
X3517548Y2008256D01*
X3517348Y2009323D01*
Y2010256D01*
X3517548Y2011056D01*
X3517948Y2011990D01*
X3518548Y2012790D01*
X3519148Y2013323D01*
X3519948Y2013723D01*
X3520648D01*
X3521448Y2013456D01*
X3522048Y2012923D01*
G01X3525948Y2005723D02*
Y2013723D01*
X3528448D01*
X3529248Y2013323D01*
X3529748Y2012790D01*
X3529948Y2011723D01*
X3529748Y2010656D01*
X3529148Y2009990D01*
X3528448Y2009590D01*
X3525948D01*
G01X3528448D02*
X3529948Y2005723D01*
G01X3535948D02*
X3535148Y2005856D01*
X3534448Y2006390D01*
X3533848Y2007190D01*
X3533448Y2008123D01*
X3533248Y2009190D01*
Y2010256D01*
X3533448Y2011323D01*
X3533848Y2012256D01*
X3534448Y2013056D01*
X3535148Y2013590D01*
X3535948Y2013723D01*
X3536748Y2013590D01*
X3537448Y2013056D01*
X3538048Y2012256D01*
X3538448Y2011323D01*
X3538648Y2010256D01*
Y2009190D01*
X3538448Y2008123D01*
X3538048Y2007190D01*
X3537448Y2006390D01*
X3536748Y2005856D01*
X3535948Y2005723D01*
G01X3541748Y2013723D02*
Y2007990D01*
X3542148Y2006789D01*
X3542948Y2005990D01*
X3543948Y2005723D01*
X3544948Y2005990D01*
X3545748Y2006789D01*
X3546148Y2007990D01*
Y2013723D01*
G01X3549948Y2005723D02*
Y2013723D01*
X3552348D01*
X3553148Y2013323D01*
X3553748Y2012390D01*
X3553948Y2011323D01*
X3553748Y2010256D01*
X3553248Y2009456D01*
X3552348Y2009056D01*
X3549948D01*
G01X3557848Y2006789D02*
X3558648Y2006123D01*
X3559548Y2005723D01*
X3560348D01*
X3561148Y2006123D01*
X3561748Y2006789D01*
X3562048Y2007723D01*
X3561848Y2008656D01*
X3561348Y2009456D01*
X3560448Y2009990D01*
X3559248Y2010256D01*
X3558548Y2010790D01*
X3558248Y2011723D01*
X3558448Y2012656D01*
X3558948Y2013323D01*
X3559648Y2013723D01*
X3560348D01*
X3561048Y2013456D01*
X3561648Y2012790D01*
G01X3576748Y2009990D02*
X3577148Y2010390D01*
X3577448Y2011056D01*
X3577648Y2011990D01*
X3577448Y2012790D01*
X3577048Y2013323D01*
X3576348Y2013723D01*
X3573648D01*
Y2005723D01*
X3576948D01*
X3577648Y2006256D01*
X3578048Y2007056D01*
X3578248Y2007990D01*
X3578048Y2008923D01*
X3577448Y2009723D01*
X3576748Y2009990D01*
X3573648D01*
G01X3812658Y2164108D02*
X3517382D01*
G01X3760008Y2142923D02*
Y2155423D01*
X3754273Y2146465D01*
X3762023D01*
G01X3766518Y2142923D02*
Y2155423D01*
X3770548Y2145006D01*
X3774578Y2155423D01*
Y2142923D01*
G01X3778918D02*
Y2155423D01*
X3782948Y2145006D01*
X3786978Y2155423D01*
Y2142923D01*
G01X3796910Y2136549D02*
X3765414D01*
G01D02*
X3804784D01*
G01X3812658Y2069619D02*
X3796910Y2077493D01*
G01Y2061745D02*
X3812658Y2069619D01*
G01X3848091Y2081430D02*
X3804784D01*
G01X3848091Y2077493D02*
X3804784D01*
G01X3796910Y2081430D02*
X3812658Y2089305D01*
G01X3796910Y2101116D02*
Y2144423D01*
G01X3812658Y2089305D02*
X3796910Y2097179D01*
G01X3844154Y2136549D02*
X3804784D01*
G01X3812658Y2093241D02*
Y2144423D01*
G01Y2093241D02*
Y2171982D01*
G01Y2136549D02*
X3844154D01*
G01X3828710Y2038316D02*
Y2081623D01*
G01X3852648Y2043723D02*
X3840148D01*
X3842648Y2041863D01*
G01X3852648D02*
Y2045583D01*
G01Y2052093D02*
X3840148D01*
X3850565Y2056123D01*
X3840148Y2060153D01*
X3852648D01*
G01Y2064493D02*
X3840148D01*
X3850565Y2068523D01*
X3840148Y2072553D01*
X3852648D01*
G01X3872648Y2079523D02*
X3874648D01*
Y2077123D01*
X3874048Y2076323D01*
X3873348Y2075790D01*
X3872348Y2075523D01*
X3871348Y2075790D01*
X3870648Y2076323D01*
X3870048Y2077123D01*
X3869648Y2078056D01*
X3869448Y2079123D01*
Y2080056D01*
X3869648Y2080856D01*
X3870048Y2081790D01*
X3870648Y2082590D01*
X3871248Y2083123D01*
X3872048Y2083523D01*
X3872748D01*
X3873548Y2083256D01*
X3874148Y2082723D01*
G01X3878048Y2075523D02*
Y2083523D01*
X3880548D01*
X3881348Y2083123D01*
X3881848Y2082590D01*
X3882048Y2081523D01*
X3881848Y2080456D01*
X3881248Y2079790D01*
X3880548Y2079390D01*
X3878048D01*
G01X3880548D02*
X3882048Y2075523D01*
G01X3888048D02*
X3887248Y2075656D01*
X3886548Y2076190D01*
X3885948Y2076990D01*
X3885548Y2077923D01*
X3885348Y2078990D01*
Y2080056D01*
X3885548Y2081123D01*
X3885948Y2082056D01*
X3886548Y2082856D01*
X3887248Y2083390D01*
X3888048Y2083523D01*
X3888848Y2083390D01*
X3889548Y2082856D01*
X3890148Y2082056D01*
X3890548Y2081123D01*
X3890748Y2080056D01*
Y2078990D01*
X3890548Y2077923D01*
X3890148Y2076990D01*
X3889548Y2076190D01*
X3888848Y2075656D01*
X3888048Y2075523D01*
G01X3893848Y2083523D02*
Y2077790D01*
X3894248Y2076589D01*
X3895048Y2075790D01*
X3896048Y2075523D01*
X3897048Y2075790D01*
X3897848Y2076589D01*
X3898248Y2077790D01*
Y2083523D01*
G01X3902048Y2075523D02*
Y2083523D01*
X3904448D01*
X3905248Y2083123D01*
X3905848Y2082190D01*
X3906048Y2081123D01*
X3905848Y2080056D01*
X3905348Y2079256D01*
X3904448Y2078856D01*
X3902048D01*
G01X3909948Y2076589D02*
X3910748Y2075923D01*
X3911648Y2075523D01*
X3912448D01*
X3913248Y2075923D01*
X3913848Y2076589D01*
X3914148Y2077523D01*
X3913948Y2078456D01*
X3913448Y2079256D01*
X3912548Y2079790D01*
X3911348Y2080056D01*
X3910648Y2080590D01*
X3910348Y2081523D01*
X3910548Y2082456D01*
X3911048Y2083123D01*
X3911748Y2083523D01*
X3912448D01*
X3913148Y2083256D01*
X3913748Y2082590D01*
G01X3925548Y2075523D02*
X3928048Y2083523D01*
X3930548Y2075523D01*
G01X3929648Y2078323D02*
X3926448D01*
G01X4253970Y132356D02*
Y232356D01*
X5004170D01*
Y132356D01*
X4253970D01*
G01Y157356D02*
X5004170D01*
G01X4253970Y182356D02*
X5004170D01*
G01X4253970Y207356D02*
X5004170D01*
G01X4259757Y-124585D02*
Y-24585D01*
X5009957D01*
Y-124585D01*
X4259757D01*
G01Y-99585D02*
X5009957D01*
G01X4259757Y-74585D02*
X5009957D01*
G01X4259757Y-49585D02*
X5009957D01*
G01X4257470Y403356D02*
Y503356D01*
X5007670D01*
Y403356D01*
X4257470D01*
G01Y428356D02*
X5007670D01*
G01X4257470Y453356D02*
X5007670D01*
G01X4257470Y478356D02*
X5007670D01*
G01X4258470Y675856D02*
Y775856D01*
X5008670D01*
Y675856D01*
X4258470D01*
G01Y700856D02*
X5008670D01*
G01X4258470Y725856D02*
X5008670D01*
G01X4258470Y750856D02*
X5008670D01*
G01X4256970Y979856D02*
Y1079856D01*
X5007170D01*
Y979856D01*
X4256970D01*
G01Y1004856D02*
X5007170D01*
G01X4256970Y1029856D02*
X5007170D01*
G01X4256970Y1054856D02*
X5007170D01*
G01X4261970Y1296356D02*
Y1396356D01*
X5012170D01*
Y1296356D01*
X4261970D01*
G01Y1321356D02*
X5012170D01*
G01X4261970Y1346356D02*
X5012170D01*
G01X4261970Y1371356D02*
X5012170D01*
G01X4264648Y1611795D02*
Y1711795D01*
X5014848D01*
Y1611795D01*
X4264648D01*
G01Y1636795D02*
X5014848D01*
G01X4264648Y1661795D02*
X5014848D01*
G01X4264648Y1686795D02*
X5014848D01*
G01X4343870Y182356D02*
Y132356D01*
G01X4349657Y-74585D02*
Y-124585D01*
G01X4347370Y453356D02*
Y403356D01*
G01X4348370Y725856D02*
Y675856D01*
G01X4346870Y1029856D02*
Y979856D01*
G01X4351870Y1346356D02*
Y1296356D01*
G01X4354548Y1661795D02*
Y1611795D01*
G01X4476757Y-74585D02*
Y-124585D01*
G01X4470970Y182356D02*
Y132356D01*
G01X4474470Y453356D02*
Y403356D01*
G01X4475470Y725856D02*
Y675856D01*
G01X4473970Y1029856D02*
Y979856D01*
G01X4478970Y1346356D02*
Y1296356D01*
G01X4481648Y1661795D02*
Y1611795D01*
G01X4672470Y182356D02*
Y132356D01*
G01X4678257Y-74585D02*
Y-124585D01*
G01X4675970Y453356D02*
Y403356D01*
G01X4676970Y725856D02*
Y675856D01*
G01X4675470Y1029856D02*
Y979856D01*
G01X4680470Y1346356D02*
Y1296356D01*
G01X4683148Y1661795D02*
Y1611795D01*
G01X4805357Y-74585D02*
Y-124585D01*
G01X4799570Y182356D02*
Y132356D01*
G01X4803070Y453356D02*
Y403356D01*
G01X4804070Y725856D02*
Y675856D01*
G01X4802570Y1029856D02*
Y979856D01*
G01X4807570Y1346356D02*
Y1296356D01*
G01X4810248Y1661795D02*
Y1611795D01*
G01X4932457Y-74585D02*
Y-124585D01*
G01X4926670Y182356D02*
Y132356D01*
G01X4930170Y453356D02*
Y403356D01*
G01X4931170Y725856D02*
Y675856D01*
G01X4929670Y1029856D02*
Y979856D01*
G01X4934670Y1346356D02*
Y1296356D01*
G01X4937348Y1661795D02*
Y1611795D01*
G01X5071614Y106866D02*
Y231866D01*
X5821814D01*
Y106866D01*
X5071614D01*
G01Y131866D02*
X5821814D01*
G01X5071614Y156866D02*
X5821814D01*
G01X5071614Y181866D02*
X5821814D01*
G01X5071614Y206866D02*
X5821814D01*
G01X5071580Y379685D02*
Y504685D01*
X5821780D01*
Y379685D01*
X5071580D01*
G01Y404685D02*
X5821780D01*
G01X5071580Y429685D02*
X5821780D01*
G01X5071580Y454685D02*
X5821780D01*
G01X5071580Y479685D02*
X5821780D01*
G01X5074170Y650856D02*
Y775856D01*
X5824370D01*
Y650856D01*
X5074170D01*
G01Y675856D02*
X5824370D01*
G01X5074170Y700856D02*
X5824370D01*
G01X5074170Y725856D02*
X5824370D01*
G01X5074170Y750856D02*
X5824370D01*
G01X5075170Y1222356D02*
Y1397356D01*
X5825370D01*
Y1222356D01*
X5075170D01*
G01Y1247356D02*
X5825370D01*
G01X5075170Y1272356D02*
X5825370D01*
G01X5075170Y1297356D02*
X5825370D01*
G01X5075170Y1322356D02*
X5825370D01*
G01X5075170Y1347356D02*
X5825370D01*
G01X5075170Y1372356D02*
X5825370D01*
G01X5075170Y1537856D02*
Y1712856D01*
X5825370D01*
Y1537856D01*
X5075170D01*
G01Y1562856D02*
X5825370D01*
G01X5075170Y1587856D02*
X5825370D01*
G01X5075170Y1612856D02*
X5825370D01*
G01X5075170Y1637856D02*
X5825370D01*
G01X5075170Y1662856D02*
X5825370D01*
G01X5075170Y1687856D02*
X5825370D01*
G01X5076170Y908356D02*
Y1083356D01*
X5826370D01*
Y908356D01*
X5076170D01*
G01Y933356D02*
X5826370D01*
G01X5076170Y958356D02*
X5826370D01*
G01X5076170Y983356D02*
X5826370D01*
G01X5076170Y1008356D02*
X5826370D01*
G01X5076170Y1033356D02*
X5826370D01*
G01X5076170Y1058356D02*
X5826370D01*
G01X5161514Y181866D02*
Y106866D01*
G01X5161480Y454685D02*
Y379685D01*
G01X5164070Y725856D02*
Y650856D01*
G01X5166070Y1033356D02*
Y908356D01*
G01X5165070Y1347356D02*
Y1222356D01*
G01Y1662856D02*
Y1537856D01*
G01X5288614Y181866D02*
Y106866D01*
G01X5288580Y454685D02*
Y379685D01*
G01X5291170Y725856D02*
Y650856D01*
G01X5293170Y1033356D02*
Y908356D01*
G01X5292170Y1347356D02*
Y1222356D01*
G01Y1662856D02*
Y1537856D01*
G01X5490114Y181866D02*
Y106866D01*
G01X5490080Y454685D02*
Y379685D01*
G01X5492670Y725856D02*
Y650856D01*
G01X5494670Y1033356D02*
Y908356D01*
G01X5493670Y1347356D02*
Y1222356D01*
G01Y1662856D02*
Y1537856D01*
G01X5617214Y181866D02*
Y106866D01*
G01X5617180Y454685D02*
Y379685D01*
G01X5619770Y725856D02*
Y650856D01*
G01X5621770Y1033356D02*
Y908356D01*
G01X5620770Y1347356D02*
Y1222356D01*
G01Y1662856D02*
Y1537856D01*
G01X5744314Y181866D02*
Y106866D01*
G01X5744280Y454685D02*
Y379685D01*
G01X5746870Y725856D02*
Y650856D01*
G01X5748870Y1033356D02*
Y908356D01*
G01X5747870Y1347356D02*
Y1222356D01*
G01Y1662856D02*
Y1537856D01*
G01X-476840Y-884638D02*
Y2768362D01*
X5911000D01*
Y-884638D01*
X-476840D01*
G01X-399280Y534165D02*
X-398350Y533123D01*
X-397265Y532498D01*
X-395870Y532290D01*
X-394475Y532707D01*
X-393390Y533540D01*
X-392615Y534998D01*
X-392460Y536665D01*
X-392770Y538332D01*
X-393545Y539373D01*
X-394630Y540207D01*
X-395715Y540415D01*
X-396800Y540207D01*
X-398195Y539373D01*
X-397730Y544790D01*
X-393545D01*
G01X-383780Y532290D02*
X-383470Y534998D01*
X-383005Y537290D01*
X-382385Y539373D01*
X-381610Y541665D01*
X-380370Y544790D01*
X-386570D01*
G01X-371070Y532290D02*
X-369985Y532498D01*
X-368745Y533123D01*
X-367970Y534165D01*
X-367660Y535623D01*
X-367970Y537081D01*
X-368900Y538332D01*
X-370295Y538957D01*
X-371845D01*
X-372775Y539373D01*
X-373550Y540415D01*
X-373860Y541873D01*
X-373395Y543332D01*
X-372310Y544373D01*
X-371070Y544790D01*
X-369830Y544373D01*
X-368745Y543332D01*
X-368280Y541873D01*
X-368590Y540415D01*
X-369365Y539373D01*
X-370295Y538957D01*
X-371845D01*
X-373240Y538332D01*
X-374170Y537081D01*
X-374480Y535623D01*
X-374170Y534165D01*
X-373395Y533123D01*
X-372155Y532498D01*
X-371070Y532290D01*
G01X-358670D02*
Y544790D01*
X-360530Y542290D01*
G01Y532290D02*
X-356810D01*
G01X-346270Y531873D02*
X-346580Y532082D01*
Y532498D01*
X-346270Y532707D01*
X-345960Y532498D01*
Y532082D01*
X-346270Y531873D01*
G01X-334180Y532290D02*
X-333870Y534998D01*
X-333405Y537290D01*
X-332785Y539373D01*
X-332010Y541665D01*
X-330770Y544790D01*
X-336970D01*
G01X-319610Y532290D02*
Y544790D01*
X-325345Y535832D01*
X-317595D01*
G01X-398815Y604369D02*
X-397730Y605828D01*
X-396800Y606661D01*
X-395560Y607078D01*
X-394475Y606661D01*
X-393700Y605828D01*
X-393080Y604578D01*
X-392925Y603119D01*
X-393080Y601869D01*
X-393700Y600619D01*
X-394630Y599578D01*
X-395715Y599161D01*
X-396955Y599578D01*
X-398040Y600827D01*
X-398660Y602703D01*
X-398815Y604786D01*
X-398505Y607494D01*
X-398040Y608953D01*
X-397265Y610411D01*
X-396180Y611453D01*
X-395095Y611661D01*
X-394010Y611244D01*
X-393235Y610203D01*
G01X-383470Y611661D02*
X-384710Y611244D01*
X-385640Y610203D01*
X-386260Y608953D01*
X-386725Y607286D01*
X-386880Y605411D01*
X-386725Y603536D01*
X-386260Y601869D01*
X-385640Y600619D01*
X-384710Y599578D01*
X-383470Y599161D01*
X-382230Y599578D01*
X-381300Y600619D01*
X-380680Y601869D01*
X-380215Y603536D01*
X-380060Y605411D01*
X-380215Y607286D01*
X-380680Y608953D01*
X-381300Y610203D01*
X-382230Y611244D01*
X-383470Y611661D01*
G01X-374480Y601036D02*
X-373550Y599994D01*
X-372465Y599369D01*
X-371070Y599161D01*
X-369675Y599578D01*
X-368590Y600411D01*
X-367815Y601869D01*
X-367660Y603536D01*
X-367970Y605203D01*
X-368745Y606244D01*
X-369830Y607078D01*
X-370915Y607286D01*
X-372000Y607078D01*
X-373395Y606244D01*
X-372930Y611661D01*
X-368745D01*
G01X-356810Y599161D02*
Y611661D01*
X-362545Y602703D01*
X-354795D01*
G01X-346270Y598744D02*
X-346580Y598953D01*
Y599369D01*
X-346270Y599578D01*
X-345960Y599369D01*
Y598953D01*
X-346270Y598744D01*
G01X-333870Y599161D02*
Y611661D01*
X-335730Y609161D01*
G01Y599161D02*
X-332010D01*
G01X-321470D02*
Y611661D01*
X-323330Y609161D01*
G01Y599161D02*
X-319610D01*
G01X-398495Y650088D02*
X-397410Y651547D01*
X-396480Y652380D01*
X-395240Y652797D01*
X-394155Y652380D01*
X-393380Y651547D01*
X-392760Y650297D01*
X-392605Y648838D01*
X-392760Y647588D01*
X-393380Y646338D01*
X-394310Y645297D01*
X-395395Y644880D01*
X-396635Y645297D01*
X-397720Y646546D01*
X-398340Y648422D01*
X-398495Y650505D01*
X-398185Y653213D01*
X-397720Y654672D01*
X-396945Y656130D01*
X-395860Y657172D01*
X-394775Y657380D01*
X-393690Y656963D01*
X-392915Y655922D01*
G01X-381290Y644880D02*
Y657380D01*
X-387025Y648422D01*
X-379275D01*
G01X-373695Y655297D02*
X-372765Y656546D01*
X-371680Y657172D01*
X-370440Y657380D01*
X-368890Y656963D01*
X-367805Y655922D01*
X-367495Y654672D01*
X-367650Y653421D01*
X-368270Y652380D01*
X-371370Y650297D01*
X-372765Y648838D01*
X-373695Y646755D01*
X-374005Y644880D01*
X-367495D01*
G01X-360985Y646338D02*
X-359900Y645297D01*
X-358660Y644880D01*
X-357420Y645297D01*
X-356335Y646546D01*
X-355560Y648422D01*
X-355250Y650297D01*
Y652588D01*
X-355560Y654463D01*
X-356335Y656130D01*
X-357265Y656963D01*
X-358350Y657380D01*
X-359590Y656963D01*
X-360520Y656130D01*
X-361140Y654880D01*
X-361450Y653213D01*
X-361140Y651755D01*
X-360365Y650297D01*
X-359435Y649463D01*
X-358350Y649255D01*
X-357110Y649671D01*
X-356180Y650713D01*
X-355250Y652588D01*
G01X-345950Y644463D02*
X-346260Y644672D01*
Y645088D01*
X-345950Y645297D01*
X-345640Y645088D01*
Y644672D01*
X-345950Y644463D01*
G01X-333860Y644880D02*
X-333550Y647588D01*
X-333085Y649880D01*
X-332465Y651963D01*
X-331690Y654255D01*
X-330450Y657380D01*
X-336650D01*
G01X-324095Y655297D02*
X-323165Y656546D01*
X-322080Y657172D01*
X-320840Y657380D01*
X-319290Y656963D01*
X-318205Y655922D01*
X-317895Y654672D01*
X-318050Y653421D01*
X-318670Y652380D01*
X-321770Y650297D01*
X-323165Y648838D01*
X-324095Y646755D01*
X-324405Y644880D01*
X-317895D01*
G01X-399785Y681300D02*
X-398700Y682759D01*
X-397770Y683592D01*
X-396530Y684009D01*
X-395445Y683592D01*
X-394670Y682759D01*
X-394050Y681509D01*
X-393895Y680050D01*
X-394050Y678800D01*
X-394670Y677550D01*
X-395600Y676509D01*
X-396685Y676092D01*
X-397925Y676509D01*
X-399010Y677758D01*
X-399630Y679634D01*
X-399785Y681717D01*
X-399475Y684425D01*
X-399010Y685884D01*
X-398235Y687342D01*
X-397150Y688384D01*
X-396065Y688592D01*
X-394980Y688175D01*
X-394205Y687134D01*
G01X-384440Y676092D02*
X-383355Y676300D01*
X-382115Y676925D01*
X-381340Y677967D01*
X-381030Y679425D01*
X-381340Y680883D01*
X-382270Y682134D01*
X-383665Y682759D01*
X-385215D01*
X-386145Y683175D01*
X-386920Y684217D01*
X-387230Y685675D01*
X-386765Y687134D01*
X-385680Y688175D01*
X-384440Y688592D01*
X-383200Y688175D01*
X-382115Y687134D01*
X-381650Y685675D01*
X-381960Y684217D01*
X-382735Y683175D01*
X-383665Y682759D01*
X-385215D01*
X-386610Y682134D01*
X-387540Y680883D01*
X-387850Y679425D01*
X-387540Y677967D01*
X-386765Y676925D01*
X-385525Y676300D01*
X-384440Y676092D01*
G01X-374985Y686509D02*
X-374055Y687758D01*
X-372970Y688384D01*
X-371730Y688592D01*
X-370180Y688175D01*
X-369095Y687134D01*
X-368785Y685884D01*
X-368940Y684633D01*
X-369560Y683592D01*
X-372660Y681509D01*
X-374055Y680050D01*
X-374985Y677967D01*
X-375295Y676092D01*
X-368785D01*
G01X-363050Y678592D02*
X-362120Y677133D01*
X-360880Y676300D01*
X-359485Y676092D01*
X-358245Y676300D01*
X-357005Y677342D01*
X-356230Y678592D01*
X-356075Y679842D01*
X-356385Y681300D01*
X-357470Y682342D01*
X-358555Y682759D01*
X-359950D01*
G01X-358555D02*
X-357625Y683384D01*
X-356850Y684425D01*
X-356540Y685675D01*
X-356850Y686925D01*
X-357625Y687967D01*
X-359020Y688592D01*
X-360415Y688384D01*
X-361810Y687550D01*
G01X-347240Y675675D02*
X-347550Y675884D01*
Y676300D01*
X-347240Y676509D01*
X-346930Y676300D01*
Y675884D01*
X-347240Y675675D01*
G01X-332980Y676092D02*
Y688592D01*
X-338715Y679634D01*
X-330965D01*
G01X-325385Y686509D02*
X-324455Y687758D01*
X-323370Y688384D01*
X-322130Y688592D01*
X-320580Y688175D01*
X-319495Y687134D01*
X-319185Y685884D01*
X-319340Y684633D01*
X-319960Y683592D01*
X-323060Y681509D01*
X-324455Y680050D01*
X-325385Y677967D01*
X-325695Y676092D01*
X-319185D01*
G01X-382880Y164420D02*
Y176920D01*
X-384740Y174420D01*
G01Y164420D02*
X-381020D01*
G01X-373890Y166295D02*
X-372960Y165253D01*
X-371875Y164628D01*
X-370480Y164420D01*
X-369085Y164837D01*
X-368000Y165670D01*
X-367225Y167128D01*
X-367070Y168795D01*
X-367380Y170462D01*
X-368155Y171503D01*
X-369240Y172337D01*
X-370325Y172545D01*
X-371410Y172337D01*
X-372805Y171503D01*
X-372340Y176920D01*
X-368155D01*
G01X-361490Y166295D02*
X-360560Y165253D01*
X-359475Y164628D01*
X-358080Y164420D01*
X-356685Y164837D01*
X-355600Y165670D01*
X-354825Y167128D01*
X-354670Y168795D01*
X-354980Y170462D01*
X-355755Y171503D01*
X-356840Y172337D01*
X-357925Y172545D01*
X-359010Y172337D01*
X-360405Y171503D01*
X-359940Y176920D01*
X-355755D01*
G01X-345680Y164420D02*
Y176920D01*
X-347540Y174420D01*
G01Y164420D02*
X-343820D01*
G01X-333280Y164003D02*
X-333590Y164212D01*
Y164628D01*
X-333280Y164837D01*
X-332970Y164628D01*
Y164212D01*
X-333280Y164003D01*
G01X-323515Y165878D02*
X-322430Y164837D01*
X-321190Y164420D01*
X-319950Y164837D01*
X-318865Y166086D01*
X-318090Y167962D01*
X-317780Y169837D01*
Y172128D01*
X-318090Y174003D01*
X-318865Y175670D01*
X-319795Y176503D01*
X-320880Y176920D01*
X-322120Y176503D01*
X-323050Y175670D01*
X-323670Y174420D01*
X-323980Y172753D01*
X-323670Y171295D01*
X-322895Y169837D01*
X-321965Y169003D01*
X-320880Y168795D01*
X-319640Y169211D01*
X-318710Y170253D01*
X-317780Y172128D01*
G01X-308790Y164420D02*
X-308480Y167128D01*
X-308015Y169420D01*
X-307395Y171503D01*
X-306620Y173795D01*
X-305380Y176920D01*
X-311580D01*
G01X-383200Y191600D02*
Y204100D01*
X-385060Y201600D01*
G01Y191600D02*
X-381340D01*
G01X-374210Y193475D02*
X-373280Y192433D01*
X-372195Y191808D01*
X-370800Y191600D01*
X-369405Y192017D01*
X-368320Y192850D01*
X-367545Y194308D01*
X-367390Y195975D01*
X-367700Y197642D01*
X-368475Y198683D01*
X-369560Y199517D01*
X-370645Y199725D01*
X-371730Y199517D01*
X-373125Y198683D01*
X-372660Y204100D01*
X-368475D01*
G01X-361035Y193058D02*
X-359950Y192017D01*
X-358710Y191600D01*
X-357470Y192017D01*
X-356385Y193266D01*
X-355610Y195142D01*
X-355300Y197017D01*
Y199308D01*
X-355610Y201183D01*
X-356385Y202850D01*
X-357315Y203683D01*
X-358400Y204100D01*
X-359640Y203683D01*
X-360570Y202850D01*
X-361190Y201600D01*
X-361500Y199933D01*
X-361190Y198475D01*
X-360415Y197017D01*
X-359485Y196183D01*
X-358400Y195975D01*
X-357160Y196391D01*
X-356230Y197433D01*
X-355300Y199308D01*
G01X-346000Y191600D02*
Y204100D01*
X-347860Y201600D01*
G01Y191600D02*
X-344140D01*
G01X-333600Y191183D02*
X-333910Y191392D01*
Y191808D01*
X-333600Y192017D01*
X-333290Y191808D01*
Y191392D01*
X-333600Y191183D01*
G01X-324610Y194100D02*
X-323680Y192641D01*
X-322440Y191808D01*
X-321045Y191600D01*
X-319805Y191808D01*
X-318565Y192850D01*
X-317790Y194100D01*
X-317635Y195350D01*
X-317945Y196808D01*
X-319030Y197850D01*
X-320115Y198267D01*
X-321510D01*
G01X-320115D02*
X-319185Y198892D01*
X-318410Y199933D01*
X-318100Y201183D01*
X-318410Y202433D01*
X-319185Y203475D01*
X-320580Y204100D01*
X-321975Y203892D01*
X-323370Y203058D01*
G01X-306940Y191600D02*
Y204100D01*
X-312675Y195142D01*
X-304925D01*
G01X-383850Y209720D02*
Y222220D01*
X-385710Y219720D01*
G01Y209720D02*
X-381990D01*
G01X-371760D02*
X-371450Y212428D01*
X-370985Y214720D01*
X-370365Y216803D01*
X-369590Y219095D01*
X-368350Y222220D01*
X-374550D01*
G01X-362460Y211595D02*
X-361530Y210553D01*
X-360445Y209928D01*
X-359050Y209720D01*
X-357655Y210137D01*
X-356570Y210970D01*
X-355795Y212428D01*
X-355640Y214095D01*
X-355950Y215762D01*
X-356725Y216803D01*
X-357810Y217637D01*
X-358895Y217845D01*
X-359980Y217637D01*
X-361375Y216803D01*
X-360910Y222220D01*
X-356725D01*
G01X-346650Y209720D02*
Y222220D01*
X-348510Y219720D01*
G01Y209720D02*
X-344790D01*
G01X-334250Y209303D02*
X-334560Y209512D01*
Y209928D01*
X-334250Y210137D01*
X-333940Y209928D01*
Y209512D01*
X-334250Y209303D01*
G01X-322160Y209720D02*
X-321850Y212428D01*
X-321385Y214720D01*
X-320765Y216803D01*
X-319990Y219095D01*
X-318750Y222220D01*
X-324950D01*
G01X-309760Y209720D02*
X-309450Y212428D01*
X-308985Y214720D01*
X-308365Y216803D01*
X-307590Y219095D01*
X-306350Y222220D01*
X-312550D01*
G01X-389385Y281403D02*
X-388455Y282652D01*
X-387370Y283278D01*
X-386130Y283486D01*
X-384580Y283069D01*
X-383495Y282028D01*
X-383185Y280778D01*
X-383340Y279527D01*
X-383960Y278486D01*
X-387060Y276403D01*
X-388455Y274944D01*
X-389385Y272861D01*
X-389695Y270986D01*
X-383185D01*
G01X-374350D02*
X-374040Y273694D01*
X-373575Y275986D01*
X-372955Y278069D01*
X-372180Y280361D01*
X-370940Y283486D01*
X-377140D01*
G01X-361950Y270986D02*
X-361640Y273694D01*
X-361175Y275986D01*
X-360555Y278069D01*
X-359780Y280361D01*
X-358540Y283486D01*
X-364740D01*
G01X-352185Y281403D02*
X-351255Y282652D01*
X-350170Y283278D01*
X-348930Y283486D01*
X-347380Y283069D01*
X-346295Y282028D01*
X-345985Y280778D01*
X-346140Y279527D01*
X-346760Y278486D01*
X-349860Y276403D01*
X-351255Y274944D01*
X-352185Y272861D01*
X-352495Y270986D01*
X-345985D01*
G01X-336840Y270569D02*
X-337150Y270778D01*
Y271194D01*
X-336840Y271403D01*
X-336530Y271194D01*
Y270778D01*
X-336840Y270569D01*
G01X-327850Y273486D02*
X-326920Y272027D01*
X-325680Y271194D01*
X-324285Y270986D01*
X-323045Y271194D01*
X-321805Y272236D01*
X-321030Y273486D01*
X-320875Y274736D01*
X-321185Y276194D01*
X-322270Y277236D01*
X-323355Y277653D01*
X-324750D01*
G01X-323355D02*
X-322425Y278278D01*
X-321650Y279319D01*
X-321340Y280569D01*
X-321650Y281819D01*
X-322425Y282861D01*
X-323820Y283486D01*
X-325215Y283278D01*
X-326610Y282444D01*
G01X-314985Y276194D02*
X-313900Y277653D01*
X-312970Y278486D01*
X-311730Y278903D01*
X-310645Y278486D01*
X-309870Y277653D01*
X-309250Y276403D01*
X-309095Y274944D01*
X-309250Y273694D01*
X-309870Y272444D01*
X-310800Y271403D01*
X-311885Y270986D01*
X-313125Y271403D01*
X-314210Y272652D01*
X-314830Y274528D01*
X-314985Y276611D01*
X-314675Y279319D01*
X-314210Y280778D01*
X-313435Y282236D01*
X-312350Y283278D01*
X-311265Y283486D01*
X-310180Y283069D01*
X-309405Y282028D01*
G01X-387910Y577928D02*
X-386980Y576886D01*
X-385895Y576261D01*
X-384500Y576053D01*
X-383105Y576470D01*
X-382020Y577303D01*
X-381245Y578761D01*
X-381090Y580428D01*
X-381400Y582095D01*
X-382175Y583136D01*
X-383260Y583970D01*
X-384345Y584178D01*
X-385430Y583970D01*
X-386825Y583136D01*
X-386360Y588553D01*
X-382175D01*
G01X-372100Y576053D02*
X-371015Y576261D01*
X-369775Y576886D01*
X-369000Y577928D01*
X-368690Y579386D01*
X-369000Y580844D01*
X-369930Y582095D01*
X-371325Y582720D01*
X-372875D01*
X-373805Y583136D01*
X-374580Y584178D01*
X-374890Y585636D01*
X-374425Y587095D01*
X-373340Y588136D01*
X-372100Y588553D01*
X-370860Y588136D01*
X-369775Y587095D01*
X-369310Y585636D01*
X-369620Y584178D01*
X-370395Y583136D01*
X-371325Y582720D01*
X-372875D01*
X-374270Y582095D01*
X-375200Y580844D01*
X-375510Y579386D01*
X-375200Y577928D01*
X-374425Y576886D01*
X-373185Y576261D01*
X-372100Y576053D01*
G01X-362645Y586470D02*
X-361715Y587719D01*
X-360630Y588345D01*
X-359390Y588553D01*
X-357840Y588136D01*
X-356755Y587095D01*
X-356445Y585845D01*
X-356600Y584594D01*
X-357220Y583553D01*
X-360320Y581470D01*
X-361715Y580011D01*
X-362645Y577928D01*
X-362955Y576053D01*
X-356445D01*
G01X-350710Y578553D02*
X-349780Y577094D01*
X-348540Y576261D01*
X-347145Y576053D01*
X-345905Y576261D01*
X-344665Y577303D01*
X-343890Y578553D01*
X-343735Y579803D01*
X-344045Y581261D01*
X-345130Y582303D01*
X-346215Y582720D01*
X-347610D01*
G01X-346215D02*
X-345285Y583345D01*
X-344510Y584386D01*
X-344200Y585636D01*
X-344510Y586886D01*
X-345285Y587928D01*
X-346680Y588553D01*
X-348075Y588345D01*
X-349470Y587511D01*
G01X-334900Y575636D02*
X-335210Y575845D01*
Y576261D01*
X-334900Y576470D01*
X-334590Y576261D01*
Y575845D01*
X-334900Y575636D01*
G01X-322500Y588553D02*
X-323740Y588136D01*
X-324670Y587095D01*
X-325290Y585845D01*
X-325755Y584178D01*
X-325910Y582303D01*
X-325755Y580428D01*
X-325290Y578761D01*
X-324670Y577511D01*
X-323740Y576470D01*
X-322500Y576053D01*
X-321260Y576470D01*
X-320330Y577511D01*
X-319710Y578761D01*
X-319245Y580428D01*
X-319090Y582303D01*
X-319245Y584178D01*
X-319710Y585845D01*
X-320330Y587095D01*
X-321260Y588136D01*
X-322500Y588553D01*
G01X-313510Y578553D02*
X-312580Y577094D01*
X-311340Y576261D01*
X-309945Y576053D01*
X-308705Y576261D01*
X-307465Y577303D01*
X-306690Y578553D01*
X-306535Y579803D01*
X-306845Y581261D01*
X-307930Y582303D01*
X-309015Y582720D01*
X-310410D01*
G01X-309015D02*
X-308085Y583345D01*
X-307310Y584386D01*
X-307000Y585636D01*
X-307310Y586886D01*
X-308085Y587928D01*
X-309480Y588553D01*
X-310875Y588345D01*
X-312270Y587511D01*
G01X-376840Y1692018D02*
Y1704518D01*
X-378700Y1702018D01*
G01Y1692018D02*
X-374980D01*
G01X-367385Y1697226D02*
X-366300Y1698685D01*
X-365370Y1699518D01*
X-364130Y1699935D01*
X-363045Y1699518D01*
X-362270Y1698685D01*
X-361650Y1697435D01*
X-361495Y1695976D01*
X-361650Y1694726D01*
X-362270Y1693476D01*
X-363200Y1692435D01*
X-364285Y1692018D01*
X-365525Y1692435D01*
X-366610Y1693684D01*
X-367230Y1695560D01*
X-367385Y1697643D01*
X-367075Y1700351D01*
X-366610Y1701810D01*
X-365835Y1703268D01*
X-364750Y1704310D01*
X-363665Y1704518D01*
X-362580Y1704101D01*
X-361805Y1703060D01*
G01X-354675Y1693476D02*
X-353590Y1692435D01*
X-352350Y1692018D01*
X-351110Y1692435D01*
X-350025Y1693684D01*
X-349250Y1695560D01*
X-348940Y1697435D01*
Y1699726D01*
X-349250Y1701601D01*
X-350025Y1703268D01*
X-350955Y1704101D01*
X-352040Y1704518D01*
X-353280Y1704101D01*
X-354210Y1703268D01*
X-354830Y1702018D01*
X-355140Y1700351D01*
X-354830Y1698893D01*
X-354055Y1697435D01*
X-353125Y1696601D01*
X-352040Y1696393D01*
X-350800Y1696809D01*
X-349870Y1697851D01*
X-348940Y1699726D01*
G01X-339640Y1692018D02*
X-338555Y1692226D01*
X-337315Y1692851D01*
X-336540Y1693893D01*
X-336230Y1695351D01*
X-336540Y1696809D01*
X-337470Y1698060D01*
X-338865Y1698685D01*
X-340415D01*
X-341345Y1699101D01*
X-342120Y1700143D01*
X-342430Y1701601D01*
X-341965Y1703060D01*
X-340880Y1704101D01*
X-339640Y1704518D01*
X-338400Y1704101D01*
X-337315Y1703060D01*
X-336850Y1701601D01*
X-337160Y1700143D01*
X-337935Y1699101D01*
X-338865Y1698685D01*
X-340415D01*
X-341810Y1698060D01*
X-342740Y1696809D01*
X-343050Y1695351D01*
X-342740Y1693893D01*
X-341965Y1692851D01*
X-340725Y1692226D01*
X-339640Y1692018D01*
G01X-330185Y1702435D02*
X-329255Y1703684D01*
X-328170Y1704310D01*
X-326930Y1704518D01*
X-325380Y1704101D01*
X-324295Y1703060D01*
X-323985Y1701810D01*
X-324140Y1700559D01*
X-324760Y1699518D01*
X-327860Y1697435D01*
X-329255Y1695976D01*
X-330185Y1693893D01*
X-330495Y1692018D01*
X-323985D01*
G01X-314840Y1691601D02*
X-315150Y1691810D01*
Y1692226D01*
X-314840Y1692435D01*
X-314530Y1692226D01*
Y1691810D01*
X-314840Y1691601D01*
G01X-305385Y1697226D02*
X-304300Y1698685D01*
X-303370Y1699518D01*
X-302130Y1699935D01*
X-301045Y1699518D01*
X-300270Y1698685D01*
X-299650Y1697435D01*
X-299495Y1695976D01*
X-299650Y1694726D01*
X-300270Y1693476D01*
X-301200Y1692435D01*
X-302285Y1692018D01*
X-303525Y1692435D01*
X-304610Y1693684D01*
X-305230Y1695560D01*
X-305385Y1697643D01*
X-305075Y1700351D01*
X-304610Y1701810D01*
X-303835Y1703268D01*
X-302750Y1704310D01*
X-301665Y1704518D01*
X-300580Y1704101D01*
X-299805Y1703060D01*
G01X-290040Y1692018D02*
X-288955Y1692226D01*
X-287715Y1692851D01*
X-286940Y1693893D01*
X-286630Y1695351D01*
X-286940Y1696809D01*
X-287870Y1698060D01*
X-289265Y1698685D01*
X-290815D01*
X-291745Y1699101D01*
X-292520Y1700143D01*
X-292830Y1701601D01*
X-292365Y1703060D01*
X-291280Y1704101D01*
X-290040Y1704518D01*
X-288800Y1704101D01*
X-287715Y1703060D01*
X-287250Y1701601D01*
X-287560Y1700143D01*
X-288335Y1699101D01*
X-289265Y1698685D01*
X-290815D01*
X-292210Y1698060D01*
X-293140Y1696809D01*
X-293450Y1695351D01*
X-293140Y1693893D01*
X-292365Y1692851D01*
X-291125Y1692226D01*
X-290040Y1692018D01*
G01X-351375Y242787D02*
X-350445Y244036D01*
X-349360Y244662D01*
X-348120Y244870D01*
X-346570Y244453D01*
X-345485Y243412D01*
X-345175Y242162D01*
X-345330Y240911D01*
X-345950Y239870D01*
X-349050Y237787D01*
X-350445Y236328D01*
X-351375Y234245D01*
X-351685Y232370D01*
X-345175D01*
G01X-336030Y244870D02*
X-337270Y244453D01*
X-338200Y243412D01*
X-338820Y242162D01*
X-339285Y240495D01*
X-339440Y238620D01*
X-339285Y236745D01*
X-338820Y235078D01*
X-338200Y233828D01*
X-337270Y232787D01*
X-336030Y232370D01*
X-334790Y232787D01*
X-333860Y233828D01*
X-333240Y235078D01*
X-332775Y236745D01*
X-332620Y238620D01*
X-332775Y240495D01*
X-333240Y242162D01*
X-333860Y243412D01*
X-334790Y244453D01*
X-336030Y244870D01*
G01X-321770Y232370D02*
Y244870D01*
X-327505Y235912D01*
X-319755D01*
G01X-311540Y232370D02*
X-311230Y235078D01*
X-310765Y237370D01*
X-310145Y239453D01*
X-309370Y241745D01*
X-308130Y244870D01*
X-314330D01*
G01X-298830Y231953D02*
X-299140Y232162D01*
Y232578D01*
X-298830Y232787D01*
X-298520Y232578D01*
Y232162D01*
X-298830Y231953D01*
G01X-289375Y242787D02*
X-288445Y244036D01*
X-287360Y244662D01*
X-286120Y244870D01*
X-284570Y244453D01*
X-283485Y243412D01*
X-283175Y242162D01*
X-283330Y240911D01*
X-283950Y239870D01*
X-287050Y237787D01*
X-288445Y236328D01*
X-289375Y234245D01*
X-289685Y232370D01*
X-283175D01*
G01X-272170D02*
Y244870D01*
X-277905Y235912D01*
X-270155D01*
G01X-286870Y532290D02*
Y544790D01*
X-288730Y542290D01*
G01Y532290D02*
X-285010D01*
G01X-272610D02*
Y544790D01*
X-278345Y535832D01*
X-270595D01*
G01X-265015Y537498D02*
X-263930Y538957D01*
X-263000Y539790D01*
X-261760Y540207D01*
X-260675Y539790D01*
X-259900Y538957D01*
X-259280Y537707D01*
X-259125Y536248D01*
X-259280Y534998D01*
X-259900Y533748D01*
X-260830Y532707D01*
X-261915Y532290D01*
X-263155Y532707D01*
X-264240Y533956D01*
X-264860Y535832D01*
X-265015Y537915D01*
X-264705Y540623D01*
X-264240Y542082D01*
X-263465Y543540D01*
X-262380Y544582D01*
X-261295Y544790D01*
X-260210Y544373D01*
X-259435Y543332D01*
G01X-249670Y531873D02*
X-249980Y532082D01*
Y532498D01*
X-249670Y532707D01*
X-249360Y532498D01*
Y532082D01*
X-249670Y531873D01*
G01X-237270Y532290D02*
X-236185Y532498D01*
X-234945Y533123D01*
X-234170Y534165D01*
X-233860Y535623D01*
X-234170Y537081D01*
X-235100Y538332D01*
X-236495Y538957D01*
X-238045D01*
X-238975Y539373D01*
X-239750Y540415D01*
X-240060Y541873D01*
X-239595Y543332D01*
X-238510Y544373D01*
X-237270Y544790D01*
X-236030Y544373D01*
X-234945Y543332D01*
X-234480Y541873D01*
X-234790Y540415D01*
X-235565Y539373D01*
X-236495Y538957D01*
X-238045D01*
X-239440Y538332D01*
X-240370Y537081D01*
X-240680Y535623D01*
X-240370Y534165D01*
X-239595Y533123D01*
X-238355Y532498D01*
X-237270Y532290D01*
G01X-227815Y537498D02*
X-226730Y538957D01*
X-225800Y539790D01*
X-224560Y540207D01*
X-223475Y539790D01*
X-222700Y538957D01*
X-222080Y537707D01*
X-221925Y536248D01*
X-222080Y534998D01*
X-222700Y533748D01*
X-223630Y532707D01*
X-224715Y532290D01*
X-225955Y532707D01*
X-227040Y533956D01*
X-227660Y535832D01*
X-227815Y537915D01*
X-227505Y540623D01*
X-227040Y542082D01*
X-226265Y543540D01*
X-225180Y544582D01*
X-224095Y544790D01*
X-223010Y544373D01*
X-222235Y543332D01*
G01X-286870Y599161D02*
Y611661D01*
X-288730Y609161D01*
G01Y599161D02*
X-285010D01*
G01X-277880Y601036D02*
X-276950Y599994D01*
X-275865Y599369D01*
X-274470Y599161D01*
X-273075Y599578D01*
X-271990Y600411D01*
X-271215Y601869D01*
X-271060Y603536D01*
X-271370Y605203D01*
X-272145Y606244D01*
X-273230Y607078D01*
X-274315Y607286D01*
X-275400Y607078D01*
X-276795Y606244D01*
X-276330Y611661D01*
X-272145D01*
G01X-265480Y601661D02*
X-264550Y600202D01*
X-263310Y599369D01*
X-261915Y599161D01*
X-260675Y599369D01*
X-259435Y600411D01*
X-258660Y601661D01*
X-258505Y602911D01*
X-258815Y604369D01*
X-259900Y605411D01*
X-260985Y605828D01*
X-262380D01*
G01X-260985D02*
X-260055Y606453D01*
X-259280Y607494D01*
X-258970Y608744D01*
X-259280Y609994D01*
X-260055Y611036D01*
X-261450Y611661D01*
X-262845Y611453D01*
X-264240Y610619D01*
G01X-249670Y598744D02*
X-249980Y598953D01*
Y599369D01*
X-249670Y599578D01*
X-249360Y599369D01*
Y598953D01*
X-249670Y598744D01*
G01X-237580Y599161D02*
X-237270Y601869D01*
X-236805Y604161D01*
X-236185Y606244D01*
X-235410Y608536D01*
X-234170Y611661D01*
X-240370D01*
G01X-225180Y599161D02*
X-224870Y601869D01*
X-224405Y604161D01*
X-223785Y606244D01*
X-223010Y608536D01*
X-221770Y611661D01*
X-227970D01*
G01X-286550Y644880D02*
Y657380D01*
X-288410Y654880D01*
G01Y644880D02*
X-284690D01*
G01X-277095Y650088D02*
X-276010Y651547D01*
X-275080Y652380D01*
X-273840Y652797D01*
X-272755Y652380D01*
X-271980Y651547D01*
X-271360Y650297D01*
X-271205Y648838D01*
X-271360Y647588D01*
X-271980Y646338D01*
X-272910Y645297D01*
X-273995Y644880D01*
X-275235Y645297D01*
X-276320Y646546D01*
X-276940Y648422D01*
X-277095Y650505D01*
X-276785Y653213D01*
X-276320Y654672D01*
X-275545Y656130D01*
X-274460Y657172D01*
X-273375Y657380D01*
X-272290Y656963D01*
X-271515Y655922D01*
G01X-265160Y647380D02*
X-264230Y645921D01*
X-262990Y645088D01*
X-261595Y644880D01*
X-260355Y645088D01*
X-259115Y646130D01*
X-258340Y647380D01*
X-258185Y648630D01*
X-258495Y650088D01*
X-259580Y651130D01*
X-260665Y651547D01*
X-262060D01*
G01X-260665D02*
X-259735Y652172D01*
X-258960Y653213D01*
X-258650Y654463D01*
X-258960Y655713D01*
X-259735Y656755D01*
X-261130Y657380D01*
X-262525Y657172D01*
X-263920Y656338D01*
G01X-249350Y644463D02*
X-249660Y644672D01*
Y645088D01*
X-249350Y645297D01*
X-249040Y645088D01*
Y644672D01*
X-249350Y644463D01*
G01X-240360Y647380D02*
X-239430Y645921D01*
X-238190Y645088D01*
X-236795Y644880D01*
X-235555Y645088D01*
X-234315Y646130D01*
X-233540Y647380D01*
X-233385Y648630D01*
X-233695Y650088D01*
X-234780Y651130D01*
X-235865Y651547D01*
X-237260D01*
G01X-235865D02*
X-234935Y652172D01*
X-234160Y653213D01*
X-233850Y654463D01*
X-234160Y655713D01*
X-234935Y656755D01*
X-236330Y657380D01*
X-237725Y657172D01*
X-239120Y656338D01*
G01X-224550Y644880D02*
Y657380D01*
X-226410Y654880D01*
G01Y644880D02*
X-222690D01*
G01X-287840Y676092D02*
Y688592D01*
X-289700Y686092D01*
G01Y676092D02*
X-285980D01*
G01X-275750D02*
X-275440Y678800D01*
X-274975Y681092D01*
X-274355Y683175D01*
X-273580Y685467D01*
X-272340Y688592D01*
X-278540D01*
G01X-266450Y678592D02*
X-265520Y677133D01*
X-264280Y676300D01*
X-262885Y676092D01*
X-261645Y676300D01*
X-260405Y677342D01*
X-259630Y678592D01*
X-259475Y679842D01*
X-259785Y681300D01*
X-260870Y682342D01*
X-261955Y682759D01*
X-263350D01*
G01X-261955D02*
X-261025Y683384D01*
X-260250Y684425D01*
X-259940Y685675D01*
X-260250Y686925D01*
X-261025Y687967D01*
X-262420Y688592D01*
X-263815Y688384D01*
X-265210Y687550D01*
G01X-250640Y675675D02*
X-250950Y675884D01*
Y676300D01*
X-250640Y676509D01*
X-250330Y676300D01*
Y675884D01*
X-250640Y675675D01*
G01X-241650Y678592D02*
X-240720Y677133D01*
X-239480Y676300D01*
X-238085Y676092D01*
X-236845Y676300D01*
X-235605Y677342D01*
X-234830Y678592D01*
X-234675Y679842D01*
X-234985Y681300D01*
X-236070Y682342D01*
X-237155Y682759D01*
X-238550D01*
G01X-237155D02*
X-236225Y683384D01*
X-235450Y684425D01*
X-235140Y685675D01*
X-235450Y686925D01*
X-236225Y687967D01*
X-237620Y688592D01*
X-239015Y688384D01*
X-240410Y687550D01*
G01X-225840Y676092D02*
Y688592D01*
X-227700Y686092D01*
G01Y676092D02*
X-223980D01*
G01X-277290Y166920D02*
X-276360Y165461D01*
X-275120Y164628D01*
X-273725Y164420D01*
X-272485Y164628D01*
X-271245Y165670D01*
X-270470Y166920D01*
X-270315Y168170D01*
X-270625Y169628D01*
X-271710Y170670D01*
X-272795Y171087D01*
X-274190D01*
G01X-272795D02*
X-271865Y171712D01*
X-271090Y172753D01*
X-270780Y174003D01*
X-271090Y175253D01*
X-271865Y176295D01*
X-273260Y176920D01*
X-274655Y176712D01*
X-276050Y175878D01*
G01X-264115Y165878D02*
X-263030Y164837D01*
X-261790Y164420D01*
X-260550Y164837D01*
X-259465Y166086D01*
X-258690Y167962D01*
X-258380Y169837D01*
Y172128D01*
X-258690Y174003D01*
X-259465Y175670D01*
X-260395Y176503D01*
X-261480Y176920D01*
X-262720Y176503D01*
X-263650Y175670D01*
X-264270Y174420D01*
X-264580Y172753D01*
X-264270Y171295D01*
X-263495Y169837D01*
X-262565Y169003D01*
X-261480Y168795D01*
X-260240Y169211D01*
X-259310Y170253D01*
X-258380Y172128D01*
G01X-249080Y164003D02*
X-249390Y164212D01*
Y164628D01*
X-249080Y164837D01*
X-248770Y164628D01*
Y164212D01*
X-249080Y164003D01*
G01X-234820Y164420D02*
Y176920D01*
X-240555Y167962D01*
X-232805D01*
G01X-227225Y174837D02*
X-226295Y176086D01*
X-225210Y176712D01*
X-223970Y176920D01*
X-222420Y176503D01*
X-221335Y175462D01*
X-221025Y174212D01*
X-221180Y172961D01*
X-221800Y171920D01*
X-224900Y169837D01*
X-226295Y168378D01*
X-227225Y166295D01*
X-227535Y164420D01*
X-221025D01*
G01X-272340Y191600D02*
Y204100D01*
X-278075Y195142D01*
X-270325D01*
G01X-261800Y204100D02*
X-263040Y203683D01*
X-263970Y202642D01*
X-264590Y201392D01*
X-265055Y199725D01*
X-265210Y197850D01*
X-265055Y195975D01*
X-264590Y194308D01*
X-263970Y193058D01*
X-263040Y192017D01*
X-261800Y191600D01*
X-260560Y192017D01*
X-259630Y193058D01*
X-259010Y194308D01*
X-258545Y195975D01*
X-258390Y197850D01*
X-258545Y199725D01*
X-259010Y201392D01*
X-259630Y202642D01*
X-260560Y203683D01*
X-261800Y204100D01*
G01X-249400Y191183D02*
X-249710Y191392D01*
Y191808D01*
X-249400Y192017D01*
X-249090Y191808D01*
Y191392D01*
X-249400Y191183D01*
G01X-235140Y191600D02*
Y204100D01*
X-240875Y195142D01*
X-233125D01*
G01X-227545Y202017D02*
X-226615Y203266D01*
X-225530Y203892D01*
X-224290Y204100D01*
X-222740Y203683D01*
X-221655Y202642D01*
X-221345Y201392D01*
X-221500Y200141D01*
X-222120Y199100D01*
X-225220Y197017D01*
X-226615Y195558D01*
X-227545Y193475D01*
X-227855Y191600D01*
X-221345D01*
G01X-272990Y209720D02*
Y222220D01*
X-278725Y213262D01*
X-270975D01*
G01X-260590Y209720D02*
Y222220D01*
X-266325Y213262D01*
X-258575D01*
G01X-250050Y209303D02*
X-250360Y209512D01*
Y209928D01*
X-250050Y210137D01*
X-249740Y209928D01*
Y209512D01*
X-250050Y209303D01*
G01X-235790Y209720D02*
Y222220D01*
X-241525Y213262D01*
X-233775D01*
G01X-227885Y211178D02*
X-226800Y210137D01*
X-225560Y209720D01*
X-224320Y210137D01*
X-223235Y211386D01*
X-222460Y213262D01*
X-222150Y215137D01*
Y217428D01*
X-222460Y219303D01*
X-223235Y220970D01*
X-224165Y221803D01*
X-225250Y222220D01*
X-226490Y221803D01*
X-227420Y220970D01*
X-228040Y219720D01*
X-228350Y218053D01*
X-228040Y216595D01*
X-227265Y215137D01*
X-226335Y214303D01*
X-225250Y214095D01*
X-224010Y214511D01*
X-223080Y215553D01*
X-222150Y217428D01*
G01X-277750Y270986D02*
X-277440Y273694D01*
X-276975Y275986D01*
X-276355Y278069D01*
X-275580Y280361D01*
X-274340Y283486D01*
X-280540D01*
G01X-265040D02*
X-266280Y283069D01*
X-267210Y282028D01*
X-267830Y280778D01*
X-268295Y279111D01*
X-268450Y277236D01*
X-268295Y275361D01*
X-267830Y273694D01*
X-267210Y272444D01*
X-266280Y271403D01*
X-265040Y270986D01*
X-263800Y271403D01*
X-262870Y272444D01*
X-262250Y273694D01*
X-261785Y275361D01*
X-261630Y277236D01*
X-261785Y279111D01*
X-262250Y280778D01*
X-262870Y282028D01*
X-263800Y283069D01*
X-265040Y283486D01*
G01X-252640Y270569D02*
X-252950Y270778D01*
Y271194D01*
X-252640Y271403D01*
X-252330Y271194D01*
Y270778D01*
X-252640Y270569D01*
G01X-238380Y270986D02*
Y283486D01*
X-244115Y274528D01*
X-236365D01*
G01X-230785Y281403D02*
X-229855Y282652D01*
X-228770Y283278D01*
X-227530Y283486D01*
X-225980Y283069D01*
X-224895Y282028D01*
X-224585Y280778D01*
X-224740Y279527D01*
X-225360Y278486D01*
X-228460Y276403D01*
X-229855Y274944D01*
X-230785Y272861D01*
X-231095Y270986D01*
X-224585D01*
G01X-275500Y576053D02*
Y588553D01*
X-277360Y586053D01*
G01Y576053D02*
X-273640D01*
G01X-261240D02*
Y588553D01*
X-266975Y579595D01*
X-259225D01*
G01X-251010Y576053D02*
X-250700Y578761D01*
X-250235Y581053D01*
X-249615Y583136D01*
X-248840Y585428D01*
X-247600Y588553D01*
X-253800D01*
G01X-238300Y575636D02*
X-238610Y575845D01*
Y576261D01*
X-238300Y576470D01*
X-237990Y576261D01*
Y575845D01*
X-238300Y575636D01*
G01X-228535Y577511D02*
X-227450Y576470D01*
X-226210Y576053D01*
X-224970Y576470D01*
X-223885Y577719D01*
X-223110Y579595D01*
X-222800Y581470D01*
Y583761D01*
X-223110Y585636D01*
X-223885Y587303D01*
X-224815Y588136D01*
X-225900Y588553D01*
X-227140Y588136D01*
X-228070Y587303D01*
X-228690Y586053D01*
X-229000Y584386D01*
X-228690Y582928D01*
X-227915Y581470D01*
X-226985Y580636D01*
X-225900Y580428D01*
X-224660Y580844D01*
X-223730Y581886D01*
X-222800Y583761D01*
G01X-253580Y1692018D02*
Y1704518D01*
X-259315Y1695560D01*
X-251565D01*
G01X-246450Y1694518D02*
X-245520Y1693059D01*
X-244280Y1692226D01*
X-242885Y1692018D01*
X-241645Y1692226D01*
X-240405Y1693268D01*
X-239630Y1694518D01*
X-239475Y1695768D01*
X-239785Y1697226D01*
X-240870Y1698268D01*
X-241955Y1698685D01*
X-243350D01*
G01X-241955D02*
X-241025Y1699310D01*
X-240250Y1700351D01*
X-239940Y1701601D01*
X-240250Y1702851D01*
X-241025Y1703893D01*
X-242420Y1704518D01*
X-243815Y1704310D01*
X-245210Y1703476D01*
G01X-230640Y1692018D02*
Y1704518D01*
X-232500Y1702018D01*
G01Y1692018D02*
X-228780D01*
G01X-218240Y1691601D02*
X-218550Y1691810D01*
Y1692226D01*
X-218240Y1692435D01*
X-217930Y1692226D01*
Y1691810D01*
X-218240Y1691601D01*
G01X-209250Y1694518D02*
X-208320Y1693059D01*
X-207080Y1692226D01*
X-205685Y1692018D01*
X-204445Y1692226D01*
X-203205Y1693268D01*
X-202430Y1694518D01*
X-202275Y1695768D01*
X-202585Y1697226D01*
X-203670Y1698268D01*
X-204755Y1698685D01*
X-206150D01*
G01X-204755D02*
X-203825Y1699310D01*
X-203050Y1700351D01*
X-202740Y1701601D01*
X-203050Y1702851D01*
X-203825Y1703893D01*
X-205220Y1704518D01*
X-206615Y1704310D01*
X-208010Y1703476D01*
G01X-196385Y1697226D02*
X-195300Y1698685D01*
X-194370Y1699518D01*
X-193130Y1699935D01*
X-192045Y1699518D01*
X-191270Y1698685D01*
X-190650Y1697435D01*
X-190495Y1695976D01*
X-190650Y1694726D01*
X-191270Y1693476D01*
X-192200Y1692435D01*
X-193285Y1692018D01*
X-194525Y1692435D01*
X-195610Y1693684D01*
X-196230Y1695560D01*
X-196385Y1697643D01*
X-196075Y1700351D01*
X-195610Y1701810D01*
X-194835Y1703268D01*
X-193750Y1704310D01*
X-192665Y1704518D01*
X-191580Y1704101D01*
X-190805Y1703060D01*
G01X-242840Y234245D02*
X-241910Y233203D01*
X-240825Y232578D01*
X-239430Y232370D01*
X-238035Y232787D01*
X-236950Y233620D01*
X-236175Y235078D01*
X-236020Y236745D01*
X-236330Y238412D01*
X-237105Y239453D01*
X-238190Y240287D01*
X-239275Y240495D01*
X-240360Y240287D01*
X-241755Y239453D01*
X-241290Y244870D01*
X-237105D01*
G01X-229975Y242787D02*
X-229045Y244036D01*
X-227960Y244662D01*
X-226720Y244870D01*
X-225170Y244453D01*
X-224085Y243412D01*
X-223775Y242162D01*
X-223930Y240911D01*
X-224550Y239870D01*
X-227650Y237787D01*
X-229045Y236328D01*
X-229975Y234245D01*
X-230285Y232370D01*
X-223775D01*
G01X-96870Y-6250D02*
X-98110Y-6667D01*
X-99040Y-7708D01*
X-99660Y-8958D01*
X-100125Y-10625D01*
X-100280Y-12500D01*
X-100125Y-14375D01*
X-99660Y-16042D01*
X-99040Y-17292D01*
X-98110Y-18333D01*
X-96870Y-18750D01*
X-95630Y-18333D01*
X-94700Y-17292D01*
X-94080Y-16042D01*
X-93615Y-14375D01*
X-93460Y-12500D01*
X-93615Y-10625D01*
X-94080Y-8958D01*
X-94700Y-7708D01*
X-95630Y-6667D01*
X-96870Y-6250D01*
G01X-97020Y18750D02*
X-98260Y18333D01*
X-99190Y17292D01*
X-99810Y16042D01*
X-100275Y14375D01*
X-100430Y12500D01*
X-100275Y10625D01*
X-99810Y8958D01*
X-99190Y7708D01*
X-98260Y6667D01*
X-97020Y6250D01*
X-95780Y6667D01*
X-94850Y7708D01*
X-94230Y8958D01*
X-93765Y10625D01*
X-93610Y12500D01*
X-93765Y14375D01*
X-94230Y16042D01*
X-94850Y17292D01*
X-95780Y18333D01*
X-97020Y18750D01*
G01X-18750Y-93160D02*
X-18333Y-94400D01*
X-17292Y-95330D01*
X-16042Y-95950D01*
X-14375Y-96415D01*
X-12500Y-96570D01*
X-10625Y-96415D01*
X-8958Y-95950D01*
X-7708Y-95330D01*
X-6667Y-94400D01*
X-6250Y-93160D01*
X-6667Y-91920D01*
X-7708Y-90990D01*
X-8958Y-90370D01*
X-10625Y-89905D01*
X-12500Y-89750D01*
X-14375Y-89905D01*
X-16042Y-90370D01*
X-17292Y-90990D01*
X-18333Y-91920D01*
X-18750Y-93160D01*
G01X8820Y-607488D02*
X10387D01*
Y-609378D01*
X9917Y-610008D01*
X9368Y-610428D01*
X8585Y-610638D01*
X7802Y-610428D01*
X7253Y-610008D01*
X6783Y-609378D01*
X6470Y-608643D01*
X6313Y-607803D01*
Y-607068D01*
X6470Y-606438D01*
X6783Y-605703D01*
X7253Y-605073D01*
X7723Y-604653D01*
X8350Y-604338D01*
X8898D01*
X9525Y-604548D01*
X9995Y-604968D01*
G01X12927Y-604338D02*
Y-608853D01*
X13240Y-609798D01*
X13867Y-610428D01*
X14650Y-610638D01*
X15433Y-610428D01*
X16060Y-609798D01*
X16373Y-608853D01*
Y-604338D01*
G01X20010D02*
X21890D01*
G01X20950D02*
Y-610638D01*
G01X20010D02*
X21890D01*
G01X25605Y-609798D02*
X26232Y-610323D01*
X26937Y-610638D01*
X27563D01*
X28190Y-610323D01*
X28660Y-609798D01*
X28895Y-609063D01*
X28738Y-608328D01*
X28347Y-607698D01*
X27642Y-607278D01*
X26702Y-607068D01*
X26153Y-606648D01*
X25918Y-605913D01*
X26075Y-605178D01*
X26467Y-604653D01*
X27015Y-604338D01*
X27563D01*
X28112Y-604548D01*
X28582Y-605073D01*
G01X31905Y-610638D02*
Y-604338D01*
G01X35195D02*
Y-610638D01*
G01Y-607488D02*
X31905D01*
G01X37892Y-610638D02*
X39850Y-604338D01*
X41808Y-610638D01*
G01X41103Y-608433D02*
X38597D01*
G01X44348Y-610638D02*
Y-604338D01*
X47952Y-610638D01*
Y-604338D01*
G01X57027Y-610638D02*
Y-604338D01*
X58593D01*
X59220Y-604653D01*
X59690Y-605073D01*
X60082Y-605703D01*
X60395Y-606438D01*
X60473Y-607488D01*
X60395Y-608538D01*
X60082Y-609273D01*
X59690Y-609903D01*
X59220Y-610323D01*
X58593Y-610638D01*
X57027D01*
G01X64110Y-604338D02*
X65990D01*
G01X65050D02*
Y-610638D01*
G01X64110D02*
X65990D01*
G01X69705Y-609798D02*
X70332Y-610323D01*
X71037Y-610638D01*
X71663D01*
X72290Y-610323D01*
X72760Y-609798D01*
X72995Y-609063D01*
X72838Y-608328D01*
X72447Y-607698D01*
X71742Y-607278D01*
X70802Y-607068D01*
X70253Y-606648D01*
X70018Y-605913D01*
X70175Y-605178D01*
X70567Y-604653D01*
X71115Y-604338D01*
X71663D01*
X72212Y-604548D01*
X72682Y-605073D01*
G01X77650Y-604338D02*
Y-610638D01*
G01X75848Y-604338D02*
X79452D01*
G01X83950Y-610848D02*
X83793Y-610743D01*
Y-610533D01*
X83950Y-610428D01*
X84107Y-610533D01*
Y-610743D01*
X83950Y-610848D01*
G01X90093Y-611793D02*
X90407Y-610428D01*
G01X96550Y-604338D02*
Y-610638D01*
G01X94748Y-604338D02*
X98352D01*
G01X100892Y-610638D02*
X102850Y-604338D01*
X104808Y-610638D01*
G01X104103Y-608433D02*
X101597D01*
G01X109150Y-610638D02*
X108523Y-610533D01*
X107975Y-610113D01*
X107505Y-609483D01*
X107192Y-608748D01*
X107035Y-607908D01*
Y-607068D01*
X107192Y-606228D01*
X107505Y-605493D01*
X107975Y-604863D01*
X108523Y-604443D01*
X109150Y-604338D01*
X109777Y-604443D01*
X110325Y-604863D01*
X110795Y-605493D01*
X111108Y-606228D01*
X111265Y-607068D01*
Y-607908D01*
X111108Y-608748D01*
X110795Y-609483D01*
X110325Y-610113D01*
X109777Y-610533D01*
X109150Y-610638D01*
G01X115450D02*
Y-607803D01*
X113883Y-604338D01*
G01X117017D02*
X115450Y-607803D01*
G01X120027Y-604338D02*
Y-608853D01*
X120340Y-609798D01*
X120967Y-610428D01*
X121750Y-610638D01*
X122533Y-610428D01*
X123160Y-609798D01*
X123473Y-608853D01*
Y-604338D01*
G01X126092Y-610638D02*
X128050Y-604338D01*
X130008Y-610638D01*
G01X129303Y-608433D02*
X126797D01*
G01X132548Y-610638D02*
Y-604338D01*
X136152Y-610638D01*
Y-604338D01*
G01X10073Y-614863D02*
X9603Y-614548D01*
X9055Y-614338D01*
X8428D01*
X7723Y-614653D01*
X7175Y-615178D01*
X6783Y-615808D01*
X6470Y-616858D01*
X6392Y-617803D01*
X6548Y-618748D01*
X6783Y-619378D01*
X7253Y-620008D01*
X7802Y-620428D01*
X8350Y-620638D01*
X8898D01*
X9447Y-620428D01*
X9917Y-620113D01*
X10308Y-619693D01*
G01X13710Y-614338D02*
X15590D01*
G01X14650D02*
Y-620638D01*
G01X13710D02*
X15590D01*
G01X20950Y-614338D02*
Y-620638D01*
G01X19148Y-614338D02*
X22752D01*
G01X27250Y-620638D02*
Y-617803D01*
X25683Y-614338D01*
G01X28817D02*
X27250Y-617803D01*
G01X38127Y-619378D02*
X38597Y-620113D01*
X39223Y-620533D01*
X39928Y-620638D01*
X40555Y-620533D01*
X41182Y-620008D01*
X41573Y-619378D01*
X41652Y-618748D01*
X41495Y-618013D01*
X40947Y-617488D01*
X40398Y-617278D01*
X39693D01*
G01X40398D02*
X40868Y-616963D01*
X41260Y-616438D01*
X41417Y-615808D01*
X41260Y-615178D01*
X40868Y-614653D01*
X40163Y-614338D01*
X39458Y-614443D01*
X38753Y-614863D01*
G01X44427Y-619378D02*
X44897Y-620113D01*
X45523Y-620533D01*
X46228Y-620638D01*
X46855Y-620533D01*
X47482Y-620008D01*
X47873Y-619378D01*
X47952Y-618748D01*
X47795Y-618013D01*
X47247Y-617488D01*
X46698Y-617278D01*
X45993D01*
G01X46698D02*
X47168Y-616963D01*
X47560Y-616438D01*
X47717Y-615808D01*
X47560Y-615178D01*
X47168Y-614653D01*
X46463Y-614338D01*
X45758Y-614443D01*
X45053Y-614863D01*
G01X50727Y-619378D02*
X51197Y-620113D01*
X51823Y-620533D01*
X52528Y-620638D01*
X53155Y-620533D01*
X53782Y-620008D01*
X54173Y-619378D01*
X54252Y-618748D01*
X54095Y-618013D01*
X53547Y-617488D01*
X52998Y-617278D01*
X52293D01*
G01X52998D02*
X53468Y-616963D01*
X53860Y-616438D01*
X54017Y-615808D01*
X53860Y-615178D01*
X53468Y-614653D01*
X52763Y-614338D01*
X52058Y-614443D01*
X51353Y-614863D01*
G01X58593Y-620638D02*
X58750Y-619273D01*
X58985Y-618118D01*
X59298Y-617068D01*
X59690Y-615913D01*
X60317Y-614338D01*
X57183D01*
G01X64893Y-620638D02*
X65050Y-619273D01*
X65285Y-618118D01*
X65598Y-617068D01*
X65990Y-615913D01*
X66617Y-614338D01*
X63483D01*
G01X71193Y-621793D02*
X71507Y-620428D01*
G01X77650Y-614338D02*
Y-620638D01*
G01X75848Y-614338D02*
X79452D01*
G01X81992Y-620638D02*
X83950Y-614338D01*
X85908Y-620638D01*
G01X85203Y-618433D02*
X82697D01*
G01X89310Y-614338D02*
X91190D01*
G01X90250D02*
Y-620638D01*
G01X89310D02*
X91190D01*
G01X94200Y-614338D02*
X95297Y-620638D01*
X96550Y-614338D01*
X97803Y-620638D01*
X98900Y-614338D01*
G01X100892Y-620638D02*
X102850Y-614338D01*
X104808Y-620638D01*
G01X104103Y-618433D02*
X101597D01*
G01X107348Y-620638D02*
Y-614338D01*
X110952Y-620638D01*
Y-614338D01*
G01X121358Y-622738D02*
X120575Y-621688D01*
X120183Y-620638D01*
Y-616438D01*
X120575Y-615388D01*
X121358Y-614338D01*
G01X132783Y-620638D02*
Y-614338D01*
X134742D01*
X135368Y-614653D01*
X135760Y-615073D01*
X135917Y-615913D01*
X135760Y-616753D01*
X135290Y-617278D01*
X134742Y-617593D01*
X132783D01*
G01X134742D02*
X135917Y-620638D01*
G01X140650Y-620848D02*
X140493Y-620743D01*
Y-620533D01*
X140650Y-620428D01*
X140807Y-620533D01*
Y-620743D01*
X140650Y-620848D01*
G01X146950Y-620638D02*
X146323Y-620533D01*
X145775Y-620113D01*
X145305Y-619483D01*
X144992Y-618748D01*
X144835Y-617908D01*
Y-617068D01*
X144992Y-616228D01*
X145305Y-615493D01*
X145775Y-614863D01*
X146323Y-614443D01*
X146950Y-614338D01*
X147577Y-614443D01*
X148125Y-614863D01*
X148595Y-615493D01*
X148908Y-616228D01*
X149065Y-617068D01*
Y-617908D01*
X148908Y-618748D01*
X148595Y-619483D01*
X148125Y-620113D01*
X147577Y-620533D01*
X146950Y-620638D01*
G01X153250Y-620848D02*
X153093Y-620743D01*
Y-620533D01*
X153250Y-620428D01*
X153407Y-620533D01*
Y-620743D01*
X153250Y-620848D01*
G01X161273Y-614863D02*
X160803Y-614548D01*
X160255Y-614338D01*
X159628D01*
X158923Y-614653D01*
X158375Y-615178D01*
X157983Y-615808D01*
X157670Y-616858D01*
X157592Y-617803D01*
X157748Y-618748D01*
X157983Y-619378D01*
X158453Y-620008D01*
X159002Y-620428D01*
X159550Y-620638D01*
X160098D01*
X160647Y-620428D01*
X161117Y-620113D01*
X161508Y-619693D01*
G01X165850Y-620848D02*
X165693Y-620743D01*
Y-620533D01*
X165850Y-620428D01*
X166007Y-620533D01*
Y-620743D01*
X165850Y-620848D01*
G01X172542Y-622738D02*
X173325Y-621688D01*
X173717Y-620638D01*
Y-616438D01*
X173325Y-615388D01*
X172542Y-614338D01*
G01X6548Y-600638D02*
Y-594338D01*
X10152Y-600638D01*
Y-594338D01*
G01X14650Y-600638D02*
X14023Y-600533D01*
X13475Y-600113D01*
X13005Y-599483D01*
X12692Y-598748D01*
X12535Y-597908D01*
Y-597068D01*
X12692Y-596228D01*
X13005Y-595493D01*
X13475Y-594863D01*
X14023Y-594443D01*
X14650Y-594338D01*
X15277Y-594443D01*
X15825Y-594863D01*
X16295Y-595493D01*
X16608Y-596228D01*
X16765Y-597068D01*
Y-597908D01*
X16608Y-598748D01*
X16295Y-599483D01*
X15825Y-600113D01*
X15277Y-600533D01*
X14650Y-600638D01*
G01X20950Y-600848D02*
X20793Y-600743D01*
Y-600533D01*
X20950Y-600428D01*
X21107Y-600533D01*
Y-600743D01*
X20950Y-600848D01*
G01X25762Y-595388D02*
X26232Y-594758D01*
X26780Y-594443D01*
X27407Y-594338D01*
X28190Y-594548D01*
X28738Y-595073D01*
X28895Y-595703D01*
X28817Y-596333D01*
X28503Y-596858D01*
X26937Y-597908D01*
X26232Y-598643D01*
X25762Y-599693D01*
X25605Y-600638D01*
X28895D01*
G01X33550D02*
Y-594338D01*
X32610Y-595598D01*
G01Y-600638D02*
X34490D01*
G01X39850D02*
Y-594338D01*
X38910Y-595598D01*
G01Y-600638D02*
X40790D01*
G01X45993Y-601793D02*
X46307Y-600428D01*
G01X50100Y-594338D02*
X51197Y-600638D01*
X52450Y-594338D01*
X53703Y-600638D01*
X54800Y-594338D01*
G01X60317Y-600638D02*
X57183D01*
Y-594338D01*
X60317D01*
G01X59063Y-597383D02*
X57183D01*
G01X63248Y-600638D02*
Y-594338D01*
X66852Y-600638D01*
Y-594338D01*
G01X69705Y-600638D02*
Y-594338D01*
G01X72995D02*
Y-600638D01*
G01Y-597488D02*
X69705D01*
G01X75927Y-594338D02*
Y-598853D01*
X76240Y-599798D01*
X76867Y-600428D01*
X77650Y-600638D01*
X78433Y-600428D01*
X79060Y-599798D01*
X79373Y-598853D01*
Y-594338D01*
G01X81992Y-600638D02*
X83950Y-594338D01*
X85908Y-600638D01*
G01X85203Y-598433D02*
X82697D01*
G01X95062Y-595388D02*
X95532Y-594758D01*
X96080Y-594443D01*
X96707Y-594338D01*
X97490Y-594548D01*
X98038Y-595073D01*
X98195Y-595703D01*
X98117Y-596333D01*
X97803Y-596858D01*
X96237Y-597908D01*
X95532Y-598643D01*
X95062Y-599693D01*
X94905Y-600638D01*
X98195D01*
G01X101048D02*
Y-594338D01*
X104652Y-600638D01*
Y-594338D01*
G01X107427Y-600638D02*
Y-594338D01*
X108993D01*
X109620Y-594653D01*
X110090Y-595073D01*
X110482Y-595703D01*
X110795Y-596438D01*
X110873Y-597488D01*
X110795Y-598538D01*
X110482Y-599273D01*
X110090Y-599903D01*
X109620Y-600323D01*
X108993Y-600638D01*
X107427D01*
G01X120183D02*
Y-594338D01*
X122142D01*
X122768Y-594653D01*
X123160Y-595073D01*
X123317Y-595913D01*
X123160Y-596753D01*
X122690Y-597278D01*
X122142Y-597593D01*
X120183D01*
G01X122142D02*
X123317Y-600638D01*
G01X126327D02*
Y-594338D01*
X127893D01*
X128520Y-594653D01*
X128990Y-595073D01*
X129382Y-595703D01*
X129695Y-596438D01*
X129773Y-597488D01*
X129695Y-598538D01*
X129382Y-599273D01*
X128990Y-599903D01*
X128520Y-600323D01*
X127893Y-600638D01*
X126327D01*
G01X134350Y-600848D02*
X134193Y-600743D01*
Y-600533D01*
X134350Y-600428D01*
X134507Y-600533D01*
Y-600743D01*
X134350Y-600848D01*
G01X6250Y-93010D02*
X6667Y-94250D01*
X7708Y-95180D01*
X8958Y-95800D01*
X10625Y-96265D01*
X12500Y-96420D01*
X14375Y-96265D01*
X16042Y-95800D01*
X17292Y-95180D01*
X18333Y-94250D01*
X18750Y-93010D01*
X18333Y-91770D01*
X17292Y-90840D01*
X16042Y-90220D01*
X14375Y-89755D01*
X12500Y-89600D01*
X10625Y-89755D01*
X8958Y-90220D01*
X7708Y-90840D01*
X6667Y-91770D01*
X6250Y-93010D01*
G01X30650Y-589938D02*
X28130Y-589521D01*
X25925Y-587855D01*
X24035Y-585355D01*
X22775Y-582438D01*
X22145Y-579105D01*
Y-575771D01*
X22775Y-572438D01*
X24035Y-569521D01*
X25925Y-567022D01*
X28130Y-565355D01*
X30650Y-564938D01*
X33170Y-565355D01*
X35375Y-567022D01*
X37265Y-569521D01*
X38525Y-572438D01*
X39155Y-575771D01*
Y-579105D01*
X38525Y-582438D01*
X37265Y-585355D01*
X35375Y-587855D01*
X33170Y-589521D01*
X30650Y-589938D01*
G01X33170Y-583271D02*
X36950Y-589938D01*
G01X50495Y-573272D02*
Y-584938D01*
X51755Y-587855D01*
X53645Y-589521D01*
X55850Y-589938D01*
X58055Y-589521D01*
X59945Y-587855D01*
X61205Y-584938D01*
G01Y-589938D02*
Y-573272D01*
G01X86720Y-589938D02*
Y-573272D01*
G01Y-576188D02*
X85460Y-574522D01*
X83570Y-573688D01*
X81365Y-573272D01*
X79160Y-574105D01*
X77270Y-575771D01*
X76010Y-578272D01*
X75380Y-581605D01*
X76010Y-584938D01*
X77270Y-587439D01*
X79160Y-589105D01*
X81365Y-589938D01*
X83570Y-589521D01*
X85460Y-588272D01*
X86720Y-586605D01*
G01X100895Y-589938D02*
Y-573272D01*
G01Y-577438D02*
X102155Y-575355D01*
X104045Y-573688D01*
X106565Y-573272D01*
X108770Y-573688D01*
X110660Y-575355D01*
X111605Y-578272D01*
Y-589938D01*
G01X131450Y-564938D02*
Y-589938D01*
G01X127040Y-573272D02*
X135860D01*
G01X162320Y-589938D02*
Y-573272D01*
G01Y-576188D02*
X161060Y-574522D01*
X159170Y-573688D01*
X156965Y-573272D01*
X154760Y-574105D01*
X152870Y-575771D01*
X151610Y-578272D01*
X150980Y-581605D01*
X151610Y-584938D01*
X152870Y-587439D01*
X154760Y-589105D01*
X156965Y-589938D01*
X159170Y-589521D01*
X161060Y-588272D01*
X162320Y-586605D01*
G01X23392Y-313505D02*
X22143Y-312575D01*
X21517Y-311490D01*
X21309Y-310250D01*
X21726Y-308700D01*
X22767Y-307615D01*
X24017Y-307305D01*
X25268Y-307460D01*
X26309Y-308080D01*
X28392Y-311180D01*
X29851Y-312575D01*
X31934Y-313505D01*
X33809Y-313815D01*
Y-307305D01*
G01Y-298470D02*
X31101Y-298160D01*
X28809Y-297695D01*
X26726Y-297075D01*
X24434Y-296300D01*
X21309Y-295060D01*
Y-301260D01*
G01X31934Y-289170D02*
X32976Y-288240D01*
X33601Y-287155D01*
X33809Y-285760D01*
X33392Y-284365D01*
X32559Y-283280D01*
X31101Y-282505D01*
X29434Y-282350D01*
X27767Y-282660D01*
X26726Y-283435D01*
X25892Y-284520D01*
X25684Y-285605D01*
X25892Y-286690D01*
X26726Y-288085D01*
X21309Y-287620D01*
Y-283435D01*
G01X34226Y-273360D02*
X34017Y-273670D01*
X33601D01*
X33392Y-273360D01*
X33601Y-273050D01*
X34017D01*
X34226Y-273360D01*
G01X31934Y-264370D02*
X32976Y-263440D01*
X33601Y-262355D01*
X33809Y-260960D01*
X33392Y-259565D01*
X32559Y-258480D01*
X31101Y-257705D01*
X29434Y-257550D01*
X27767Y-257860D01*
X26726Y-258635D01*
X25892Y-259720D01*
X25684Y-260805D01*
X25892Y-261890D01*
X26726Y-263285D01*
X21309Y-262820D01*
Y-258635D01*
G01X32351Y-251195D02*
X33392Y-250110D01*
X33809Y-248870D01*
X33392Y-247630D01*
X32143Y-246545D01*
X30267Y-245770D01*
X28392Y-245460D01*
X26101D01*
X24226Y-245770D01*
X22559Y-246545D01*
X21726Y-247475D01*
X21309Y-248560D01*
X21726Y-249800D01*
X22559Y-250730D01*
X23809Y-251350D01*
X25476Y-251660D01*
X26934Y-251350D01*
X28392Y-250575D01*
X29226Y-249645D01*
X29434Y-248560D01*
X29018Y-247320D01*
X27976Y-246390D01*
X26101Y-245460D01*
G01X33809Y-214270D02*
X31101Y-213960D01*
X28809Y-213495D01*
X26726Y-212875D01*
X24434Y-212100D01*
X21309Y-210860D01*
Y-217060D01*
G01X54030Y-350300D02*
X55489Y-349370D01*
X56322Y-348130D01*
X56530Y-346735D01*
X56322Y-345495D01*
X55280Y-344255D01*
X54030Y-343480D01*
X52780Y-343325D01*
X51322Y-343635D01*
X50280Y-344720D01*
X49863Y-345805D01*
Y-347200D01*
G01Y-345805D02*
X49238Y-344875D01*
X48197Y-344100D01*
X46947Y-343790D01*
X45697Y-344100D01*
X44655Y-344875D01*
X44030Y-346270D01*
X44238Y-347665D01*
X45072Y-349060D01*
G01X56530Y-334490D02*
X56322Y-333405D01*
X55697Y-332165D01*
X54655Y-331390D01*
X53197Y-331080D01*
X51739Y-331390D01*
X50488Y-332320D01*
X49863Y-333715D01*
Y-335265D01*
X49447Y-336195D01*
X48405Y-336970D01*
X46947Y-337280D01*
X45488Y-336815D01*
X44447Y-335730D01*
X44030Y-334490D01*
X44447Y-333250D01*
X45488Y-332165D01*
X46947Y-331700D01*
X48405Y-332010D01*
X49447Y-332785D01*
X49863Y-333715D01*
Y-335265D01*
X50488Y-336660D01*
X51739Y-337590D01*
X53197Y-337900D01*
X54655Y-337590D01*
X55697Y-336815D01*
X56322Y-335575D01*
X56530Y-334490D01*
G01X54030Y-325500D02*
X55489Y-324570D01*
X56322Y-323330D01*
X56530Y-321935D01*
X56322Y-320695D01*
X55280Y-319455D01*
X54030Y-318680D01*
X52780Y-318525D01*
X51322Y-318835D01*
X50280Y-319920D01*
X49863Y-321005D01*
Y-322400D01*
G01Y-321005D02*
X49238Y-320075D01*
X48197Y-319300D01*
X46947Y-318990D01*
X45697Y-319300D01*
X44655Y-320075D01*
X44030Y-321470D01*
X44238Y-322865D01*
X45072Y-324260D01*
G01X56947Y-309690D02*
X56738Y-310000D01*
X56322D01*
X56113Y-309690D01*
X56322Y-309380D01*
X56738D01*
X56947Y-309690D01*
G01X56530Y-295430D02*
X44030D01*
X52988Y-301165D01*
Y-293415D01*
G01X51322Y-287835D02*
X49863Y-286750D01*
X49030Y-285820D01*
X48613Y-284580D01*
X49030Y-283495D01*
X49863Y-282720D01*
X51113Y-282100D01*
X52572Y-281945D01*
X53822Y-282100D01*
X55072Y-282720D01*
X56113Y-283650D01*
X56530Y-284735D01*
X56113Y-285975D01*
X54864Y-287060D01*
X52988Y-287680D01*
X50905Y-287835D01*
X48197Y-287525D01*
X46738Y-287060D01*
X45280Y-286285D01*
X44238Y-285200D01*
X44030Y-284115D01*
X44447Y-283030D01*
X45488Y-282255D01*
G01X55072Y-252925D02*
X56113Y-251840D01*
X56530Y-250600D01*
X56113Y-249360D01*
X54864Y-248275D01*
X52988Y-247500D01*
X51113Y-247190D01*
X48822D01*
X46947Y-247500D01*
X45280Y-248275D01*
X44447Y-249205D01*
X44030Y-250290D01*
X44447Y-251530D01*
X45280Y-252460D01*
X46530Y-253080D01*
X48197Y-253390D01*
X49655Y-253080D01*
X51113Y-252305D01*
X51947Y-251375D01*
X52155Y-250290D01*
X51739Y-249050D01*
X50697Y-248120D01*
X48822Y-247190D01*
G01X56947Y-237890D02*
X56738Y-238200D01*
X56322D01*
X56113Y-237890D01*
X56322Y-237580D01*
X56738D01*
X56947Y-237890D01*
G01X56530Y-225800D02*
X53822Y-225490D01*
X51530Y-225025D01*
X49447Y-224405D01*
X47155Y-223630D01*
X44030Y-222390D01*
Y-228590D01*
G01X56530Y-211230D02*
X44030D01*
X52988Y-216965D01*
Y-209215D01*
G01X80040Y-357780D02*
X67540D01*
X76498Y-363515D01*
Y-355765D01*
G01X67540Y-347240D02*
X67957Y-348480D01*
X68998Y-349410D01*
X70248Y-350030D01*
X71915Y-350495D01*
X73790Y-350650D01*
X75665Y-350495D01*
X77332Y-350030D01*
X78582Y-349410D01*
X79623Y-348480D01*
X80040Y-347240D01*
X79623Y-346000D01*
X78582Y-345070D01*
X77332Y-344450D01*
X75665Y-343985D01*
X73790Y-343830D01*
X71915Y-343985D01*
X70248Y-344450D01*
X68998Y-345070D01*
X67957Y-346000D01*
X67540Y-347240D01*
G01X80040Y-335150D02*
X77332Y-334840D01*
X75040Y-334375D01*
X72957Y-333755D01*
X70665Y-332980D01*
X67540Y-331740D01*
Y-337940D01*
G01X80457Y-322440D02*
X80248Y-322750D01*
X79832D01*
X79623Y-322440D01*
X79832Y-322130D01*
X80248D01*
X80457Y-322440D01*
G01X67540Y-310040D02*
X67957Y-311280D01*
X68998Y-312210D01*
X70248Y-312830D01*
X71915Y-313295D01*
X73790Y-313450D01*
X75665Y-313295D01*
X77332Y-312830D01*
X78582Y-312210D01*
X79623Y-311280D01*
X80040Y-310040D01*
X79623Y-308800D01*
X78582Y-307870D01*
X77332Y-307250D01*
X75665Y-306785D01*
X73790Y-306630D01*
X71915Y-306785D01*
X70248Y-307250D01*
X68998Y-307870D01*
X67957Y-308800D01*
X67540Y-310040D01*
G01X80040Y-297640D02*
X79832Y-296555D01*
X79207Y-295315D01*
X78165Y-294540D01*
X76707Y-294230D01*
X75249Y-294540D01*
X73998Y-295470D01*
X73373Y-296865D01*
Y-298415D01*
X72957Y-299345D01*
X71915Y-300120D01*
X70457Y-300430D01*
X68998Y-299965D01*
X67957Y-298880D01*
X67540Y-297640D01*
X67957Y-296400D01*
X68998Y-295315D01*
X70457Y-294850D01*
X71915Y-295160D01*
X72957Y-295935D01*
X73373Y-296865D01*
Y-298415D01*
X73998Y-299810D01*
X75249Y-300740D01*
X76707Y-301050D01*
X78165Y-300740D01*
X79207Y-299965D01*
X79832Y-298725D01*
X80040Y-297640D01*
G01Y-263040D02*
X67540D01*
X70040Y-264900D01*
G01X80040D02*
Y-261180D01*
G01X67540Y-250640D02*
X67957Y-251880D01*
X68998Y-252810D01*
X70248Y-253430D01*
X71915Y-253895D01*
X73790Y-254050D01*
X75665Y-253895D01*
X77332Y-253430D01*
X78582Y-252810D01*
X79623Y-251880D01*
X80040Y-250640D01*
X79623Y-249400D01*
X78582Y-248470D01*
X77332Y-247850D01*
X75665Y-247385D01*
X73790Y-247230D01*
X71915Y-247385D01*
X70248Y-247850D01*
X68998Y-248470D01*
X67957Y-249400D01*
X67540Y-250640D01*
G01X80457Y-238240D02*
X80248Y-238550D01*
X79832D01*
X79623Y-238240D01*
X79832Y-237930D01*
X80248D01*
X80457Y-238240D01*
G01X77540Y-229250D02*
X78999Y-228320D01*
X79832Y-227080D01*
X80040Y-225685D01*
X79832Y-224445D01*
X78790Y-223205D01*
X77540Y-222430D01*
X76290Y-222275D01*
X74832Y-222585D01*
X73790Y-223670D01*
X73373Y-224755D01*
Y-226150D01*
G01Y-224755D02*
X72748Y-223825D01*
X71707Y-223050D01*
X70457Y-222740D01*
X69207Y-223050D01*
X68165Y-223825D01*
X67540Y-225220D01*
X67748Y-226615D01*
X68582Y-228010D01*
G01X80040Y-211580D02*
X67540D01*
X76498Y-217315D01*
Y-209565D01*
G01X101675Y-326340D02*
X102717Y-325410D01*
X103342Y-324325D01*
X103550Y-322930D01*
X103133Y-321535D01*
X102300Y-320450D01*
X100842Y-319675D01*
X99175Y-319520D01*
X97508Y-319830D01*
X96467Y-320605D01*
X95633Y-321690D01*
X95425Y-322775D01*
X95633Y-323860D01*
X96467Y-325255D01*
X91050Y-324790D01*
Y-320605D01*
G01X103550Y-310530D02*
X91050D01*
X93550Y-312390D01*
G01X103550D02*
Y-308670D01*
G01Y-298130D02*
X91050D01*
X93550Y-299990D01*
G01X103550D02*
Y-296270D01*
G01X103967Y-285730D02*
X103758Y-286040D01*
X103342D01*
X103133Y-285730D01*
X103342Y-285420D01*
X103758D01*
X103967Y-285730D01*
G01X103550Y-273330D02*
X103342Y-272245D01*
X102717Y-271005D01*
X101675Y-270230D01*
X100217Y-269920D01*
X98759Y-270230D01*
X97508Y-271160D01*
X96883Y-272555D01*
Y-274105D01*
X96467Y-275035D01*
X95425Y-275810D01*
X93967Y-276120D01*
X92508Y-275655D01*
X91467Y-274570D01*
X91050Y-273330D01*
X91467Y-272090D01*
X92508Y-271005D01*
X93967Y-270540D01*
X95425Y-270850D01*
X96467Y-271625D01*
X96883Y-272555D01*
Y-274105D01*
X97508Y-275500D01*
X98759Y-276430D01*
X100217Y-276740D01*
X101675Y-276430D01*
X102717Y-275655D01*
X103342Y-274415D01*
X103550Y-273330D01*
G01X91050Y-260930D02*
X91467Y-262170D01*
X92508Y-263100D01*
X93758Y-263720D01*
X95425Y-264185D01*
X97300Y-264340D01*
X99175Y-264185D01*
X100842Y-263720D01*
X102092Y-263100D01*
X103133Y-262170D01*
X103550Y-260930D01*
X103133Y-259690D01*
X102092Y-258760D01*
X100842Y-258140D01*
X99175Y-257675D01*
X97300Y-257520D01*
X95425Y-257675D01*
X93758Y-258140D01*
X92508Y-258760D01*
X91467Y-259690D01*
X91050Y-260930D01*
G01X103550Y-226330D02*
X91050D01*
X93550Y-228190D01*
G01X103550D02*
Y-224470D01*
G01X101050Y-217340D02*
X102509Y-216410D01*
X103342Y-215170D01*
X103550Y-213775D01*
X103342Y-212535D01*
X102300Y-211295D01*
X101050Y-210520D01*
X99800Y-210365D01*
X98342Y-210675D01*
X97300Y-211760D01*
X96883Y-212845D01*
Y-214240D01*
G01Y-212845D02*
X96258Y-211915D01*
X95217Y-211140D01*
X93967Y-210830D01*
X92717Y-211140D01*
X91675Y-211915D01*
X91050Y-213310D01*
X91258Y-214705D01*
X92092Y-216100D01*
G01X127105Y-363430D02*
X128147Y-362500D01*
X128772Y-361415D01*
X128980Y-360020D01*
X128563Y-358625D01*
X127730Y-357540D01*
X126272Y-356765D01*
X124605Y-356610D01*
X122938Y-356920D01*
X121897Y-357695D01*
X121063Y-358780D01*
X120855Y-359865D01*
X121063Y-360950D01*
X121897Y-362345D01*
X116480Y-361880D01*
Y-357695D01*
G01X128980Y-347620D02*
X128772Y-346535D01*
X128147Y-345295D01*
X127105Y-344520D01*
X125647Y-344210D01*
X124189Y-344520D01*
X122938Y-345450D01*
X122313Y-346845D01*
Y-348395D01*
X121897Y-349325D01*
X120855Y-350100D01*
X119397Y-350410D01*
X117938Y-349945D01*
X116897Y-348860D01*
X116480Y-347620D01*
X116897Y-346380D01*
X117938Y-345295D01*
X119397Y-344830D01*
X120855Y-345140D01*
X121897Y-345915D01*
X122313Y-346845D01*
Y-348395D01*
X122938Y-349790D01*
X124189Y-350720D01*
X125647Y-351030D01*
X127105Y-350720D01*
X128147Y-349945D01*
X128772Y-348705D01*
X128980Y-347620D01*
G01X123772Y-338165D02*
X122313Y-337080D01*
X121480Y-336150D01*
X121063Y-334910D01*
X121480Y-333825D01*
X122313Y-333050D01*
X123563Y-332430D01*
X125022Y-332275D01*
X126272Y-332430D01*
X127522Y-333050D01*
X128563Y-333980D01*
X128980Y-335065D01*
X128563Y-336305D01*
X127314Y-337390D01*
X125438Y-338010D01*
X123355Y-338165D01*
X120647Y-337855D01*
X119188Y-337390D01*
X117730Y-336615D01*
X116688Y-335530D01*
X116480Y-334445D01*
X116897Y-333360D01*
X117938Y-332585D01*
G01X129397Y-322820D02*
X129188Y-323130D01*
X128772D01*
X128563Y-322820D01*
X128772Y-322510D01*
X129188D01*
X129397Y-322820D01*
G01X116480Y-310420D02*
X116897Y-311660D01*
X117938Y-312590D01*
X119188Y-313210D01*
X120855Y-313675D01*
X122730Y-313830D01*
X124605Y-313675D01*
X126272Y-313210D01*
X127522Y-312590D01*
X128563Y-311660D01*
X128980Y-310420D01*
X128563Y-309180D01*
X127522Y-308250D01*
X126272Y-307630D01*
X124605Y-307165D01*
X122730Y-307010D01*
X120855Y-307165D01*
X119188Y-307630D01*
X117938Y-308250D01*
X116897Y-309180D01*
X116480Y-310420D01*
G01X127522Y-300655D02*
X128563Y-299570D01*
X128980Y-298330D01*
X128563Y-297090D01*
X127314Y-296005D01*
X125438Y-295230D01*
X123563Y-294920D01*
X121272D01*
X119397Y-295230D01*
X117730Y-296005D01*
X116897Y-296935D01*
X116480Y-298020D01*
X116897Y-299260D01*
X117730Y-300190D01*
X118980Y-300810D01*
X120647Y-301120D01*
X122105Y-300810D01*
X123563Y-300035D01*
X124397Y-299105D01*
X124605Y-298020D01*
X124189Y-296780D01*
X123147Y-295850D01*
X121272Y-294920D01*
G01X128980Y-263420D02*
X116480D01*
X118980Y-265280D01*
G01X128980D02*
Y-261560D01*
G01Y-249160D02*
X116480D01*
X125438Y-254895D01*
Y-247145D01*
G01X129397Y-238620D02*
X129188Y-238930D01*
X128772D01*
X128563Y-238620D01*
X128772Y-238310D01*
X129188D01*
X129397Y-238620D01*
G01X128980Y-226220D02*
X128772Y-225135D01*
X128147Y-223895D01*
X127105Y-223120D01*
X125647Y-222810D01*
X124189Y-223120D01*
X122938Y-224050D01*
X122313Y-225445D01*
Y-226995D01*
X121897Y-227925D01*
X120855Y-228700D01*
X119397Y-229010D01*
X117938Y-228545D01*
X116897Y-227460D01*
X116480Y-226220D01*
X116897Y-224980D01*
X117938Y-223895D01*
X119397Y-223430D01*
X120855Y-223740D01*
X121897Y-224515D01*
X122313Y-225445D01*
Y-226995D01*
X122938Y-228390D01*
X124189Y-229320D01*
X125647Y-229630D01*
X127105Y-229320D01*
X128147Y-228545D01*
X128772Y-227305D01*
X128980Y-226220D01*
G01X127522Y-216455D02*
X128563Y-215370D01*
X128980Y-214130D01*
X128563Y-212890D01*
X127314Y-211805D01*
X125438Y-211030D01*
X123563Y-210720D01*
X121272D01*
X119397Y-211030D01*
X117730Y-211805D01*
X116897Y-212735D01*
X116480Y-213820D01*
X116897Y-215060D01*
X117730Y-215990D01*
X118980Y-216610D01*
X120647Y-216920D01*
X122105Y-216610D01*
X123563Y-215835D01*
X124397Y-214905D01*
X124605Y-213820D01*
X124189Y-212580D01*
X123147Y-211650D01*
X121272Y-210720D01*
G01X127690Y222810D02*
Y230810D01*
X132290Y222810D01*
Y230810D01*
G01X135990Y222810D02*
Y230810D01*
X138390D01*
X139190Y230410D01*
X139790Y229477D01*
X139990Y228410D01*
X139790Y227343D01*
X139290Y226543D01*
X138390Y226143D01*
X135990D01*
G01X145990Y230810D02*
Y222810D01*
G01X143690Y230810D02*
X148290D01*
G01X151890Y222810D02*
Y230810D01*
G01X156090D02*
Y222810D01*
G01Y226810D02*
X151890D01*
G01X160580Y-361100D02*
X157872Y-360790D01*
X155580Y-360325D01*
X153497Y-359705D01*
X151205Y-358930D01*
X148080Y-357690D01*
Y-363890D01*
G01X159122Y-351025D02*
X160163Y-349940D01*
X160580Y-348700D01*
X160163Y-347460D01*
X158914Y-346375D01*
X157038Y-345600D01*
X155163Y-345290D01*
X152872D01*
X150997Y-345600D01*
X149330Y-346375D01*
X148497Y-347305D01*
X148080Y-348390D01*
X148497Y-349630D01*
X149330Y-350560D01*
X150580Y-351180D01*
X152247Y-351490D01*
X153705Y-351180D01*
X155163Y-350405D01*
X155997Y-349475D01*
X156205Y-348390D01*
X155789Y-347150D01*
X154747Y-346220D01*
X152872Y-345290D01*
G01X158705Y-339400D02*
X159747Y-338470D01*
X160372Y-337385D01*
X160580Y-335990D01*
X160163Y-334595D01*
X159330Y-333510D01*
X157872Y-332735D01*
X156205Y-332580D01*
X154538Y-332890D01*
X153497Y-333665D01*
X152663Y-334750D01*
X152455Y-335835D01*
X152663Y-336920D01*
X153497Y-338315D01*
X148080Y-337850D01*
Y-333665D01*
G01X160997Y-323590D02*
X160788Y-323900D01*
X160372D01*
X160163Y-323590D01*
X160372Y-323280D01*
X160788D01*
X160997Y-323590D01*
G01X159122Y-313825D02*
X160163Y-312740D01*
X160580Y-311500D01*
X160163Y-310260D01*
X158914Y-309175D01*
X157038Y-308400D01*
X155163Y-308090D01*
X152872D01*
X150997Y-308400D01*
X149330Y-309175D01*
X148497Y-310105D01*
X148080Y-311190D01*
X148497Y-312430D01*
X149330Y-313360D01*
X150580Y-313980D01*
X152247Y-314290D01*
X153705Y-313980D01*
X155163Y-313205D01*
X155997Y-312275D01*
X156205Y-311190D01*
X155789Y-309950D01*
X154747Y-309020D01*
X152872Y-308090D01*
G01X148080Y-298790D02*
X148497Y-300030D01*
X149538Y-300960D01*
X150788Y-301580D01*
X152455Y-302045D01*
X154330Y-302200D01*
X156205Y-302045D01*
X157872Y-301580D01*
X159122Y-300960D01*
X160163Y-300030D01*
X160580Y-298790D01*
X160163Y-297550D01*
X159122Y-296620D01*
X157872Y-296000D01*
X156205Y-295535D01*
X154330Y-295380D01*
X152455Y-295535D01*
X150788Y-296000D01*
X149538Y-296620D01*
X148497Y-297550D01*
X148080Y-298790D01*
G01X150163Y-267135D02*
X148914Y-266205D01*
X148288Y-265120D01*
X148080Y-263880D01*
X148497Y-262330D01*
X149538Y-261245D01*
X150788Y-260935D01*
X152039Y-261090D01*
X153080Y-261710D01*
X155163Y-264810D01*
X156622Y-266205D01*
X158705Y-267135D01*
X160580Y-267445D01*
Y-260935D01*
G01X148080Y-251790D02*
X148497Y-253030D01*
X149538Y-253960D01*
X150788Y-254580D01*
X152455Y-255045D01*
X154330Y-255200D01*
X156205Y-255045D01*
X157872Y-254580D01*
X159122Y-253960D01*
X160163Y-253030D01*
X160580Y-251790D01*
X160163Y-250550D01*
X159122Y-249620D01*
X157872Y-249000D01*
X156205Y-248535D01*
X154330Y-248380D01*
X152455Y-248535D01*
X150788Y-249000D01*
X149538Y-249620D01*
X148497Y-250550D01*
X148080Y-251790D01*
G01X160997Y-239390D02*
X160788Y-239700D01*
X160372D01*
X160163Y-239390D01*
X160372Y-239080D01*
X160788D01*
X160997Y-239390D01*
G01X150163Y-229935D02*
X148914Y-229005D01*
X148288Y-227920D01*
X148080Y-226680D01*
X148497Y-225130D01*
X149538Y-224045D01*
X150788Y-223735D01*
X152039Y-223890D01*
X153080Y-224510D01*
X155163Y-227610D01*
X156622Y-229005D01*
X158705Y-229935D01*
X160580Y-230245D01*
Y-223735D01*
G01X150163Y-217535D02*
X148914Y-216605D01*
X148288Y-215520D01*
X148080Y-214280D01*
X148497Y-212730D01*
X149538Y-211645D01*
X150788Y-211335D01*
X152039Y-211490D01*
X153080Y-212110D01*
X155163Y-215210D01*
X156622Y-216605D01*
X158705Y-217535D01*
X160580Y-217845D01*
Y-211335D01*
G01X185240Y-373930D02*
X172740D01*
X175240Y-375790D01*
G01X185240D02*
Y-372070D01*
G01Y-361530D02*
X172740D01*
X175240Y-363390D01*
G01X185240D02*
Y-359670D01*
G01Y-349440D02*
X182532Y-349130D01*
X180240Y-348665D01*
X178157Y-348045D01*
X175865Y-347270D01*
X172740Y-346030D01*
Y-352230D01*
G01X183782Y-339365D02*
X184823Y-338280D01*
X185240Y-337040D01*
X184823Y-335800D01*
X183574Y-334715D01*
X181698Y-333940D01*
X179823Y-333630D01*
X177532D01*
X175657Y-333940D01*
X173990Y-334715D01*
X173157Y-335645D01*
X172740Y-336730D01*
X173157Y-337970D01*
X173990Y-338900D01*
X175240Y-339520D01*
X176907Y-339830D01*
X178365Y-339520D01*
X179823Y-338745D01*
X180657Y-337815D01*
X180865Y-336730D01*
X180449Y-335490D01*
X179407Y-334560D01*
X177532Y-333630D01*
G01X185657Y-324330D02*
X185448Y-324640D01*
X185032D01*
X184823Y-324330D01*
X185032Y-324020D01*
X185448D01*
X185657Y-324330D01*
G01X182740Y-315340D02*
X184199Y-314410D01*
X185032Y-313170D01*
X185240Y-311775D01*
X185032Y-310535D01*
X183990Y-309295D01*
X182740Y-308520D01*
X181490Y-308365D01*
X180032Y-308675D01*
X178990Y-309760D01*
X178573Y-310845D01*
Y-312240D01*
G01Y-310845D02*
X177948Y-309915D01*
X176907Y-309140D01*
X175657Y-308830D01*
X174407Y-309140D01*
X173365Y-309915D01*
X172740Y-311310D01*
X172948Y-312705D01*
X173782Y-314100D01*
G01X182740Y-302940D02*
X184199Y-302010D01*
X185032Y-300770D01*
X185240Y-299375D01*
X185032Y-298135D01*
X183990Y-296895D01*
X182740Y-296120D01*
X181490Y-295965D01*
X180032Y-296275D01*
X178990Y-297360D01*
X178573Y-298445D01*
Y-299840D01*
G01Y-298445D02*
X177948Y-297515D01*
X176907Y-296740D01*
X175657Y-296430D01*
X174407Y-296740D01*
X173365Y-297515D01*
X172740Y-298910D01*
X172948Y-300305D01*
X173782Y-301700D01*
G01X174823Y-267875D02*
X173574Y-266945D01*
X172948Y-265860D01*
X172740Y-264620D01*
X173157Y-263070D01*
X174198Y-261985D01*
X175448Y-261675D01*
X176699Y-261830D01*
X177740Y-262450D01*
X179823Y-265550D01*
X181282Y-266945D01*
X183365Y-267875D01*
X185240Y-268185D01*
Y-261675D01*
G01X183782Y-255165D02*
X184823Y-254080D01*
X185240Y-252840D01*
X184823Y-251600D01*
X183574Y-250515D01*
X181698Y-249740D01*
X179823Y-249430D01*
X177532D01*
X175657Y-249740D01*
X173990Y-250515D01*
X173157Y-251445D01*
X172740Y-252530D01*
X173157Y-253770D01*
X173990Y-254700D01*
X175240Y-255320D01*
X176907Y-255630D01*
X178365Y-255320D01*
X179823Y-254545D01*
X180657Y-253615D01*
X180865Y-252530D01*
X180449Y-251290D01*
X179407Y-250360D01*
X177532Y-249430D01*
G01X185657Y-240130D02*
X185448Y-240440D01*
X185032D01*
X184823Y-240130D01*
X185032Y-239820D01*
X185448D01*
X185657Y-240130D01*
G01X183782Y-230365D02*
X184823Y-229280D01*
X185240Y-228040D01*
X184823Y-226800D01*
X183574Y-225715D01*
X181698Y-224940D01*
X179823Y-224630D01*
X177532D01*
X175657Y-224940D01*
X173990Y-225715D01*
X173157Y-226645D01*
X172740Y-227730D01*
X173157Y-228970D01*
X173990Y-229900D01*
X175240Y-230520D01*
X176907Y-230830D01*
X178365Y-230520D01*
X179823Y-229745D01*
X180657Y-228815D01*
X180865Y-227730D01*
X180449Y-226490D01*
X179407Y-225560D01*
X177532Y-224630D01*
G01X183365Y-218740D02*
X184407Y-217810D01*
X185032Y-216725D01*
X185240Y-215330D01*
X184823Y-213935D01*
X183990Y-212850D01*
X182532Y-212075D01*
X180865Y-211920D01*
X179198Y-212230D01*
X178157Y-213005D01*
X177323Y-214090D01*
X177115Y-215175D01*
X177323Y-216260D01*
X178157Y-217655D01*
X172740Y-217190D01*
Y-213005D01*
G01X202000Y-569638D02*
Y-577638D01*
X206000D01*
G01X213800D02*
Y-572305D01*
G01Y-573238D02*
X213400Y-572705D01*
X212800Y-572438D01*
X212100Y-572305D01*
X211400Y-572571D01*
X210800Y-573105D01*
X210400Y-573905D01*
X210200Y-574971D01*
X210400Y-576038D01*
X210800Y-576838D01*
X211400Y-577371D01*
X212100Y-577638D01*
X212800Y-577505D01*
X213400Y-577105D01*
X213800Y-576572D01*
G01X217900Y-580038D02*
X218500Y-580305D01*
X219300Y-580038D01*
X219800Y-579505D01*
X220200Y-578838D01*
X220800Y-576705D01*
X222100Y-572305D01*
G01X218900D02*
X220800Y-576705D01*
G01X226500Y-574038D02*
X229700D01*
X229400Y-573105D01*
X228900Y-572571D01*
X228200Y-572305D01*
X227500Y-572438D01*
X226900Y-572838D01*
X226500Y-573771D01*
X226300Y-574572D01*
Y-575371D01*
X226500Y-576171D01*
X227000Y-576971D01*
X227600Y-577505D01*
X228300Y-577638D01*
X229000Y-577371D01*
X229700Y-576572D01*
G01X234600Y-577638D02*
Y-572305D01*
G01Y-573371D02*
X235100Y-572838D01*
X235600Y-572438D01*
X236300Y-572305D01*
X236800Y-572438D01*
X237400Y-572838D01*
G01X226000Y-626038D02*
X226500Y-626838D01*
X227100Y-627371D01*
X227800Y-627638D01*
X228600Y-627371D01*
X229200Y-626838D01*
X229800Y-626038D01*
X230000Y-624971D01*
Y-619638D01*
G01X237800Y-627638D02*
Y-622305D01*
G01Y-623238D02*
X237400Y-622705D01*
X236800Y-622438D01*
X236100Y-622305D01*
X235400Y-622571D01*
X234800Y-623105D01*
X234400Y-623905D01*
X234200Y-624971D01*
X234400Y-626038D01*
X234800Y-626838D01*
X235400Y-627371D01*
X236100Y-627638D01*
X236800Y-627505D01*
X237400Y-627105D01*
X237800Y-626572D01*
G01X245600Y-622971D02*
X244900Y-622438D01*
X244300Y-622305D01*
X243500Y-622571D01*
X242900Y-623105D01*
X242500Y-624038D01*
X242400Y-624971D01*
X242500Y-625905D01*
X242900Y-626705D01*
X243500Y-627371D01*
X244300Y-627638D01*
X245000Y-627371D01*
X245600Y-626838D01*
G01X250300Y-627638D02*
Y-619638D01*
G01X253500Y-622305D02*
X250300Y-625371D01*
G01X251600Y-624171D02*
X253700Y-627638D01*
G01X226100Y-602638D02*
Y-594638D01*
X229900D01*
G01X228500Y-598505D02*
X226100D01*
G01X233500Y-602638D02*
X236000Y-594638D01*
X238500Y-602638D01*
G01X237600Y-599838D02*
X234400D01*
G01X244800Y-598371D02*
X245200Y-597971D01*
X245500Y-597305D01*
X245700Y-596371D01*
X245500Y-595571D01*
X245100Y-595038D01*
X244400Y-594638D01*
X241700D01*
Y-602638D01*
X245000D01*
X245700Y-602105D01*
X246100Y-601305D01*
X246300Y-600371D01*
X246100Y-599438D01*
X245500Y-598638D01*
X244800Y-598371D01*
X241700D01*
G01X225693Y-377645D02*
X224444Y-376715D01*
X223818Y-375630D01*
X223610Y-374390D01*
X224027Y-372840D01*
X225068Y-371755D01*
X226318Y-371445D01*
X227569Y-371600D01*
X228610Y-372220D01*
X230693Y-375320D01*
X232152Y-376715D01*
X234235Y-377645D01*
X236110Y-377955D01*
Y-371445D01*
G01Y-362300D02*
X223610D01*
X226110Y-364160D01*
G01X236110D02*
Y-360440D01*
G01X234235Y-353310D02*
X235277Y-352380D01*
X235902Y-351295D01*
X236110Y-349900D01*
X235693Y-348505D01*
X234860Y-347420D01*
X233402Y-346645D01*
X231735Y-346490D01*
X230068Y-346800D01*
X229027Y-347575D01*
X228193Y-348660D01*
X227985Y-349745D01*
X228193Y-350830D01*
X229027Y-352225D01*
X223610Y-351760D01*
Y-347575D01*
G01X236110Y-335640D02*
X223610D01*
X232568Y-341375D01*
Y-333625D01*
G01X236527Y-325100D02*
X236318Y-325410D01*
X235902D01*
X235693Y-325100D01*
X235902Y-324790D01*
X236318D01*
X236527Y-325100D01*
G01X236110Y-312700D02*
X223610D01*
X226110Y-314560D01*
G01X236110D02*
Y-310840D01*
G01Y-300300D02*
X235902Y-299215D01*
X235277Y-297975D01*
X234235Y-297200D01*
X232777Y-296890D01*
X231319Y-297200D01*
X230068Y-298130D01*
X229443Y-299525D01*
Y-301075D01*
X229027Y-302005D01*
X227985Y-302780D01*
X226527Y-303090D01*
X225068Y-302625D01*
X224027Y-301540D01*
X223610Y-300300D01*
X224027Y-299060D01*
X225068Y-297975D01*
X226527Y-297510D01*
X227985Y-297820D01*
X229027Y-298595D01*
X229443Y-299525D01*
Y-301075D01*
X230068Y-302470D01*
X231319Y-303400D01*
X232777Y-303710D01*
X234235Y-303400D01*
X235277Y-302625D01*
X235902Y-301385D01*
X236110Y-300300D01*
G01X234235Y-269110D02*
X235277Y-268180D01*
X235902Y-267095D01*
X236110Y-265700D01*
X235693Y-264305D01*
X234860Y-263220D01*
X233402Y-262445D01*
X231735Y-262290D01*
X230068Y-262600D01*
X229027Y-263375D01*
X228193Y-264460D01*
X227985Y-265545D01*
X228193Y-266630D01*
X229027Y-268025D01*
X223610Y-267560D01*
Y-263375D01*
G01X236110Y-251440D02*
X223610D01*
X232568Y-257175D01*
Y-249425D01*
G01X236527Y-240900D02*
X236318Y-241210D01*
X235902D01*
X235693Y-240900D01*
X235902Y-240590D01*
X236318D01*
X236527Y-240900D01*
G01X236110Y-228810D02*
X233402Y-228500D01*
X231110Y-228035D01*
X229027Y-227415D01*
X226735Y-226640D01*
X223610Y-225400D01*
Y-231600D01*
G01X225693Y-219045D02*
X224444Y-218115D01*
X223818Y-217030D01*
X223610Y-215790D01*
X224027Y-214240D01*
X225068Y-213155D01*
X226318Y-212845D01*
X227569Y-213000D01*
X228610Y-213620D01*
X230693Y-216720D01*
X232152Y-218115D01*
X234235Y-219045D01*
X236110Y-219355D01*
Y-212845D01*
G01X233405Y1658621D02*
G03I-2500J0D01*
G01Y1644448D02*
G03I-2500J0D01*
G01Y1672795D02*
G03I-2500J0D01*
G01Y1686968D02*
G03I-2500J0D01*
G01Y1701141D02*
G03I-2500J0D01*
G01Y1715314D02*
G03I-2500J0D01*
G01Y1729488D02*
G03I-2500J0D01*
G01X246159Y-376875D02*
X244910Y-375945D01*
X244284Y-374860D01*
X244076Y-373620D01*
X244493Y-372070D01*
X245534Y-370985D01*
X246784Y-370675D01*
X248035Y-370830D01*
X249076Y-371450D01*
X251159Y-374550D01*
X252618Y-375945D01*
X254701Y-376875D01*
X256576Y-377185D01*
Y-370675D01*
G01X254701Y-364940D02*
X255743Y-364010D01*
X256368Y-362925D01*
X256576Y-361530D01*
X256159Y-360135D01*
X255326Y-359050D01*
X253868Y-358275D01*
X252201Y-358120D01*
X250534Y-358430D01*
X249493Y-359205D01*
X248659Y-360290D01*
X248451Y-361375D01*
X248659Y-362460D01*
X249493Y-363855D01*
X244076Y-363390D01*
Y-359205D01*
G01Y-349130D02*
X244493Y-350370D01*
X245534Y-351300D01*
X246784Y-351920D01*
X248451Y-352385D01*
X250326Y-352540D01*
X252201Y-352385D01*
X253868Y-351920D01*
X255118Y-351300D01*
X256159Y-350370D01*
X256576Y-349130D01*
X256159Y-347890D01*
X255118Y-346960D01*
X253868Y-346340D01*
X252201Y-345875D01*
X250326Y-345720D01*
X248451Y-345875D01*
X246784Y-346340D01*
X245534Y-346960D01*
X244493Y-347890D01*
X244076Y-349130D01*
G01X254076Y-340140D02*
X255535Y-339210D01*
X256368Y-337970D01*
X256576Y-336575D01*
X256368Y-335335D01*
X255326Y-334095D01*
X254076Y-333320D01*
X252826Y-333165D01*
X251368Y-333475D01*
X250326Y-334560D01*
X249909Y-335645D01*
Y-337040D01*
G01Y-335645D02*
X249284Y-334715D01*
X248243Y-333940D01*
X246993Y-333630D01*
X245743Y-333940D01*
X244701Y-334715D01*
X244076Y-336110D01*
X244284Y-337505D01*
X245118Y-338900D01*
G01X256993Y-324330D02*
X256784Y-324640D01*
X256368D01*
X256159Y-324330D01*
X256368Y-324020D01*
X256784D01*
X256993Y-324330D01*
G01X246159Y-314875D02*
X244910Y-313945D01*
X244284Y-312860D01*
X244076Y-311620D01*
X244493Y-310070D01*
X245534Y-308985D01*
X246784Y-308675D01*
X248035Y-308830D01*
X249076Y-309450D01*
X251159Y-312550D01*
X252618Y-313945D01*
X254701Y-314875D01*
X256576Y-315185D01*
Y-308675D01*
G01X251368Y-302475D02*
X249909Y-301390D01*
X249076Y-300460D01*
X248659Y-299220D01*
X249076Y-298135D01*
X249909Y-297360D01*
X251159Y-296740D01*
X252618Y-296585D01*
X253868Y-296740D01*
X255118Y-297360D01*
X256159Y-298290D01*
X256576Y-299375D01*
X256159Y-300615D01*
X254910Y-301700D01*
X253034Y-302320D01*
X250951Y-302475D01*
X248243Y-302165D01*
X246784Y-301700D01*
X245326Y-300925D01*
X244284Y-299840D01*
X244076Y-298755D01*
X244493Y-297670D01*
X245534Y-296895D01*
G01X251368Y-267875D02*
X249909Y-266790D01*
X249076Y-265860D01*
X248659Y-264620D01*
X249076Y-263535D01*
X249909Y-262760D01*
X251159Y-262140D01*
X252618Y-261985D01*
X253868Y-262140D01*
X255118Y-262760D01*
X256159Y-263690D01*
X256576Y-264775D01*
X256159Y-266015D01*
X254910Y-267100D01*
X253034Y-267720D01*
X250951Y-267875D01*
X248243Y-267565D01*
X246784Y-267100D01*
X245326Y-266325D01*
X244284Y-265240D01*
X244076Y-264155D01*
X244493Y-263070D01*
X245534Y-262295D01*
G01X254076Y-255940D02*
X255535Y-255010D01*
X256368Y-253770D01*
X256576Y-252375D01*
X256368Y-251135D01*
X255326Y-249895D01*
X254076Y-249120D01*
X252826Y-248965D01*
X251368Y-249275D01*
X250326Y-250360D01*
X249909Y-251445D01*
Y-252840D01*
G01Y-251445D02*
X249284Y-250515D01*
X248243Y-249740D01*
X246993Y-249430D01*
X245743Y-249740D01*
X244701Y-250515D01*
X244076Y-251910D01*
X244284Y-253305D01*
X245118Y-254700D01*
G01X256993Y-240130D02*
X256784Y-240440D01*
X256368D01*
X256159Y-240130D01*
X256368Y-239820D01*
X256784D01*
X256993Y-240130D01*
G01X254701Y-231140D02*
X255743Y-230210D01*
X256368Y-229125D01*
X256576Y-227730D01*
X256159Y-226335D01*
X255326Y-225250D01*
X253868Y-224475D01*
X252201Y-224320D01*
X250534Y-224630D01*
X249493Y-225405D01*
X248659Y-226490D01*
X248451Y-227575D01*
X248659Y-228660D01*
X249493Y-230055D01*
X244076Y-229590D01*
Y-225405D01*
G01X256576Y-215330D02*
X256368Y-214245D01*
X255743Y-213005D01*
X254701Y-212230D01*
X253243Y-211920D01*
X251785Y-212230D01*
X250534Y-213160D01*
X249909Y-214555D01*
Y-216105D01*
X249493Y-217035D01*
X248451Y-217810D01*
X246993Y-218120D01*
X245534Y-217655D01*
X244493Y-216570D01*
X244076Y-215330D01*
X244493Y-214090D01*
X245534Y-213005D01*
X246993Y-212540D01*
X248451Y-212850D01*
X249493Y-213625D01*
X249909Y-214555D01*
Y-216105D01*
X250534Y-217500D01*
X251785Y-218430D01*
X253243Y-218740D01*
X254701Y-218430D01*
X255743Y-217655D01*
X256368Y-216415D01*
X256576Y-215330D01*
G01X249153Y1644448D02*
G03I-2500J0D01*
G01X241279Y1648385D02*
G03I-2500J0D01*
G01X249153Y1672795D02*
G03I-2500J0D01*
G01Y1658621D02*
G03I-2500J0D01*
G01X241279Y1662558D02*
G03I-2500J0D01*
G01X249153Y1686968D02*
G03I-2500J0D01*
G01X241279Y1676732D02*
G03I-2500J0D01*
G01X249153Y1701141D02*
G03I-2500J0D01*
G01X241279Y1690905D02*
G03I-2500J0D01*
G01X249153Y1715314D02*
G03I-2500J0D01*
G01X241279Y1705078D02*
G03I-2500J0D01*
G01X249153Y1729488D02*
G03I-2500J0D01*
G01X241279Y1719251D02*
G03I-2500J0D01*
G01Y1733425D02*
G03I-2500J0D01*
G01X264901Y1644448D02*
G03I-2500J0D01*
G01X257027Y1648385D02*
G03I-2500J0D01*
G01X264901Y1658621D02*
G03I-2500J0D01*
G01X257027Y1662558D02*
G03I-2500J0D01*
G01X264901Y1686968D02*
G03I-2500J0D01*
G01Y1672795D02*
G03I-2500J0D01*
G01X257027Y1676732D02*
G03I-2500J0D01*
G01X264901Y1701141D02*
G03I-2500J0D01*
G01X257027Y1690905D02*
G03I-2500J0D01*
G01X264901Y1715314D02*
G03I-2500J0D01*
G01X257027Y1705078D02*
G03I-2500J0D01*
G01X264901Y1729488D02*
G03I-2500J0D01*
G01X257027Y1719251D02*
G03I-2500J0D01*
G01Y1733425D02*
G03I-2500J0D01*
G01X270746Y-377645D02*
X269497Y-376715D01*
X268871Y-375630D01*
X268663Y-374390D01*
X269080Y-372840D01*
X270121Y-371755D01*
X271371Y-371445D01*
X272622Y-371600D01*
X273663Y-372220D01*
X275746Y-375320D01*
X277205Y-376715D01*
X279288Y-377645D01*
X281163Y-377955D01*
Y-371445D01*
G01Y-362610D02*
X278455Y-362300D01*
X276163Y-361835D01*
X274080Y-361215D01*
X271788Y-360440D01*
X268663Y-359200D01*
Y-365400D01*
G01X281163Y-348040D02*
X268663D01*
X277621Y-353775D01*
Y-346025D01*
G01X279705Y-340135D02*
X280746Y-339050D01*
X281163Y-337810D01*
X280746Y-336570D01*
X279497Y-335485D01*
X277621Y-334710D01*
X275746Y-334400D01*
X273455D01*
X271580Y-334710D01*
X269913Y-335485D01*
X269080Y-336415D01*
X268663Y-337500D01*
X269080Y-338740D01*
X269913Y-339670D01*
X271163Y-340290D01*
X272830Y-340600D01*
X274288Y-340290D01*
X275746Y-339515D01*
X276580Y-338585D01*
X276788Y-337500D01*
X276372Y-336260D01*
X275330Y-335330D01*
X273455Y-334400D01*
G01X281580Y-325100D02*
X281371Y-325410D01*
X280955D01*
X280746Y-325100D01*
X280955Y-324790D01*
X281371D01*
X281580Y-325100D01*
G01X281163Y-312700D02*
X268663D01*
X271163Y-314560D01*
G01X281163D02*
Y-310840D01*
G01X278663Y-303710D02*
X280122Y-302780D01*
X280955Y-301540D01*
X281163Y-300145D01*
X280955Y-298905D01*
X279913Y-297665D01*
X278663Y-296890D01*
X277413Y-296735D01*
X275955Y-297045D01*
X274913Y-298130D01*
X274496Y-299215D01*
Y-300610D01*
G01Y-299215D02*
X273871Y-298285D01*
X272830Y-297510D01*
X271580Y-297200D01*
X270330Y-297510D01*
X269288Y-298285D01*
X268663Y-299680D01*
X268871Y-301075D01*
X269705Y-302470D01*
G01X275955Y-268645D02*
X274496Y-267560D01*
X273663Y-266630D01*
X273246Y-265390D01*
X273663Y-264305D01*
X274496Y-263530D01*
X275746Y-262910D01*
X277205Y-262755D01*
X278455Y-262910D01*
X279705Y-263530D01*
X280746Y-264460D01*
X281163Y-265545D01*
X280746Y-266785D01*
X279497Y-267870D01*
X277621Y-268490D01*
X275538Y-268645D01*
X272830Y-268335D01*
X271371Y-267870D01*
X269913Y-267095D01*
X268871Y-266010D01*
X268663Y-264925D01*
X269080Y-263840D01*
X270121Y-263065D01*
G01X279705Y-255935D02*
X280746Y-254850D01*
X281163Y-253610D01*
X280746Y-252370D01*
X279497Y-251285D01*
X277621Y-250510D01*
X275746Y-250200D01*
X273455D01*
X271580Y-250510D01*
X269913Y-251285D01*
X269080Y-252215D01*
X268663Y-253300D01*
X269080Y-254540D01*
X269913Y-255470D01*
X271163Y-256090D01*
X272830Y-256400D01*
X274288Y-256090D01*
X275746Y-255315D01*
X276580Y-254385D01*
X276788Y-253300D01*
X276372Y-252060D01*
X275330Y-251130D01*
X273455Y-250200D01*
G01X281580Y-240900D02*
X281371Y-241210D01*
X280955D01*
X280746Y-240900D01*
X280955Y-240590D01*
X281371D01*
X281580Y-240900D01*
G01X281163Y-228500D02*
X280955Y-227415D01*
X280330Y-226175D01*
X279288Y-225400D01*
X277830Y-225090D01*
X276372Y-225400D01*
X275121Y-226330D01*
X274496Y-227725D01*
Y-229275D01*
X274080Y-230205D01*
X273038Y-230980D01*
X271580Y-231290D01*
X270121Y-230825D01*
X269080Y-229740D01*
X268663Y-228500D01*
X269080Y-227260D01*
X270121Y-226175D01*
X271580Y-225710D01*
X273038Y-226020D01*
X274080Y-226795D01*
X274496Y-227725D01*
Y-229275D01*
X275121Y-230670D01*
X276372Y-231600D01*
X277830Y-231910D01*
X279288Y-231600D01*
X280330Y-230825D01*
X280955Y-229585D01*
X281163Y-228500D01*
G01X278663Y-219510D02*
X280122Y-218580D01*
X280955Y-217340D01*
X281163Y-215945D01*
X280955Y-214705D01*
X279913Y-213465D01*
X278663Y-212690D01*
X277413Y-212535D01*
X275955Y-212845D01*
X274913Y-213930D01*
X274496Y-215015D01*
Y-216410D01*
G01Y-215015D02*
X273871Y-214085D01*
X272830Y-213310D01*
X271580Y-213000D01*
X270330Y-213310D01*
X269288Y-214085D01*
X268663Y-215480D01*
X268871Y-216875D01*
X269705Y-218270D01*
G01X272775Y1648385D02*
G03I-2500J0D01*
G01Y1662558D02*
G03I-2500J0D01*
G01Y1676732D02*
G03I-2500J0D01*
G01Y1690905D02*
G03I-2500J0D01*
G01Y1705078D02*
G03I-2500J0D01*
G01Y1719251D02*
G03I-2500J0D01*
G01Y1733425D02*
G03I-2500J0D01*
G01X291973Y-378415D02*
X290724Y-377485D01*
X290098Y-376400D01*
X289890Y-375160D01*
X290307Y-373610D01*
X291348Y-372525D01*
X292598Y-372215D01*
X293849Y-372370D01*
X294890Y-372990D01*
X296973Y-376090D01*
X298432Y-377485D01*
X300515Y-378415D01*
X302390Y-378725D01*
Y-372215D01*
G01Y-363380D02*
X299682Y-363070D01*
X297390Y-362605D01*
X295307Y-361985D01*
X293015Y-361210D01*
X289890Y-359970D01*
Y-366170D01*
G01X297182Y-353615D02*
X295723Y-352530D01*
X294890Y-351600D01*
X294473Y-350360D01*
X294890Y-349275D01*
X295723Y-348500D01*
X296973Y-347880D01*
X298432Y-347725D01*
X299682Y-347880D01*
X300932Y-348500D01*
X301973Y-349430D01*
X302390Y-350515D01*
X301973Y-351755D01*
X300724Y-352840D01*
X298848Y-353460D01*
X296765Y-353615D01*
X294057Y-353305D01*
X292598Y-352840D01*
X291140Y-352065D01*
X290098Y-350980D01*
X289890Y-349895D01*
X290307Y-348810D01*
X291348Y-348035D01*
G01X302390Y-336410D02*
X289890D01*
X298848Y-342145D01*
Y-334395D01*
G01X302807Y-325870D02*
X302598Y-326180D01*
X302182D01*
X301973Y-325870D01*
X302182Y-325560D01*
X302598D01*
X302807Y-325870D01*
G01X302390Y-311610D02*
X289890D01*
X298848Y-317345D01*
Y-309595D01*
G01X289890Y-301070D02*
X290307Y-302310D01*
X291348Y-303240D01*
X292598Y-303860D01*
X294265Y-304325D01*
X296140Y-304480D01*
X298015Y-304325D01*
X299682Y-303860D01*
X300932Y-303240D01*
X301973Y-302310D01*
X302390Y-301070D01*
X301973Y-299830D01*
X300932Y-298900D01*
X299682Y-298280D01*
X298015Y-297815D01*
X296140Y-297660D01*
X294265Y-297815D01*
X292598Y-298280D01*
X291348Y-298900D01*
X290307Y-299830D01*
X289890Y-301070D01*
G01X302390Y-266780D02*
X299682Y-266470D01*
X297390Y-266005D01*
X295307Y-265385D01*
X293015Y-264610D01*
X289890Y-263370D01*
Y-269570D01*
G01Y-254070D02*
X290307Y-255310D01*
X291348Y-256240D01*
X292598Y-256860D01*
X294265Y-257325D01*
X296140Y-257480D01*
X298015Y-257325D01*
X299682Y-256860D01*
X300932Y-256240D01*
X301973Y-255310D01*
X302390Y-254070D01*
X301973Y-252830D01*
X300932Y-251900D01*
X299682Y-251280D01*
X298015Y-250815D01*
X296140Y-250660D01*
X294265Y-250815D01*
X292598Y-251280D01*
X291348Y-251900D01*
X290307Y-252830D01*
X289890Y-254070D01*
G01X302807Y-241670D02*
X302598Y-241980D01*
X302182D01*
X301973Y-241670D01*
X302182Y-241360D01*
X302598D01*
X302807Y-241670D01*
G01X291973Y-232215D02*
X290724Y-231285D01*
X290098Y-230200D01*
X289890Y-228960D01*
X290307Y-227410D01*
X291348Y-226325D01*
X292598Y-226015D01*
X293849Y-226170D01*
X294890Y-226790D01*
X296973Y-229890D01*
X298432Y-231285D01*
X300515Y-232215D01*
X302390Y-232525D01*
Y-226015D01*
G01X291973Y-219815D02*
X290724Y-218885D01*
X290098Y-217800D01*
X289890Y-216560D01*
X290307Y-215010D01*
X291348Y-213925D01*
X292598Y-213615D01*
X293849Y-213770D01*
X294890Y-214390D01*
X296973Y-217490D01*
X298432Y-218885D01*
X300515Y-219815D01*
X302390Y-220125D01*
Y-213615D01*
G01X280649Y1644448D02*
G03I-2500J0D01*
G01Y1658621D02*
G03I-2500J0D01*
G01X288523Y1648385D02*
G03I-2500J0D01*
G01X280649Y1672795D02*
G03I-2500J0D01*
G01X288523Y1662558D02*
G03I-2500J0D01*
G01X280649Y1686968D02*
G03I-2500J0D01*
G01X288523Y1676732D02*
G03I-2500J0D01*
G01X280649Y1701141D02*
G03I-2500J0D01*
G01X288523Y1690905D02*
G03I-2500J0D01*
G01X280649Y1715314D02*
G03I-2500J0D01*
G01X288523Y1705078D02*
G03I-2500J0D01*
G01X280649Y1729488D02*
G03I-2500J0D01*
G01X288523Y1719251D02*
G03I-2500J0D01*
G01Y1733425D02*
G03I-2500J0D01*
G01X300335Y1672795D02*
G03I-2500J0D01*
G01X308209Y1676732D02*
G03I-2500J0D01*
G01X300335Y1686968D02*
G03I-2500J0D01*
G01X308209Y1690905D02*
G03I-2500J0D01*
G01X300335Y1701141D02*
G03I-2500J0D01*
G01X308209Y1705078D02*
G03I-2500J0D01*
G01X300335Y1715314D02*
G03I-2500J0D01*
G01X308209Y1719251D02*
G03I-2500J0D01*
G01X300335Y1729488D02*
G03I-2500J0D01*
G01X308209Y1733425D02*
G03I-2500J0D01*
G01X314323Y-380345D02*
X313074Y-379415D01*
X312448Y-378330D01*
X312240Y-377090D01*
X312657Y-375540D01*
X313698Y-374455D01*
X314948Y-374145D01*
X316199Y-374300D01*
X317240Y-374920D01*
X319323Y-378020D01*
X320782Y-379415D01*
X322865Y-380345D01*
X324740Y-380655D01*
Y-374145D01*
G01Y-365310D02*
X322032Y-365000D01*
X319740Y-364535D01*
X317657Y-363915D01*
X315365Y-363140D01*
X312240Y-361900D01*
Y-368100D01*
G01X324740Y-352910D02*
X322032Y-352600D01*
X319740Y-352135D01*
X317657Y-351515D01*
X315365Y-350740D01*
X312240Y-349500D01*
Y-355700D01*
G01Y-340200D02*
X312657Y-341440D01*
X313698Y-342370D01*
X314948Y-342990D01*
X316615Y-343455D01*
X318490Y-343610D01*
X320365Y-343455D01*
X322032Y-342990D01*
X323282Y-342370D01*
X324323Y-341440D01*
X324740Y-340200D01*
X324323Y-338960D01*
X323282Y-338030D01*
X322032Y-337410D01*
X320365Y-336945D01*
X318490Y-336790D01*
X316615Y-336945D01*
X314948Y-337410D01*
X313698Y-338030D01*
X312657Y-338960D01*
X312240Y-340200D01*
G01X325157Y-327800D02*
X324948Y-328110D01*
X324532D01*
X324323Y-327800D01*
X324532Y-327490D01*
X324948D01*
X325157Y-327800D01*
G01X323282Y-318035D02*
X324323Y-316950D01*
X324740Y-315710D01*
X324323Y-314470D01*
X323074Y-313385D01*
X321198Y-312610D01*
X319323Y-312300D01*
X317032D01*
X315157Y-312610D01*
X313490Y-313385D01*
X312657Y-314315D01*
X312240Y-315400D01*
X312657Y-316640D01*
X313490Y-317570D01*
X314740Y-318190D01*
X316407Y-318500D01*
X317865Y-318190D01*
X319323Y-317415D01*
X320157Y-316485D01*
X320365Y-315400D01*
X319949Y-314160D01*
X318907Y-313230D01*
X317032Y-312300D01*
G01X324740Y-303000D02*
X324532Y-301915D01*
X323907Y-300675D01*
X322865Y-299900D01*
X321407Y-299590D01*
X319949Y-299900D01*
X318698Y-300830D01*
X318073Y-302225D01*
Y-303775D01*
X317657Y-304705D01*
X316615Y-305480D01*
X315157Y-305790D01*
X313698Y-305325D01*
X312657Y-304240D01*
X312240Y-303000D01*
X312657Y-301760D01*
X313698Y-300675D01*
X315157Y-300210D01*
X316615Y-300520D01*
X317657Y-301295D01*
X318073Y-302225D01*
Y-303775D01*
X318698Y-305170D01*
X319949Y-306100D01*
X321407Y-306410D01*
X322865Y-306100D01*
X323907Y-305325D01*
X324532Y-304085D01*
X324740Y-303000D01*
G01Y-268710D02*
X322032Y-268400D01*
X319740Y-267935D01*
X317657Y-267315D01*
X315365Y-266540D01*
X312240Y-265300D01*
Y-271500D01*
G01Y-256000D02*
X312657Y-257240D01*
X313698Y-258170D01*
X314948Y-258790D01*
X316615Y-259255D01*
X318490Y-259410D01*
X320365Y-259255D01*
X322032Y-258790D01*
X323282Y-258170D01*
X324323Y-257240D01*
X324740Y-256000D01*
X324323Y-254760D01*
X323282Y-253830D01*
X322032Y-253210D01*
X320365Y-252745D01*
X318490Y-252590D01*
X316615Y-252745D01*
X314948Y-253210D01*
X313698Y-253830D01*
X312657Y-254760D01*
X312240Y-256000D01*
G01X325157Y-243600D02*
X324948Y-243910D01*
X324532D01*
X324323Y-243600D01*
X324532Y-243290D01*
X324948D01*
X325157Y-243600D01*
G01X322240Y-234610D02*
X323699Y-233680D01*
X324532Y-232440D01*
X324740Y-231045D01*
X324532Y-229805D01*
X323490Y-228565D01*
X322240Y-227790D01*
X320990Y-227635D01*
X319532Y-227945D01*
X318490Y-229030D01*
X318073Y-230115D01*
Y-231510D01*
G01Y-230115D02*
X317448Y-229185D01*
X316407Y-228410D01*
X315157Y-228100D01*
X313907Y-228410D01*
X312865Y-229185D01*
X312240Y-230580D01*
X312448Y-231975D01*
X313282Y-233370D01*
G01X324740Y-218800D02*
X324532Y-217715D01*
X323907Y-216475D01*
X322865Y-215700D01*
X321407Y-215390D01*
X319949Y-215700D01*
X318698Y-216630D01*
X318073Y-218025D01*
Y-219575D01*
X317657Y-220505D01*
X316615Y-221280D01*
X315157Y-221590D01*
X313698Y-221125D01*
X312657Y-220040D01*
X312240Y-218800D01*
X312657Y-217560D01*
X313698Y-216475D01*
X315157Y-216010D01*
X316615Y-216320D01*
X317657Y-217095D01*
X318073Y-218025D01*
Y-219575D01*
X318698Y-220970D01*
X319949Y-221900D01*
X321407Y-222210D01*
X322865Y-221900D01*
X323907Y-221125D01*
X324532Y-219885D01*
X324740Y-218800D01*
G01X316083Y1672795D02*
G03I-2500J0D01*
G01X323957Y1676732D02*
G03I-2500J0D01*
G01X316083Y1686968D02*
G03I-2500J0D01*
G01X323957Y1690905D02*
G03I-2500J0D01*
G01X316083Y1701141D02*
G03I-2500J0D01*
G01X323957Y1705078D02*
G03I-2500J0D01*
G01X316083Y1715314D02*
G03I-2500J0D01*
G01X323957Y1719251D02*
G03I-2500J0D01*
G01X316083Y1729488D02*
G03I-2500J0D01*
G01X323957Y1733425D02*
G03I-2500J0D01*
G01X328600Y-620971D02*
X329200Y-620171D01*
X329900Y-619771D01*
X330700Y-619638D01*
X331700Y-619905D01*
X332400Y-620571D01*
X332600Y-621371D01*
X332500Y-622172D01*
X332100Y-622838D01*
X330100Y-624171D01*
X329200Y-625105D01*
X328600Y-626438D01*
X328400Y-627638D01*
X332600D01*
G01X338500Y-619638D02*
X337700Y-619905D01*
X337100Y-620571D01*
X336700Y-621371D01*
X336400Y-622438D01*
X336300Y-623638D01*
X336400Y-624838D01*
X336700Y-625905D01*
X337100Y-626705D01*
X337700Y-627371D01*
X338500Y-627638D01*
X339300Y-627371D01*
X339900Y-626705D01*
X340300Y-625905D01*
X340600Y-624838D01*
X340700Y-623638D01*
X340600Y-622438D01*
X340300Y-621371D01*
X339900Y-620571D01*
X339300Y-619905D01*
X338500Y-619638D01*
G01X344600Y-620971D02*
X345200Y-620171D01*
X345900Y-619771D01*
X346700Y-619638D01*
X347700Y-619905D01*
X348400Y-620571D01*
X348600Y-621371D01*
X348500Y-622172D01*
X348100Y-622838D01*
X346100Y-624171D01*
X345200Y-625105D01*
X344600Y-626438D01*
X344400Y-627638D01*
X348600D01*
G01X352300Y-626038D02*
X352900Y-626971D01*
X353700Y-627505D01*
X354600Y-627638D01*
X355400Y-627505D01*
X356200Y-626838D01*
X356700Y-626038D01*
X356800Y-625238D01*
X356600Y-624305D01*
X355900Y-623638D01*
X355200Y-623371D01*
X354300D01*
G01X355200D02*
X355800Y-622971D01*
X356300Y-622305D01*
X356500Y-621505D01*
X356300Y-620705D01*
X355800Y-620038D01*
X354900Y-619638D01*
X354000Y-619771D01*
X353100Y-620305D01*
G01X360700Y-627905D02*
X364300Y-619638D01*
G01X370500D02*
X369700Y-619905D01*
X369100Y-620571D01*
X368700Y-621371D01*
X368400Y-622438D01*
X368300Y-623638D01*
X368400Y-624838D01*
X368700Y-625905D01*
X369100Y-626705D01*
X369700Y-627371D01*
X370500Y-627638D01*
X371300Y-627371D01*
X371900Y-626705D01*
X372300Y-625905D01*
X372600Y-624838D01*
X372700Y-623638D01*
X372600Y-622438D01*
X372300Y-621371D01*
X371900Y-620571D01*
X371300Y-619905D01*
X370500Y-619638D01*
G01X379700Y-627638D02*
Y-619638D01*
X376000Y-625371D01*
X381000D01*
G01X384700Y-627905D02*
X388300Y-619638D01*
G01X394500Y-627638D02*
Y-619638D01*
X393300Y-621238D01*
G01Y-627638D02*
X395700D01*
G01X402300D02*
X402500Y-625905D01*
X402800Y-624438D01*
X403200Y-623105D01*
X403700Y-621638D01*
X404500Y-619638D01*
X400500D01*
G01X328300Y-602638D02*
Y-594638D01*
X330300D01*
X331100Y-595038D01*
X331700Y-595571D01*
X332200Y-596371D01*
X332600Y-597305D01*
X332700Y-598638D01*
X332600Y-599971D01*
X332200Y-600905D01*
X331700Y-601705D01*
X331100Y-602238D01*
X330300Y-602638D01*
X328300D01*
G01X336000D02*
X338500Y-594638D01*
X341000Y-602638D01*
G01X340100Y-599838D02*
X336900D01*
G01X344600Y-602638D02*
Y-594638D01*
X348400D01*
G01X347000Y-598505D02*
X344600D01*
G01X354500Y-594638D02*
X353700Y-594905D01*
X353100Y-595571D01*
X352700Y-596371D01*
X352400Y-597438D01*
X352300Y-598638D01*
X352400Y-599838D01*
X352700Y-600905D01*
X353100Y-601705D01*
X353700Y-602371D01*
X354500Y-602638D01*
X355300Y-602371D01*
X355900Y-601705D01*
X356300Y-600905D01*
X356600Y-599838D01*
X356700Y-598638D01*
X356600Y-597438D01*
X356300Y-596371D01*
X355900Y-595571D01*
X355300Y-594905D01*
X354500Y-594638D01*
G01X362500D02*
Y-602638D01*
G01X360200Y-594638D02*
X364800D01*
G01X367900Y-602638D02*
Y-594638D01*
X370500Y-601305D01*
X373100Y-594638D01*
Y-602638D01*
G01X379300Y-598371D02*
X379700Y-597971D01*
X380000Y-597305D01*
X380200Y-596371D01*
X380000Y-595571D01*
X379600Y-595038D01*
X378900Y-594638D01*
X376200D01*
Y-602638D01*
X379500D01*
X380200Y-602105D01*
X380600Y-601305D01*
X380800Y-600371D01*
X380600Y-599438D01*
X380000Y-598638D01*
X379300Y-598371D01*
X376200D01*
G01X384300Y-601038D02*
X384900Y-601971D01*
X385700Y-602505D01*
X386600Y-602638D01*
X387400Y-602505D01*
X388200Y-601838D01*
X388700Y-601038D01*
X388800Y-600238D01*
X388600Y-599305D01*
X387900Y-598638D01*
X387200Y-598371D01*
X386300D01*
G01X387200D02*
X387800Y-597971D01*
X388300Y-597305D01*
X388500Y-596505D01*
X388300Y-595705D01*
X387800Y-595038D01*
X386900Y-594638D01*
X386000Y-594771D01*
X385100Y-595305D01*
G01X393300Y-594638D02*
X395700D01*
G01X394500D02*
Y-602638D01*
G01X393300D02*
X395700D01*
G01X404700Y-595305D02*
X404100Y-594905D01*
X403400Y-594638D01*
X402600D01*
X401700Y-595038D01*
X401000Y-595705D01*
X400500Y-596505D01*
X400100Y-597838D01*
X400000Y-599038D01*
X400200Y-600238D01*
X400500Y-601038D01*
X401100Y-601838D01*
X401800Y-602371D01*
X402500Y-602638D01*
X403200D01*
X403900Y-602371D01*
X404500Y-601971D01*
X405000Y-601438D01*
G01X410500Y-594638D02*
X409700Y-594905D01*
X409100Y-595571D01*
X408700Y-596371D01*
X408400Y-597438D01*
X408300Y-598638D01*
X408400Y-599838D01*
X408700Y-600905D01*
X409100Y-601705D01*
X409700Y-602371D01*
X410500Y-602638D01*
X411300Y-602371D01*
X411900Y-601705D01*
X412300Y-600905D01*
X412600Y-599838D01*
X412700Y-598638D01*
X412600Y-597438D01*
X412300Y-596371D01*
X411900Y-595571D01*
X411300Y-594905D01*
X410500Y-594638D01*
G01X331831Y1672795D02*
G03I-2500J0D01*
G01X339705Y1676732D02*
G03I-2500J0D01*
G01X331831Y1686968D02*
G03I-2500J0D01*
G01X339705Y1690905D02*
G03I-2500J0D01*
G01X331831Y1701141D02*
G03I-2500J0D01*
G01X339705Y1705078D02*
G03I-2500J0D01*
G01X331831Y1715314D02*
G03I-2500J0D01*
G01X339705Y1719251D02*
G03I-2500J0D01*
G01X331831Y1729488D02*
G03I-2500J0D01*
G01X339705Y1733425D02*
G03I-2500J0D01*
G01X346100Y-577638D02*
Y-569638D01*
X349900D01*
G01X348500Y-573505D02*
X346100D01*
G01X356000Y-569638D02*
X355200Y-569905D01*
X354600Y-570571D01*
X354200Y-571371D01*
X353900Y-572438D01*
X353800Y-573638D01*
X353900Y-574838D01*
X354200Y-575905D01*
X354600Y-576705D01*
X355200Y-577371D01*
X356000Y-577638D01*
X356800Y-577371D01*
X357400Y-576705D01*
X357800Y-575905D01*
X358100Y-574838D01*
X358200Y-573638D01*
X358100Y-572438D01*
X357800Y-571371D01*
X357400Y-570571D01*
X356800Y-569905D01*
X356000Y-569638D01*
G01X364000D02*
Y-577638D01*
G01X361700Y-569638D02*
X366300D01*
G01X372600Y-573638D02*
X374600D01*
Y-576038D01*
X374000Y-576838D01*
X373300Y-577371D01*
X372300Y-577638D01*
X371300Y-577371D01*
X370600Y-576838D01*
X370000Y-576038D01*
X369600Y-575105D01*
X369400Y-574038D01*
Y-573105D01*
X369600Y-572305D01*
X370000Y-571371D01*
X370600Y-570571D01*
X371200Y-570038D01*
X372000Y-569638D01*
X372700D01*
X373500Y-569905D01*
X374100Y-570438D01*
G01X377000Y-580305D02*
X383000D01*
G01X385400Y-577638D02*
Y-569638D01*
X388000Y-576305D01*
X390600Y-569638D01*
Y-577638D01*
G01X396800Y-573371D02*
X397200Y-572971D01*
X397500Y-572305D01*
X397700Y-571371D01*
X397500Y-570571D01*
X397100Y-570038D01*
X396400Y-569638D01*
X393700D01*
Y-577638D01*
X397000D01*
X397700Y-577105D01*
X398100Y-576305D01*
X398300Y-575371D01*
X398100Y-574438D01*
X397500Y-573638D01*
X396800Y-573371D01*
X393700D01*
G01X345360Y-381190D02*
X346819Y-380260D01*
X347652Y-379020D01*
X347860Y-377625D01*
X347652Y-376385D01*
X346610Y-375145D01*
X345360Y-374370D01*
X344110Y-374215D01*
X342652Y-374525D01*
X341610Y-375610D01*
X341193Y-376695D01*
Y-378090D01*
G01Y-376695D02*
X340568Y-375765D01*
X339527Y-374990D01*
X338277Y-374680D01*
X337027Y-374990D01*
X335985Y-375765D01*
X335360Y-377160D01*
X335568Y-378555D01*
X336402Y-379950D01*
G01X337443Y-368325D02*
X336194Y-367395D01*
X335568Y-366310D01*
X335360Y-365070D01*
X335777Y-363520D01*
X336818Y-362435D01*
X338068Y-362125D01*
X339319Y-362280D01*
X340360Y-362900D01*
X342443Y-366000D01*
X343902Y-367395D01*
X345985Y-368325D01*
X347860Y-368635D01*
Y-362125D01*
G01X335360Y-352980D02*
X335777Y-354220D01*
X336818Y-355150D01*
X338068Y-355770D01*
X339735Y-356235D01*
X341610Y-356390D01*
X343485Y-356235D01*
X345152Y-355770D01*
X346402Y-355150D01*
X347443Y-354220D01*
X347860Y-352980D01*
X347443Y-351740D01*
X346402Y-350810D01*
X345152Y-350190D01*
X343485Y-349725D01*
X341610Y-349570D01*
X339735Y-349725D01*
X338068Y-350190D01*
X336818Y-350810D01*
X335777Y-351740D01*
X335360Y-352980D01*
G01X347860Y-340580D02*
X335360D01*
X337860Y-342440D01*
G01X347860D02*
Y-338720D01*
G01X348277Y-328180D02*
X348068Y-328490D01*
X347652D01*
X347443Y-328180D01*
X347652Y-327870D01*
X348068D01*
X348277Y-328180D01*
G01X347860Y-315780D02*
X347652Y-314695D01*
X347027Y-313455D01*
X345985Y-312680D01*
X344527Y-312370D01*
X343069Y-312680D01*
X341818Y-313610D01*
X341193Y-315005D01*
Y-316555D01*
X340777Y-317485D01*
X339735Y-318260D01*
X338277Y-318570D01*
X336818Y-318105D01*
X335777Y-317020D01*
X335360Y-315780D01*
X335777Y-314540D01*
X336818Y-313455D01*
X338277Y-312990D01*
X339735Y-313300D01*
X340777Y-314075D01*
X341193Y-315005D01*
Y-316555D01*
X341818Y-317950D01*
X343069Y-318880D01*
X344527Y-319190D01*
X345985Y-318880D01*
X347027Y-318105D01*
X347652Y-316865D01*
X347860Y-315780D01*
G01X346402Y-306015D02*
X347443Y-304930D01*
X347860Y-303690D01*
X347443Y-302450D01*
X346194Y-301365D01*
X344318Y-300590D01*
X342443Y-300280D01*
X340152D01*
X338277Y-300590D01*
X336610Y-301365D01*
X335777Y-302295D01*
X335360Y-303380D01*
X335777Y-304620D01*
X336610Y-305550D01*
X337860Y-306170D01*
X339527Y-306480D01*
X340985Y-306170D01*
X342443Y-305395D01*
X343277Y-304465D01*
X343485Y-303380D01*
X343069Y-302140D01*
X342027Y-301210D01*
X340152Y-300280D01*
G01X347860Y-268780D02*
X347652Y-267695D01*
X347027Y-266455D01*
X345985Y-265680D01*
X344527Y-265370D01*
X343069Y-265680D01*
X341818Y-266610D01*
X341193Y-268005D01*
Y-269555D01*
X340777Y-270485D01*
X339735Y-271260D01*
X338277Y-271570D01*
X336818Y-271105D01*
X335777Y-270020D01*
X335360Y-268780D01*
X335777Y-267540D01*
X336818Y-266455D01*
X338277Y-265990D01*
X339735Y-266300D01*
X340777Y-267075D01*
X341193Y-268005D01*
Y-269555D01*
X341818Y-270950D01*
X343069Y-271880D01*
X344527Y-272190D01*
X345985Y-271880D01*
X347027Y-271105D01*
X347652Y-269865D01*
X347860Y-268780D01*
G01Y-256380D02*
X335360D01*
X337860Y-258240D01*
G01X347860D02*
Y-254520D01*
G01X348277Y-243980D02*
X348068Y-244290D01*
X347652D01*
X347443Y-243980D01*
X347652Y-243670D01*
X348068D01*
X348277Y-243980D01*
G01X345360Y-234990D02*
X346819Y-234060D01*
X347652Y-232820D01*
X347860Y-231425D01*
X347652Y-230185D01*
X346610Y-228945D01*
X345360Y-228170D01*
X344110Y-228015D01*
X342652Y-228325D01*
X341610Y-229410D01*
X341193Y-230495D01*
Y-231890D01*
G01Y-230495D02*
X340568Y-229565D01*
X339527Y-228790D01*
X338277Y-228480D01*
X337027Y-228790D01*
X335985Y-229565D01*
X335360Y-230960D01*
X335568Y-232355D01*
X336402Y-233750D01*
G01X345360Y-222590D02*
X346819Y-221660D01*
X347652Y-220420D01*
X347860Y-219025D01*
X347652Y-217785D01*
X346610Y-216545D01*
X345360Y-215770D01*
X344110Y-215615D01*
X342652Y-215925D01*
X341610Y-217010D01*
X341193Y-218095D01*
Y-219490D01*
G01Y-218095D02*
X340568Y-217165D01*
X339527Y-216390D01*
X338277Y-216080D01*
X337027Y-216390D01*
X335985Y-217165D01*
X335360Y-218560D01*
X335568Y-219955D01*
X336402Y-221350D01*
G01X347579Y1672795D02*
G03I-2500J0D01*
G01Y1686968D02*
G03I-2500J0D01*
G01Y1701141D02*
G03I-2500J0D01*
G01Y1715314D02*
G03I-2500J0D01*
G01Y1729488D02*
G03I-2500J0D01*
G01X372187Y-380420D02*
X373646Y-379490D01*
X374479Y-378250D01*
X374687Y-376855D01*
X374479Y-375615D01*
X373437Y-374375D01*
X372187Y-373600D01*
X370937Y-373445D01*
X369479Y-373755D01*
X368437Y-374840D01*
X368020Y-375925D01*
Y-377320D01*
G01Y-375925D02*
X367395Y-374995D01*
X366354Y-374220D01*
X365104Y-373910D01*
X363854Y-374220D01*
X362812Y-374995D01*
X362187Y-376390D01*
X362395Y-377785D01*
X363229Y-379180D01*
G01X369479Y-367555D02*
X368020Y-366470D01*
X367187Y-365540D01*
X366770Y-364300D01*
X367187Y-363215D01*
X368020Y-362440D01*
X369270Y-361820D01*
X370729Y-361665D01*
X371979Y-361820D01*
X373229Y-362440D01*
X374270Y-363370D01*
X374687Y-364455D01*
X374270Y-365695D01*
X373021Y-366780D01*
X371145Y-367400D01*
X369062Y-367555D01*
X366354Y-367245D01*
X364895Y-366780D01*
X363437Y-366005D01*
X362395Y-364920D01*
X362187Y-363835D01*
X362604Y-362750D01*
X363645Y-361975D01*
G01X374687Y-352210D02*
X374479Y-351125D01*
X373854Y-349885D01*
X372812Y-349110D01*
X371354Y-348800D01*
X369896Y-349110D01*
X368645Y-350040D01*
X368020Y-351435D01*
Y-352985D01*
X367604Y-353915D01*
X366562Y-354690D01*
X365104Y-355000D01*
X363645Y-354535D01*
X362604Y-353450D01*
X362187Y-352210D01*
X362604Y-350970D01*
X363645Y-349885D01*
X365104Y-349420D01*
X366562Y-349730D01*
X367604Y-350505D01*
X368020Y-351435D01*
Y-352985D01*
X368645Y-354380D01*
X369896Y-355310D01*
X371354Y-355620D01*
X372812Y-355310D01*
X373854Y-354535D01*
X374479Y-353295D01*
X374687Y-352210D01*
G01Y-337950D02*
X362187D01*
X371145Y-343685D01*
Y-335935D01*
G01X375104Y-327410D02*
X374895Y-327720D01*
X374479D01*
X374270Y-327410D01*
X374479Y-327100D01*
X374895D01*
X375104Y-327410D01*
G01X372187Y-318420D02*
X373646Y-317490D01*
X374479Y-316250D01*
X374687Y-314855D01*
X374479Y-313615D01*
X373437Y-312375D01*
X372187Y-311600D01*
X370937Y-311445D01*
X369479Y-311755D01*
X368437Y-312840D01*
X368020Y-313925D01*
Y-315320D01*
G01Y-313925D02*
X367395Y-312995D01*
X366354Y-312220D01*
X365104Y-311910D01*
X363854Y-312220D01*
X362812Y-312995D01*
X362187Y-314390D01*
X362395Y-315785D01*
X363229Y-317180D01*
G01X374687Y-302920D02*
X371979Y-302610D01*
X369687Y-302145D01*
X367604Y-301525D01*
X365312Y-300750D01*
X362187Y-299510D01*
Y-305710D01*
G01X373229Y-270645D02*
X374270Y-269560D01*
X374687Y-268320D01*
X374270Y-267080D01*
X373021Y-265995D01*
X371145Y-265220D01*
X369270Y-264910D01*
X366979D01*
X365104Y-265220D01*
X363437Y-265995D01*
X362604Y-266925D01*
X362187Y-268010D01*
X362604Y-269250D01*
X363437Y-270180D01*
X364687Y-270800D01*
X366354Y-271110D01*
X367812Y-270800D01*
X369270Y-270025D01*
X370104Y-269095D01*
X370312Y-268010D01*
X369896Y-266770D01*
X368854Y-265840D01*
X366979Y-264910D01*
G01X372187Y-259020D02*
X373646Y-258090D01*
X374479Y-256850D01*
X374687Y-255455D01*
X374479Y-254215D01*
X373437Y-252975D01*
X372187Y-252200D01*
X370937Y-252045D01*
X369479Y-252355D01*
X368437Y-253440D01*
X368020Y-254525D01*
Y-255920D01*
G01Y-254525D02*
X367395Y-253595D01*
X366354Y-252820D01*
X365104Y-252510D01*
X363854Y-252820D01*
X362812Y-253595D01*
X362187Y-254990D01*
X362395Y-256385D01*
X363229Y-257780D01*
G01X375104Y-243210D02*
X374895Y-243520D01*
X374479D01*
X374270Y-243210D01*
X374479Y-242900D01*
X374895D01*
X375104Y-243210D01*
G01X372812Y-234220D02*
X373854Y-233290D01*
X374479Y-232205D01*
X374687Y-230810D01*
X374270Y-229415D01*
X373437Y-228330D01*
X371979Y-227555D01*
X370312Y-227400D01*
X368645Y-227710D01*
X367604Y-228485D01*
X366770Y-229570D01*
X366562Y-230655D01*
X366770Y-231740D01*
X367604Y-233135D01*
X362187Y-232670D01*
Y-228485D01*
G01X374687Y-218410D02*
X374479Y-217325D01*
X373854Y-216085D01*
X372812Y-215310D01*
X371354Y-215000D01*
X369896Y-215310D01*
X368645Y-216240D01*
X368020Y-217635D01*
Y-219185D01*
X367604Y-220115D01*
X366562Y-220890D01*
X365104Y-221200D01*
X363645Y-220735D01*
X362604Y-219650D01*
X362187Y-218410D01*
X362604Y-217170D01*
X363645Y-216085D01*
X365104Y-215620D01*
X366562Y-215930D01*
X367604Y-216705D01*
X368020Y-217635D01*
Y-219185D01*
X368645Y-220580D01*
X369896Y-221510D01*
X371354Y-221820D01*
X372812Y-221510D01*
X373854Y-220735D01*
X374479Y-219495D01*
X374687Y-218410D01*
G01X355453Y1676732D02*
G03I-2500J0D01*
G01Y1690905D02*
G03I-2500J0D01*
G01Y1705078D02*
G03I-2500J0D01*
G01Y1719251D02*
G03I-2500J0D01*
G01Y1733425D02*
G03I-2500J0D01*
G01X397000Y-368060D02*
X398459Y-367130D01*
X399292Y-365890D01*
X399500Y-364495D01*
X399292Y-363255D01*
X398250Y-362015D01*
X397000Y-361240D01*
X395750Y-361085D01*
X394292Y-361395D01*
X393250Y-362480D01*
X392833Y-363565D01*
Y-364960D01*
G01Y-363565D02*
X392208Y-362635D01*
X391167Y-361860D01*
X389917Y-361550D01*
X388667Y-361860D01*
X387625Y-362635D01*
X387000Y-364030D01*
X387208Y-365425D01*
X388042Y-366820D01*
G01X399500Y-352560D02*
X396792Y-352250D01*
X394500Y-351785D01*
X392417Y-351165D01*
X390125Y-350390D01*
X387000Y-349150D01*
Y-355350D01*
G01X397000Y-343260D02*
X398459Y-342330D01*
X399292Y-341090D01*
X399500Y-339695D01*
X399292Y-338455D01*
X398250Y-337215D01*
X397000Y-336440D01*
X395750Y-336285D01*
X394292Y-336595D01*
X393250Y-337680D01*
X392833Y-338765D01*
Y-340160D01*
G01Y-338765D02*
X392208Y-337835D01*
X391167Y-337060D01*
X389917Y-336750D01*
X388667Y-337060D01*
X387625Y-337835D01*
X387000Y-339230D01*
X387208Y-340625D01*
X388042Y-342020D01*
G01X394292Y-330395D02*
X392833Y-329310D01*
X392000Y-328380D01*
X391583Y-327140D01*
X392000Y-326055D01*
X392833Y-325280D01*
X394083Y-324660D01*
X395542Y-324505D01*
X396792Y-324660D01*
X398042Y-325280D01*
X399083Y-326210D01*
X399500Y-327295D01*
X399083Y-328535D01*
X397834Y-329620D01*
X395958Y-330240D01*
X393875Y-330395D01*
X391167Y-330085D01*
X389708Y-329620D01*
X388250Y-328845D01*
X387208Y-327760D01*
X387000Y-326675D01*
X387417Y-325590D01*
X388458Y-324815D01*
G01X399917Y-315050D02*
X399708Y-315360D01*
X399292D01*
X399083Y-315050D01*
X399292Y-314740D01*
X399708D01*
X399917Y-315050D01*
G01X389083Y-305595D02*
X387834Y-304665D01*
X387208Y-303580D01*
X387000Y-302340D01*
X387417Y-300790D01*
X388458Y-299705D01*
X389708Y-299395D01*
X390959Y-299550D01*
X392000Y-300170D01*
X394083Y-303270D01*
X395542Y-304665D01*
X397625Y-305595D01*
X399500Y-305905D01*
Y-299395D01*
G01X389083Y-293195D02*
X387834Y-292265D01*
X387208Y-291180D01*
X387000Y-289940D01*
X387417Y-288390D01*
X388458Y-287305D01*
X389708Y-286995D01*
X390959Y-287150D01*
X392000Y-287770D01*
X394083Y-290870D01*
X395542Y-292265D01*
X397625Y-293195D01*
X399500Y-293505D01*
Y-286995D01*
G01X398042Y-258285D02*
X399083Y-257200D01*
X399500Y-255960D01*
X399083Y-254720D01*
X397834Y-253635D01*
X395958Y-252860D01*
X394083Y-252550D01*
X391792D01*
X389917Y-252860D01*
X388250Y-253635D01*
X387417Y-254565D01*
X387000Y-255650D01*
X387417Y-256890D01*
X388250Y-257820D01*
X389500Y-258440D01*
X391167Y-258750D01*
X392625Y-258440D01*
X394083Y-257665D01*
X394917Y-256735D01*
X395125Y-255650D01*
X394709Y-254410D01*
X393667Y-253480D01*
X391792Y-252550D01*
G01X399500Y-241390D02*
X387000D01*
X395958Y-247125D01*
Y-239375D01*
G01X399917Y-230850D02*
X399708Y-231160D01*
X399292D01*
X399083Y-230850D01*
X399292Y-230540D01*
X399708D01*
X399917Y-230850D01*
G01X398042Y-221085D02*
X399083Y-220000D01*
X399500Y-218760D01*
X399083Y-217520D01*
X397834Y-216435D01*
X395958Y-215660D01*
X394083Y-215350D01*
X391792D01*
X389917Y-215660D01*
X388250Y-216435D01*
X387417Y-217365D01*
X387000Y-218450D01*
X387417Y-219690D01*
X388250Y-220620D01*
X389500Y-221240D01*
X391167Y-221550D01*
X392625Y-221240D01*
X394083Y-220465D01*
X394917Y-219535D01*
X395125Y-218450D01*
X394709Y-217210D01*
X393667Y-216280D01*
X391792Y-215350D01*
G01X388115Y1928475D02*
X380615D01*
X386865Y1930902D01*
X380615Y1933329D01*
X388115D01*
G01Y1936069D02*
X380615Y1938402D01*
X388115Y1940735D01*
G01X385490Y1939895D02*
Y1936909D01*
G01X388115Y1944035D02*
X380615D01*
Y1946369D01*
X380990Y1947115D01*
X381490Y1947582D01*
X382490Y1947769D01*
X383490Y1947582D01*
X384115Y1947022D01*
X384490Y1946369D01*
Y1944035D01*
G01Y1946369D02*
X388115Y1947769D01*
G01Y1951349D02*
X380615D01*
G01Y1954895D02*
X385240Y1951349D01*
G01X388115Y1955455D02*
X383115Y1952935D01*
G01X388365Y1960902D02*
X388240Y1960715D01*
X387990D01*
X387865Y1960902D01*
X387990Y1961089D01*
X388240D01*
X388365Y1960902D01*
G01X384990D02*
X384865Y1960715D01*
X384615D01*
X384490Y1960902D01*
X384615Y1961089D01*
X384865D01*
X384990Y1960902D01*
G01X380615Y1968402D02*
X388115D01*
G01X380615Y1966255D02*
Y1970549D01*
G01Y1974782D02*
Y1977022D01*
G01Y1975902D02*
X388115D01*
G01Y1974782D02*
Y1977022D01*
G01Y1981255D02*
X380615D01*
X388115Y1985549D01*
X380615D01*
G01Y1996535D02*
X388115D01*
Y2000269D01*
G01Y2007769D02*
Y2004035D01*
X380615D01*
Y2007769D01*
G01X384240Y2006275D02*
Y2004035D01*
G01X388115Y2011069D02*
X380615Y2013402D01*
X388115Y2015735D01*
G01X385490Y2014895D02*
Y2011909D01*
G01X388115Y2018849D02*
X380615D01*
Y2020715D01*
X380990Y2021462D01*
X381490Y2022022D01*
X382240Y2022489D01*
X383115Y2022862D01*
X384365Y2022955D01*
X385615Y2022862D01*
X386490Y2022489D01*
X387240Y2022022D01*
X387740Y2021462D01*
X388115Y2020715D01*
Y2018849D01*
G01X388365Y2028402D02*
X388240Y2028215D01*
X387990D01*
X387865Y2028402D01*
X387990Y2028589D01*
X388240D01*
X388365Y2028402D01*
G01X384990D02*
X384865Y2028215D01*
X384615D01*
X384490Y2028402D01*
X384615Y2028589D01*
X384865D01*
X384990Y2028402D01*
G01X388115Y2034035D02*
X380615D01*
Y2036369D01*
X380990Y2037115D01*
X381490Y2037582D01*
X382490Y2037769D01*
X383490Y2037582D01*
X384115Y2037022D01*
X384490Y2036369D01*
Y2034035D01*
G01Y2036369D02*
X388115Y2037769D01*
G01Y2045269D02*
Y2041535D01*
X380615D01*
Y2045269D01*
G01X384240Y2043775D02*
Y2041535D01*
G01X381240Y2052955D02*
X380865Y2052395D01*
X380615Y2051742D01*
Y2050995D01*
X380990Y2050155D01*
X381615Y2049502D01*
X382365Y2049035D01*
X383615Y2048662D01*
X384740Y2048569D01*
X385865Y2048755D01*
X386615Y2049035D01*
X387365Y2049595D01*
X387865Y2050249D01*
X388115Y2050902D01*
Y2051555D01*
X387865Y2052209D01*
X387490Y2052769D01*
X386990Y2053235D01*
G01X388115Y2058402D02*
X387990Y2057655D01*
X387490Y2057002D01*
X386740Y2056442D01*
X385865Y2056069D01*
X384865Y2055882D01*
X383865D01*
X382865Y2056069D01*
X381990Y2056442D01*
X381240Y2057002D01*
X380740Y2057655D01*
X380615Y2058402D01*
X380740Y2059149D01*
X381240Y2059802D01*
X381990Y2060362D01*
X382865Y2060735D01*
X383865Y2060922D01*
X384865D01*
X385865Y2060735D01*
X386740Y2060362D01*
X387490Y2059802D01*
X387990Y2059149D01*
X388115Y2058402D01*
G01Y2063475D02*
X380615D01*
X386865Y2065902D01*
X380615Y2068329D01*
X388115D01*
G01Y2070975D02*
X380615D01*
X386865Y2073402D01*
X380615Y2075829D01*
X388115D01*
G01Y2082769D02*
Y2079035D01*
X380615D01*
Y2082769D01*
G01X384240Y2081275D02*
Y2079035D01*
G01X388115Y2086255D02*
X380615D01*
X388115Y2090549D01*
X380615D01*
G01X388115Y2093849D02*
X380615D01*
Y2095715D01*
X380990Y2096462D01*
X381490Y2097022D01*
X382240Y2097489D01*
X383115Y2097862D01*
X384365Y2097955D01*
X385615Y2097862D01*
X386490Y2097489D01*
X387240Y2097022D01*
X387740Y2096462D01*
X388115Y2095715D01*
Y2093849D01*
G01Y2105269D02*
Y2101535D01*
X380615D01*
Y2105269D01*
G01X384240Y2103775D02*
Y2101535D01*
G01X388115Y2108849D02*
X380615D01*
Y2110715D01*
X380990Y2111462D01*
X381490Y2112022D01*
X382240Y2112489D01*
X383115Y2112862D01*
X384365Y2112955D01*
X385615Y2112862D01*
X386490Y2112489D01*
X387240Y2112022D01*
X387740Y2111462D01*
X388115Y2110715D01*
Y2108849D01*
G01Y2123849D02*
X380615D01*
Y2125715D01*
X380990Y2126462D01*
X381490Y2127022D01*
X382240Y2127489D01*
X383115Y2127862D01*
X384365Y2127955D01*
X385615Y2127862D01*
X386490Y2127489D01*
X387240Y2127022D01*
X387740Y2126462D01*
X388115Y2125715D01*
Y2123849D01*
G01Y2131535D02*
X380615D01*
Y2133869D01*
X380990Y2134615D01*
X381490Y2135082D01*
X382490Y2135269D01*
X383490Y2135082D01*
X384115Y2134522D01*
X384490Y2133869D01*
Y2131535D01*
G01Y2133869D02*
X388115Y2135269D01*
G01X380615Y2139782D02*
Y2142022D01*
G01Y2140902D02*
X388115D01*
G01Y2139782D02*
Y2142022D01*
G01X380615Y2146535D02*
X388115D01*
Y2150269D01*
G01X380615Y2154035D02*
X388115D01*
Y2157769D01*
G01X387115Y2168942D02*
X387740Y2169689D01*
X388115Y2170529D01*
Y2171275D01*
X387740Y2172022D01*
X387115Y2172582D01*
X386240Y2172862D01*
X385365Y2172675D01*
X384615Y2172209D01*
X384115Y2171369D01*
X383865Y2170249D01*
X383365Y2169595D01*
X382490Y2169315D01*
X381615Y2169502D01*
X380990Y2169969D01*
X380615Y2170622D01*
Y2171275D01*
X380865Y2171929D01*
X381490Y2172489D01*
G01X380615Y2177282D02*
Y2179522D01*
G01Y2178402D02*
X388115D01*
G01Y2177282D02*
Y2179522D01*
G01X380615Y2184129D02*
Y2187675D01*
X388115Y2184129D01*
Y2187675D01*
G01Y2195269D02*
Y2191535D01*
X380615D01*
Y2195269D01*
G01X384240Y2193775D02*
Y2191535D01*
G01X388115Y2206629D02*
X380615D01*
Y2210175D01*
G01X384240Y2208869D02*
Y2206629D01*
G01X388115Y2215902D02*
X387990Y2215155D01*
X387490Y2214502D01*
X386740Y2213942D01*
X385865Y2213569D01*
X384865Y2213382D01*
X383865D01*
X382865Y2213569D01*
X381990Y2213942D01*
X381240Y2214502D01*
X380740Y2215155D01*
X380615Y2215902D01*
X380740Y2216649D01*
X381240Y2217302D01*
X381990Y2217862D01*
X382865Y2218235D01*
X383865Y2218422D01*
X384865D01*
X385865Y2218235D01*
X386740Y2217862D01*
X387490Y2217302D01*
X387990Y2216649D01*
X388115Y2215902D01*
G01Y2221535D02*
X380615D01*
Y2223869D01*
X380990Y2224615D01*
X381490Y2225082D01*
X382490Y2225269D01*
X383490Y2225082D01*
X384115Y2224522D01*
X384490Y2223869D01*
Y2221535D01*
G01Y2223869D02*
X388115Y2225269D01*
G01X380615Y2238402D02*
X380865Y2237655D01*
X381490Y2237095D01*
X382240Y2236722D01*
X383240Y2236442D01*
X384365Y2236349D01*
X385490Y2236442D01*
X386490Y2236722D01*
X387240Y2237095D01*
X387865Y2237655D01*
X388115Y2238402D01*
X387865Y2239149D01*
X387240Y2239709D01*
X386490Y2240082D01*
X385490Y2240362D01*
X384365Y2240455D01*
X383240Y2240362D01*
X382240Y2240082D01*
X381490Y2239709D01*
X380865Y2239149D01*
X380615Y2238402D01*
G01X388365Y2245902D02*
X388240Y2245715D01*
X387990D01*
X387865Y2245902D01*
X387990Y2246089D01*
X388240D01*
X388365Y2245902D01*
G01X386990Y2251349D02*
X387615Y2251909D01*
X387990Y2252562D01*
X388115Y2253402D01*
X387865Y2254242D01*
X387365Y2254895D01*
X386490Y2255362D01*
X385490Y2255455D01*
X384490Y2255269D01*
X383865Y2254802D01*
X383365Y2254149D01*
X383240Y2253495D01*
X383365Y2252842D01*
X383865Y2252002D01*
X380615Y2252282D01*
Y2254802D01*
G01X388115Y2258475D02*
X380615D01*
X386865Y2260902D01*
X380615Y2263329D01*
X388115D01*
G01Y2265975D02*
X380615D01*
X386865Y2268402D01*
X380615Y2270829D01*
X388115D01*
G01Y2281629D02*
X380615D01*
Y2285175D01*
G01X384240Y2283869D02*
Y2281629D01*
G01X380615Y2289782D02*
Y2292022D01*
G01Y2290902D02*
X388115D01*
G01Y2289782D02*
Y2292022D01*
G01Y2296255D02*
X380615D01*
X388115Y2300549D01*
X380615D01*
G01Y2304782D02*
Y2307022D01*
G01Y2305902D02*
X388115D01*
G01Y2304782D02*
Y2307022D01*
G01X387115Y2311442D02*
X387740Y2312189D01*
X388115Y2313029D01*
Y2313775D01*
X387740Y2314522D01*
X387115Y2315082D01*
X386240Y2315362D01*
X385365Y2315175D01*
X384615Y2314709D01*
X384115Y2313869D01*
X383865Y2312749D01*
X383365Y2312095D01*
X382490Y2311815D01*
X381615Y2312002D01*
X380990Y2312469D01*
X380615Y2313122D01*
Y2313775D01*
X380865Y2314429D01*
X381490Y2314989D01*
G01X388115Y2318942D02*
X380615D01*
G01Y2322862D02*
X388115D01*
G01X384365D02*
Y2318942D01*
G01X388115Y2330269D02*
Y2326535D01*
X380615D01*
Y2330269D01*
G01X384240Y2328775D02*
Y2326535D01*
G01X388115Y2333849D02*
X380615D01*
Y2335715D01*
X380990Y2336462D01*
X381490Y2337022D01*
X382240Y2337489D01*
X383115Y2337862D01*
X384365Y2337955D01*
X385615Y2337862D01*
X386490Y2337489D01*
X387240Y2337022D01*
X387740Y2336462D01*
X388115Y2335715D01*
Y2333849D01*
G01Y2349035D02*
X380615D01*
Y2351275D01*
X380990Y2352022D01*
X381865Y2352582D01*
X382865Y2352769D01*
X383865Y2352582D01*
X384615Y2352115D01*
X384990Y2351275D01*
Y2349035D01*
G01X380615Y2358402D02*
X388115D01*
G01X380615Y2356255D02*
Y2360549D01*
G01X388115Y2363942D02*
X380615D01*
G01Y2367862D02*
X388115D01*
G01X384365D02*
Y2363942D01*
G01X380615Y2379782D02*
Y2382022D01*
G01Y2380902D02*
X388115D01*
G01Y2379782D02*
Y2382022D01*
G01X387115Y2386442D02*
X387740Y2387189D01*
X388115Y2388029D01*
Y2388775D01*
X387740Y2389522D01*
X387115Y2390082D01*
X386240Y2390362D01*
X385365Y2390175D01*
X384615Y2389709D01*
X384115Y2388869D01*
X383865Y2387749D01*
X383365Y2387095D01*
X382490Y2386815D01*
X381615Y2387002D01*
X380990Y2387469D01*
X380615Y2388122D01*
Y2388775D01*
X380865Y2389429D01*
X381490Y2389989D01*
G01X380615Y2403402D02*
X380865Y2402655D01*
X381490Y2402095D01*
X382240Y2401722D01*
X383240Y2401442D01*
X384365Y2401349D01*
X385490Y2401442D01*
X386490Y2401722D01*
X387240Y2402095D01*
X387865Y2402655D01*
X388115Y2403402D01*
X387865Y2404149D01*
X387240Y2404709D01*
X386490Y2405082D01*
X385490Y2405362D01*
X384365Y2405455D01*
X383240Y2405362D01*
X382240Y2405082D01*
X381490Y2404709D01*
X380865Y2404149D01*
X380615Y2403402D01*
G01X388365Y2410902D02*
X388240Y2410715D01*
X387990D01*
X387865Y2410902D01*
X387990Y2411089D01*
X388240D01*
X388365Y2410902D01*
G01X384990Y2416629D02*
X384115Y2417282D01*
X383615Y2417842D01*
X383365Y2418589D01*
X383615Y2419242D01*
X384115Y2419709D01*
X384865Y2420082D01*
X385740Y2420175D01*
X386490Y2420082D01*
X387240Y2419709D01*
X387865Y2419149D01*
X388115Y2418495D01*
X387865Y2417749D01*
X387115Y2417095D01*
X385990Y2416722D01*
X384740Y2416629D01*
X383115Y2416815D01*
X382240Y2417095D01*
X381365Y2417562D01*
X380740Y2418215D01*
X380615Y2418869D01*
X380865Y2419522D01*
X381490Y2419989D01*
G01X388115Y2423475D02*
X380615D01*
X386865Y2425902D01*
X380615Y2428329D01*
X388115D01*
G01Y2430975D02*
X380615D01*
X386865Y2433402D01*
X380615Y2435829D01*
X388115D01*
G01Y2445975D02*
X380615D01*
X386865Y2448402D01*
X380615Y2450829D01*
X388115D01*
G01Y2457769D02*
Y2454035D01*
X380615D01*
Y2457769D01*
G01X384240Y2456275D02*
Y2454035D01*
G01X380615Y2463402D02*
X388115D01*
G01X380615Y2461255D02*
Y2465549D01*
G01X388115Y2469035D02*
X380615D01*
Y2471369D01*
X380990Y2472115D01*
X381490Y2472582D01*
X382490Y2472769D01*
X383490Y2472582D01*
X384115Y2472022D01*
X384490Y2471369D01*
Y2469035D01*
G01Y2471369D02*
X388115Y2472769D01*
G01X380615Y2477282D02*
Y2479522D01*
G01Y2478402D02*
X388115D01*
G01Y2477282D02*
Y2479522D01*
G01X381240Y2487955D02*
X380865Y2487395D01*
X380615Y2486742D01*
Y2485995D01*
X380990Y2485155D01*
X381615Y2484502D01*
X382365Y2484035D01*
X383615Y2483662D01*
X384740Y2483569D01*
X385865Y2483755D01*
X386615Y2484035D01*
X387365Y2484595D01*
X387865Y2485249D01*
X388115Y2485902D01*
Y2486555D01*
X387865Y2487209D01*
X387490Y2487769D01*
X386990Y2488235D01*
G01X388115Y2498849D02*
X380615D01*
Y2500715D01*
X380990Y2501462D01*
X381490Y2502022D01*
X382240Y2502489D01*
X383115Y2502862D01*
X384365Y2502955D01*
X385615Y2502862D01*
X386490Y2502489D01*
X387240Y2502022D01*
X387740Y2501462D01*
X388115Y2500715D01*
Y2498849D01*
G01Y2506535D02*
X380615D01*
Y2508869D01*
X380990Y2509615D01*
X381490Y2510082D01*
X382490Y2510269D01*
X383490Y2510082D01*
X384115Y2509522D01*
X384490Y2508869D01*
Y2506535D01*
G01Y2508869D02*
X388115Y2510269D01*
G01X380615Y2514782D02*
Y2517022D01*
G01Y2515902D02*
X388115D01*
G01Y2514782D02*
Y2517022D01*
G01X380615Y2521535D02*
X388115D01*
Y2525269D01*
G01X380615Y2529035D02*
X388115D01*
Y2532769D01*
G01X390615Y2537935D02*
X389365Y2537002D01*
X388115Y2536535D01*
X383115D01*
X381865Y2537002D01*
X380615Y2537935D01*
G01Y2545902D02*
X380865Y2545155D01*
X381490Y2544595D01*
X382240Y2544222D01*
X383240Y2543942D01*
X384365Y2543849D01*
X385490Y2543942D01*
X386490Y2544222D01*
X387240Y2544595D01*
X387865Y2545155D01*
X388115Y2545902D01*
X387865Y2546649D01*
X387240Y2547209D01*
X386490Y2547582D01*
X385490Y2547862D01*
X384365Y2547955D01*
X383240Y2547862D01*
X382240Y2547582D01*
X381490Y2547209D01*
X380865Y2546649D01*
X380615Y2545902D01*
G01X388365Y2553402D02*
X388240Y2553215D01*
X387990D01*
X387865Y2553402D01*
X387990Y2553589D01*
X388240D01*
X388365Y2553402D01*
G01X380615Y2560902D02*
X380865Y2560155D01*
X381490Y2559595D01*
X382240Y2559222D01*
X383240Y2558942D01*
X384365Y2558849D01*
X385490Y2558942D01*
X386490Y2559222D01*
X387240Y2559595D01*
X387865Y2560155D01*
X388115Y2560902D01*
X387865Y2561649D01*
X387240Y2562209D01*
X386490Y2562582D01*
X385490Y2562862D01*
X384365Y2562955D01*
X383240Y2562862D01*
X382240Y2562582D01*
X381490Y2562209D01*
X380865Y2561649D01*
X380615Y2560902D01*
G01X381865Y2566629D02*
X381115Y2567189D01*
X380740Y2567842D01*
X380615Y2568589D01*
X380865Y2569522D01*
X381490Y2570175D01*
X382240Y2570362D01*
X382990Y2570269D01*
X383615Y2569895D01*
X384865Y2568029D01*
X385740Y2567189D01*
X386990Y2566629D01*
X388115Y2566442D01*
Y2570362D01*
G01X386615Y2573849D02*
X387490Y2574409D01*
X387990Y2575155D01*
X388115Y2575995D01*
X387990Y2576742D01*
X387365Y2577489D01*
X386615Y2577955D01*
X385865Y2578049D01*
X384990Y2577862D01*
X384365Y2577209D01*
X384115Y2576555D01*
Y2575715D01*
G01Y2576555D02*
X383740Y2577115D01*
X383115Y2577582D01*
X382365Y2577769D01*
X381615Y2577582D01*
X380990Y2577115D01*
X380615Y2576275D01*
X380740Y2575435D01*
X381240Y2574595D01*
G01X384990Y2581629D02*
X384115Y2582282D01*
X383615Y2582842D01*
X383365Y2583589D01*
X383615Y2584242D01*
X384115Y2584709D01*
X384865Y2585082D01*
X385740Y2585175D01*
X386490Y2585082D01*
X387240Y2584709D01*
X387865Y2584149D01*
X388115Y2583495D01*
X387865Y2582749D01*
X387115Y2582095D01*
X385990Y2581722D01*
X384740Y2581629D01*
X383115Y2581815D01*
X382240Y2582095D01*
X381365Y2582562D01*
X380740Y2583215D01*
X380615Y2583869D01*
X380865Y2584522D01*
X381490Y2584989D01*
G01X382240Y2590062D02*
X380615Y2590529D01*
G01Y2591742D02*
X382240Y2591275D01*
G01X390615Y2598869D02*
X389365Y2599802D01*
X388115Y2600269D01*
X383115D01*
X381865Y2599802D01*
X380615Y2598869D01*
G01X388365Y2605902D02*
X388240Y2605715D01*
X387990D01*
X387865Y2605902D01*
X387990Y2606089D01*
X388240D01*
X388365Y2605902D01*
G01X416650Y-392790D02*
X418109Y-391860D01*
X418942Y-390620D01*
X419150Y-389225D01*
X418942Y-387985D01*
X417900Y-386745D01*
X416650Y-385970D01*
X415400Y-385815D01*
X413942Y-386125D01*
X412900Y-387210D01*
X412483Y-388295D01*
Y-389690D01*
G01Y-388295D02*
X411858Y-387365D01*
X410817Y-386590D01*
X409567Y-386280D01*
X408317Y-386590D01*
X407275Y-387365D01*
X406650Y-388760D01*
X406858Y-390155D01*
X407692Y-391550D01*
G01X417692Y-379615D02*
X418733Y-378530D01*
X419150Y-377290D01*
X418733Y-376050D01*
X417484Y-374965D01*
X415608Y-374190D01*
X413733Y-373880D01*
X411442D01*
X409567Y-374190D01*
X407900Y-374965D01*
X407067Y-375895D01*
X406650Y-376980D01*
X407067Y-378220D01*
X407900Y-379150D01*
X409150Y-379770D01*
X410817Y-380080D01*
X412275Y-379770D01*
X413733Y-378995D01*
X414567Y-378065D01*
X414775Y-376980D01*
X414359Y-375740D01*
X413317Y-374810D01*
X411442Y-373880D01*
G01X417275Y-367990D02*
X418317Y-367060D01*
X418942Y-365975D01*
X419150Y-364580D01*
X418733Y-363185D01*
X417900Y-362100D01*
X416442Y-361325D01*
X414775Y-361170D01*
X413108Y-361480D01*
X412067Y-362255D01*
X411233Y-363340D01*
X411025Y-364425D01*
X411233Y-365510D01*
X412067Y-366905D01*
X406650Y-366440D01*
Y-362255D01*
G01X408733Y-355125D02*
X407484Y-354195D01*
X406858Y-353110D01*
X406650Y-351870D01*
X407067Y-350320D01*
X408108Y-349235D01*
X409358Y-348925D01*
X410609Y-349080D01*
X411650Y-349700D01*
X413733Y-352800D01*
X415192Y-354195D01*
X417275Y-355125D01*
X419150Y-355435D01*
Y-348925D01*
G01X419567Y-339780D02*
X419358Y-340090D01*
X418942D01*
X418733Y-339780D01*
X418942Y-339470D01*
X419358D01*
X419567Y-339780D01*
G01X406650Y-327380D02*
X407067Y-328620D01*
X408108Y-329550D01*
X409358Y-330170D01*
X411025Y-330635D01*
X412900Y-330790D01*
X414775Y-330635D01*
X416442Y-330170D01*
X417692Y-329550D01*
X418733Y-328620D01*
X419150Y-327380D01*
X418733Y-326140D01*
X417692Y-325210D01*
X416442Y-324590D01*
X414775Y-324125D01*
X412900Y-323970D01*
X411025Y-324125D01*
X409358Y-324590D01*
X408108Y-325210D01*
X407067Y-326140D01*
X406650Y-327380D01*
G01X419150Y-314980D02*
X418942Y-313895D01*
X418317Y-312655D01*
X417275Y-311880D01*
X415817Y-311570D01*
X414359Y-311880D01*
X413108Y-312810D01*
X412483Y-314205D01*
Y-315755D01*
X412067Y-316685D01*
X411025Y-317460D01*
X409567Y-317770D01*
X408108Y-317305D01*
X407067Y-316220D01*
X406650Y-314980D01*
X407067Y-313740D01*
X408108Y-312655D01*
X409567Y-312190D01*
X411025Y-312500D01*
X412067Y-313275D01*
X412483Y-314205D01*
Y-315755D01*
X413108Y-317150D01*
X414359Y-318080D01*
X415817Y-318390D01*
X417275Y-318080D01*
X418317Y-317305D01*
X418942Y-316065D01*
X419150Y-314980D01*
G01Y-280380D02*
X406650D01*
X409150Y-282240D01*
G01X419150D02*
Y-278520D01*
G01X406650Y-267980D02*
X407067Y-269220D01*
X408108Y-270150D01*
X409358Y-270770D01*
X411025Y-271235D01*
X412900Y-271390D01*
X414775Y-271235D01*
X416442Y-270770D01*
X417692Y-270150D01*
X418733Y-269220D01*
X419150Y-267980D01*
X418733Y-266740D01*
X417692Y-265810D01*
X416442Y-265190D01*
X414775Y-264725D01*
X412900Y-264570D01*
X411025Y-264725D01*
X409358Y-265190D01*
X408108Y-265810D01*
X407067Y-266740D01*
X406650Y-267980D01*
G01Y-255580D02*
X407067Y-256820D01*
X408108Y-257750D01*
X409358Y-258370D01*
X411025Y-258835D01*
X412900Y-258990D01*
X414775Y-258835D01*
X416442Y-258370D01*
X417692Y-257750D01*
X418733Y-256820D01*
X419150Y-255580D01*
X418733Y-254340D01*
X417692Y-253410D01*
X416442Y-252790D01*
X414775Y-252325D01*
X412900Y-252170D01*
X411025Y-252325D01*
X409358Y-252790D01*
X408108Y-253410D01*
X407067Y-254340D01*
X406650Y-255580D01*
G01X419567Y-243180D02*
X419358Y-243490D01*
X418942D01*
X418733Y-243180D01*
X418942Y-242870D01*
X419358D01*
X419567Y-243180D01*
G01X416650Y-234190D02*
X418109Y-233260D01*
X418942Y-232020D01*
X419150Y-230625D01*
X418942Y-229385D01*
X417900Y-228145D01*
X416650Y-227370D01*
X415400Y-227215D01*
X413942Y-227525D01*
X412900Y-228610D01*
X412483Y-229695D01*
Y-231090D01*
G01Y-229695D02*
X411858Y-228765D01*
X410817Y-227990D01*
X409567Y-227680D01*
X408317Y-227990D01*
X407275Y-228765D01*
X406650Y-230160D01*
X406858Y-231555D01*
X407692Y-232950D01*
G01X419150Y-218380D02*
X418942Y-217295D01*
X418317Y-216055D01*
X417275Y-215280D01*
X415817Y-214970D01*
X414359Y-215280D01*
X413108Y-216210D01*
X412483Y-217605D01*
Y-219155D01*
X412067Y-220085D01*
X411025Y-220860D01*
X409567Y-221170D01*
X408108Y-220705D01*
X407067Y-219620D01*
X406650Y-218380D01*
X407067Y-217140D01*
X408108Y-216055D01*
X409567Y-215590D01*
X411025Y-215900D01*
X412067Y-216675D01*
X412483Y-217605D01*
Y-219155D01*
X413108Y-220550D01*
X414359Y-221480D01*
X415817Y-221790D01*
X417275Y-221480D01*
X418317Y-220705D01*
X418942Y-219465D01*
X419150Y-218380D01*
G01X395520Y1970683D02*
X395145Y1970123D01*
X394895Y1969470D01*
Y1968723D01*
X395270Y1967883D01*
X395895Y1967230D01*
X396645Y1966763D01*
X397895Y1966390D01*
X399020Y1966297D01*
X400145Y1966483D01*
X400895Y1966763D01*
X401645Y1967323D01*
X402145Y1967977D01*
X402395Y1968630D01*
Y1969283D01*
X402145Y1969937D01*
X401770Y1970497D01*
X401270Y1970963D01*
G01X402395Y1976130D02*
X402270Y1975383D01*
X401770Y1974730D01*
X401020Y1974170D01*
X400145Y1973797D01*
X399145Y1973610D01*
X398145D01*
X397145Y1973797D01*
X396270Y1974170D01*
X395520Y1974730D01*
X395020Y1975383D01*
X394895Y1976130D01*
X395020Y1976877D01*
X395520Y1977530D01*
X396270Y1978090D01*
X397145Y1978463D01*
X398145Y1978650D01*
X399145D01*
X400145Y1978463D01*
X401020Y1978090D01*
X401770Y1977530D01*
X402270Y1976877D01*
X402395Y1976130D01*
G01Y1981763D02*
X394895D01*
Y1984003D01*
X395270Y1984750D01*
X396145Y1985310D01*
X397145Y1985497D01*
X398145Y1985310D01*
X398895Y1984843D01*
X399270Y1984003D01*
Y1981763D01*
G01X402395Y1989263D02*
X394895D01*
Y1991503D01*
X395270Y1992250D01*
X396145Y1992810D01*
X397145Y1992997D01*
X398145Y1992810D01*
X398895Y1992343D01*
X399270Y1991503D01*
Y1989263D01*
G01X402395Y2000497D02*
Y1996763D01*
X394895D01*
Y2000497D01*
G01X398520Y1999003D02*
Y1996763D01*
G01X402395Y2004263D02*
X394895D01*
Y2006597D01*
X395270Y2007343D01*
X395770Y2007810D01*
X396770Y2007997D01*
X397770Y2007810D01*
X398395Y2007250D01*
X398770Y2006597D01*
Y2004263D01*
G01Y2006597D02*
X402395Y2007997D01*
G01Y2021130D02*
X402270Y2020383D01*
X401770Y2019730D01*
X401020Y2019170D01*
X400145Y2018797D01*
X399145Y2018610D01*
X398145D01*
X397145Y2018797D01*
X396270Y2019170D01*
X395520Y2019730D01*
X395020Y2020383D01*
X394895Y2021130D01*
X395020Y2021877D01*
X395520Y2022530D01*
X396270Y2023090D01*
X397145Y2023463D01*
X398145Y2023650D01*
X399145D01*
X400145Y2023463D01*
X401020Y2023090D01*
X401770Y2022530D01*
X402270Y2021877D01*
X402395Y2021130D01*
G01X401395Y2026670D02*
X402020Y2027417D01*
X402395Y2028257D01*
Y2029003D01*
X402020Y2029750D01*
X401395Y2030310D01*
X400520Y2030590D01*
X399645Y2030403D01*
X398895Y2029937D01*
X398395Y2029097D01*
X398145Y2027977D01*
X397645Y2027323D01*
X396770Y2027043D01*
X395895Y2027230D01*
X395270Y2027697D01*
X394895Y2028350D01*
Y2029003D01*
X395145Y2029657D01*
X395770Y2030217D01*
G01X402395Y2034263D02*
X394895D01*
Y2036503D01*
X395270Y2037250D01*
X396145Y2037810D01*
X397145Y2037997D01*
X398145Y2037810D01*
X398895Y2037343D01*
X399270Y2036503D01*
Y2034263D01*
G01X402645Y2041950D02*
X394895Y2045310D01*
G01Y2051130D02*
X402395D01*
G01X394895Y2048983D02*
Y2053277D01*
G01Y2057510D02*
Y2059750D01*
G01Y2058630D02*
X402395D01*
G01Y2057510D02*
Y2059750D01*
G01Y2063983D02*
X394895D01*
X402395Y2068277D01*
X394895D01*
G01X404895Y2073163D02*
X403645Y2072230D01*
X402395Y2071763D01*
X397395D01*
X396145Y2072230D01*
X394895Y2073163D01*
G01Y2080010D02*
Y2082250D01*
G01Y2081130D02*
X402395D01*
G01Y2080010D02*
Y2082250D01*
G01Y2086203D02*
X394895D01*
X401145Y2088630D01*
X394895Y2091057D01*
X402395D01*
G01Y2093703D02*
X394895D01*
X401145Y2096130D01*
X394895Y2098557D01*
X402395D01*
G01Y2105497D02*
Y2101763D01*
X394895D01*
Y2105497D01*
G01X398520Y2104003D02*
Y2101763D01*
G01X402395Y2109263D02*
X394895D01*
Y2111597D01*
X395270Y2112343D01*
X395770Y2112810D01*
X396770Y2112997D01*
X397770Y2112810D01*
X398395Y2112250D01*
X398770Y2111597D01*
Y2109263D01*
G01Y2111597D02*
X402395Y2112997D01*
G01X401395Y2116670D02*
X402020Y2117417D01*
X402395Y2118257D01*
Y2119003D01*
X402020Y2119750D01*
X401395Y2120310D01*
X400520Y2120590D01*
X399645Y2120403D01*
X398895Y2119937D01*
X398395Y2119097D01*
X398145Y2117977D01*
X397645Y2117323D01*
X396770Y2117043D01*
X395895Y2117230D01*
X395270Y2117697D01*
X394895Y2118350D01*
Y2119003D01*
X395145Y2119657D01*
X395770Y2120217D01*
G01X394895Y2125010D02*
Y2127250D01*
G01Y2126130D02*
X402395D01*
G01Y2125010D02*
Y2127250D01*
G01Y2133630D02*
X402270Y2132883D01*
X401770Y2132230D01*
X401020Y2131670D01*
X400145Y2131297D01*
X399145Y2131110D01*
X398145D01*
X397145Y2131297D01*
X396270Y2131670D01*
X395520Y2132230D01*
X395020Y2132883D01*
X394895Y2133630D01*
X395020Y2134377D01*
X395520Y2135030D01*
X396270Y2135590D01*
X397145Y2135963D01*
X398145Y2136150D01*
X399145D01*
X400145Y2135963D01*
X401020Y2135590D01*
X401770Y2135030D01*
X402270Y2134377D01*
X402395Y2133630D01*
G01Y2138983D02*
X394895D01*
X402395Y2143277D01*
X394895D01*
G01X404895Y2149097D02*
X403645Y2150030D01*
X402395Y2150497D01*
X397395D01*
X396145Y2150030D01*
X394895Y2149097D01*
G01X402645Y2156130D02*
X402520Y2155943D01*
X402270D01*
X402145Y2156130D01*
X402270Y2156317D01*
X402520D01*
X402645Y2156130D01*
G01X399270D02*
X399145Y2155943D01*
X398895D01*
X398770Y2156130D01*
X398895Y2156317D01*
X399145D01*
X399270Y2156130D01*
G01X402395Y2161763D02*
X394895D01*
Y2164097D01*
X395270Y2164843D01*
X395770Y2165310D01*
X396770Y2165497D01*
X397770Y2165310D01*
X398395Y2164750D01*
X398770Y2164097D01*
Y2161763D01*
G01Y2164097D02*
X402395Y2165497D01*
G01Y2172997D02*
Y2169263D01*
X394895D01*
Y2172997D01*
G01X398520Y2171503D02*
Y2169263D01*
G01X395520Y2180683D02*
X395145Y2180123D01*
X394895Y2179470D01*
Y2178723D01*
X395270Y2177883D01*
X395895Y2177230D01*
X396645Y2176763D01*
X397895Y2176390D01*
X399020Y2176297D01*
X400145Y2176483D01*
X400895Y2176763D01*
X401645Y2177323D01*
X402145Y2177977D01*
X402395Y2178630D01*
Y2179283D01*
X402145Y2179937D01*
X401770Y2180497D01*
X401270Y2180963D01*
G01X402395Y2186130D02*
X402270Y2185383D01*
X401770Y2184730D01*
X401020Y2184170D01*
X400145Y2183797D01*
X399145Y2183610D01*
X398145D01*
X397145Y2183797D01*
X396270Y2184170D01*
X395520Y2184730D01*
X395020Y2185383D01*
X394895Y2186130D01*
X395020Y2186877D01*
X395520Y2187530D01*
X396270Y2188090D01*
X397145Y2188463D01*
X398145Y2188650D01*
X399145D01*
X400145Y2188463D01*
X401020Y2188090D01*
X401770Y2187530D01*
X402270Y2186877D01*
X402395Y2186130D01*
G01Y2191203D02*
X394895D01*
X401145Y2193630D01*
X394895Y2196057D01*
X402395D01*
G01Y2198703D02*
X394895D01*
X401145Y2201130D01*
X394895Y2203557D01*
X402395D01*
G01Y2210497D02*
Y2206763D01*
X394895D01*
Y2210497D01*
G01X398520Y2209003D02*
Y2206763D01*
G01X402395Y2213983D02*
X394895D01*
X402395Y2218277D01*
X394895D01*
G01X402395Y2221577D02*
X394895D01*
Y2223443D01*
X395270Y2224190D01*
X395770Y2224750D01*
X396520Y2225217D01*
X397395Y2225590D01*
X398645Y2225683D01*
X399895Y2225590D01*
X400770Y2225217D01*
X401520Y2224750D01*
X402020Y2224190D01*
X402395Y2223443D01*
Y2221577D01*
G01Y2232997D02*
Y2229263D01*
X394895D01*
Y2232997D01*
G01X398520Y2231503D02*
Y2229263D01*
G01X402395Y2236577D02*
X394895D01*
Y2238443D01*
X395270Y2239190D01*
X395770Y2239750D01*
X396520Y2240217D01*
X397395Y2240590D01*
X398645Y2240683D01*
X399895Y2240590D01*
X400770Y2240217D01*
X401520Y2239750D01*
X402020Y2239190D01*
X402395Y2238443D01*
Y2236577D01*
G01Y2251577D02*
X394895D01*
Y2253443D01*
X395270Y2254190D01*
X395770Y2254750D01*
X396520Y2255217D01*
X397395Y2255590D01*
X398645Y2255683D01*
X399895Y2255590D01*
X400770Y2255217D01*
X401520Y2254750D01*
X402020Y2254190D01*
X402395Y2253443D01*
Y2251577D01*
G01Y2259263D02*
X394895D01*
Y2261597D01*
X395270Y2262343D01*
X395770Y2262810D01*
X396770Y2262997D01*
X397770Y2262810D01*
X398395Y2262250D01*
X398770Y2261597D01*
Y2259263D01*
G01Y2261597D02*
X402395Y2262997D01*
G01X394895Y2267510D02*
Y2269750D01*
G01Y2268630D02*
X402395D01*
G01Y2267510D02*
Y2269750D01*
G01X394895Y2274263D02*
X402395D01*
Y2277997D01*
G01X394895Y2281763D02*
X402395D01*
Y2285497D01*
G01X401395Y2296670D02*
X402020Y2297417D01*
X402395Y2298257D01*
Y2299003D01*
X402020Y2299750D01*
X401395Y2300310D01*
X400520Y2300590D01*
X399645Y2300403D01*
X398895Y2299937D01*
X398395Y2299097D01*
X398145Y2297977D01*
X397645Y2297323D01*
X396770Y2297043D01*
X395895Y2297230D01*
X395270Y2297697D01*
X394895Y2298350D01*
Y2299003D01*
X395145Y2299657D01*
X395770Y2300217D01*
G01X394895Y2305010D02*
Y2307250D01*
G01Y2306130D02*
X402395D01*
G01Y2305010D02*
Y2307250D01*
G01X394895Y2311857D02*
Y2315403D01*
X402395Y2311857D01*
Y2315403D01*
G01Y2322997D02*
Y2319263D01*
X394895D01*
Y2322997D01*
G01X398520Y2321503D02*
Y2319263D01*
G01X402395Y2334357D02*
X394895D01*
Y2337903D01*
G01X398520Y2336597D02*
Y2334357D01*
G01X402395Y2343630D02*
X402270Y2342883D01*
X401770Y2342230D01*
X401020Y2341670D01*
X400145Y2341297D01*
X399145Y2341110D01*
X398145D01*
X397145Y2341297D01*
X396270Y2341670D01*
X395520Y2342230D01*
X395020Y2342883D01*
X394895Y2343630D01*
X395020Y2344377D01*
X395520Y2345030D01*
X396270Y2345590D01*
X397145Y2345963D01*
X398145Y2346150D01*
X399145D01*
X400145Y2345963D01*
X401020Y2345590D01*
X401770Y2345030D01*
X402270Y2344377D01*
X402395Y2343630D01*
G01Y2349263D02*
X394895D01*
Y2351597D01*
X395270Y2352343D01*
X395770Y2352810D01*
X396770Y2352997D01*
X397770Y2352810D01*
X398395Y2352250D01*
X398770Y2351597D01*
Y2349263D01*
G01Y2351597D02*
X402395Y2352997D01*
G01X394895Y2366130D02*
X395145Y2365383D01*
X395770Y2364823D01*
X396520Y2364450D01*
X397520Y2364170D01*
X398645Y2364077D01*
X399770Y2364170D01*
X400770Y2364450D01*
X401520Y2364823D01*
X402145Y2365383D01*
X402395Y2366130D01*
X402145Y2366877D01*
X401520Y2367437D01*
X400770Y2367810D01*
X399770Y2368090D01*
X398645Y2368183D01*
X397520Y2368090D01*
X396520Y2367810D01*
X395770Y2367437D01*
X395145Y2366877D01*
X394895Y2366130D01*
G01X402645Y2373630D02*
X402520Y2373443D01*
X402270D01*
X402145Y2373630D01*
X402270Y2373817D01*
X402520D01*
X402645Y2373630D01*
G01X401270Y2379077D02*
X401895Y2379637D01*
X402270Y2380290D01*
X402395Y2381130D01*
X402145Y2381970D01*
X401645Y2382623D01*
X400770Y2383090D01*
X399770Y2383183D01*
X398770Y2382997D01*
X398145Y2382530D01*
X397645Y2381877D01*
X397520Y2381223D01*
X397645Y2380570D01*
X398145Y2379730D01*
X394895Y2380010D01*
Y2382530D01*
G01X402395Y2386203D02*
X394895D01*
X401145Y2388630D01*
X394895Y2391057D01*
X402395D01*
G01Y2393703D02*
X394895D01*
X401145Y2396130D01*
X394895Y2398557D01*
X402395D01*
G01Y2409357D02*
X394895D01*
Y2412903D01*
G01X398520Y2411597D02*
Y2409357D01*
G01X394895Y2417510D02*
Y2419750D01*
G01Y2418630D02*
X402395D01*
G01Y2417510D02*
Y2419750D01*
G01Y2423983D02*
X394895D01*
X402395Y2428277D01*
X394895D01*
G01Y2432510D02*
Y2434750D01*
G01Y2433630D02*
X402395D01*
G01Y2432510D02*
Y2434750D01*
G01X401395Y2439170D02*
X402020Y2439917D01*
X402395Y2440757D01*
Y2441503D01*
X402020Y2442250D01*
X401395Y2442810D01*
X400520Y2443090D01*
X399645Y2442903D01*
X398895Y2442437D01*
X398395Y2441597D01*
X398145Y2440477D01*
X397645Y2439823D01*
X396770Y2439543D01*
X395895Y2439730D01*
X395270Y2440197D01*
X394895Y2440850D01*
Y2441503D01*
X395145Y2442157D01*
X395770Y2442717D01*
G01X402395Y2446670D02*
X394895D01*
G01Y2450590D02*
X402395D01*
G01X398645D02*
Y2446670D01*
G01X402395Y2457997D02*
Y2454263D01*
X394895D01*
Y2457997D01*
G01X398520Y2456503D02*
Y2454263D01*
G01X402395Y2461577D02*
X394895D01*
Y2463443D01*
X395270Y2464190D01*
X395770Y2464750D01*
X396520Y2465217D01*
X397395Y2465590D01*
X398645Y2465683D01*
X399895Y2465590D01*
X400770Y2465217D01*
X401520Y2464750D01*
X402020Y2464190D01*
X402395Y2463443D01*
Y2461577D01*
G01Y2476763D02*
X394895D01*
Y2479003D01*
X395270Y2479750D01*
X396145Y2480310D01*
X397145Y2480497D01*
X398145Y2480310D01*
X398895Y2479843D01*
X399270Y2479003D01*
Y2476763D01*
G01X394895Y2486130D02*
X402395D01*
G01X394895Y2483983D02*
Y2488277D01*
G01X402395Y2491670D02*
X394895D01*
G01Y2495590D02*
X402395D01*
G01X398645D02*
Y2491670D01*
G01X394895Y2507510D02*
Y2509750D01*
G01Y2508630D02*
X402395D01*
G01Y2507510D02*
Y2509750D01*
G01X401395Y2514170D02*
X402020Y2514917D01*
X402395Y2515757D01*
Y2516503D01*
X402020Y2517250D01*
X401395Y2517810D01*
X400520Y2518090D01*
X399645Y2517903D01*
X398895Y2517437D01*
X398395Y2516597D01*
X398145Y2515477D01*
X397645Y2514823D01*
X396770Y2514543D01*
X395895Y2514730D01*
X395270Y2515197D01*
X394895Y2515850D01*
Y2516503D01*
X395145Y2517157D01*
X395770Y2517717D01*
G01X394895Y2531130D02*
X395145Y2530383D01*
X395770Y2529823D01*
X396520Y2529450D01*
X397520Y2529170D01*
X398645Y2529077D01*
X399770Y2529170D01*
X400770Y2529450D01*
X401520Y2529823D01*
X402145Y2530383D01*
X402395Y2531130D01*
X402145Y2531877D01*
X401520Y2532437D01*
X400770Y2532810D01*
X399770Y2533090D01*
X398645Y2533183D01*
X397520Y2533090D01*
X396520Y2532810D01*
X395770Y2532437D01*
X395145Y2531877D01*
X394895Y2531130D01*
G01X402645Y2538630D02*
X402520Y2538443D01*
X402270D01*
X402145Y2538630D01*
X402270Y2538817D01*
X402520D01*
X402645Y2538630D01*
G01X399270Y2544357D02*
X398395Y2545010D01*
X397895Y2545570D01*
X397645Y2546317D01*
X397895Y2546970D01*
X398395Y2547437D01*
X399145Y2547810D01*
X400020Y2547903D01*
X400770Y2547810D01*
X401520Y2547437D01*
X402145Y2546877D01*
X402395Y2546223D01*
X402145Y2545477D01*
X401395Y2544823D01*
X400270Y2544450D01*
X399020Y2544357D01*
X397395Y2544543D01*
X396520Y2544823D01*
X395645Y2545290D01*
X395020Y2545943D01*
X394895Y2546597D01*
X395145Y2547250D01*
X395770Y2547717D01*
G01X402395Y2551203D02*
X394895D01*
X401145Y2553630D01*
X394895Y2556057D01*
X402395D01*
G01Y2558703D02*
X394895D01*
X401145Y2561130D01*
X394895Y2563557D01*
X402395D01*
G01Y2573703D02*
X394895D01*
X401145Y2576130D01*
X394895Y2578557D01*
X402395D01*
G01Y2585497D02*
Y2581763D01*
X394895D01*
Y2585497D01*
G01X398520Y2584003D02*
Y2581763D01*
G01X394895Y2591130D02*
X402395D01*
G01X394895Y2588983D02*
Y2593277D01*
G01X402395Y2596763D02*
X394895D01*
Y2599097D01*
X395270Y2599843D01*
X395770Y2600310D01*
X396770Y2600497D01*
X397770Y2600310D01*
X398395Y2599750D01*
X398770Y2599097D01*
Y2596763D01*
G01Y2599097D02*
X402395Y2600497D01*
G01X394895Y2605010D02*
Y2607250D01*
G01Y2606130D02*
X402395D01*
G01Y2605010D02*
Y2607250D01*
G01X395520Y2615683D02*
X395145Y2615123D01*
X394895Y2614470D01*
Y2613723D01*
X395270Y2612883D01*
X395895Y2612230D01*
X396645Y2611763D01*
X397895Y2611390D01*
X399020Y2611297D01*
X400145Y2611483D01*
X400895Y2611763D01*
X401645Y2612323D01*
X402145Y2612977D01*
X402395Y2613630D01*
Y2614283D01*
X402145Y2614937D01*
X401770Y2615497D01*
X401270Y2615963D01*
G01X402395Y2626577D02*
X394895D01*
Y2628443D01*
X395270Y2629190D01*
X395770Y2629750D01*
X396520Y2630217D01*
X397395Y2630590D01*
X398645Y2630683D01*
X399895Y2630590D01*
X400770Y2630217D01*
X401520Y2629750D01*
X402020Y2629190D01*
X402395Y2628443D01*
Y2626577D01*
G01Y2634263D02*
X394895D01*
Y2636597D01*
X395270Y2637343D01*
X395770Y2637810D01*
X396770Y2637997D01*
X397770Y2637810D01*
X398395Y2637250D01*
X398770Y2636597D01*
Y2634263D01*
G01Y2636597D02*
X402395Y2637997D01*
G01X394895Y2642510D02*
Y2644750D01*
G01Y2643630D02*
X402395D01*
G01Y2642510D02*
Y2644750D01*
G01X394895Y2649263D02*
X402395D01*
Y2652997D01*
G01X394895Y2656763D02*
X402395D01*
Y2660497D01*
G01X404895Y2665663D02*
X403645Y2664730D01*
X402395Y2664263D01*
X397395D01*
X396145Y2664730D01*
X394895Y2665663D01*
G01Y2673630D02*
X395145Y2672883D01*
X395770Y2672323D01*
X396520Y2671950D01*
X397520Y2671670D01*
X398645Y2671577D01*
X399770Y2671670D01*
X400770Y2671950D01*
X401520Y2672323D01*
X402145Y2672883D01*
X402395Y2673630D01*
X402145Y2674377D01*
X401520Y2674937D01*
X400770Y2675310D01*
X399770Y2675590D01*
X398645Y2675683D01*
X397520Y2675590D01*
X396520Y2675310D01*
X395770Y2674937D01*
X395145Y2674377D01*
X394895Y2673630D01*
G01X402645Y2681130D02*
X402520Y2680943D01*
X402270D01*
X402145Y2681130D01*
X402270Y2681317D01*
X402520D01*
X402645Y2681130D01*
G01X394895Y2688630D02*
X395145Y2687883D01*
X395770Y2687323D01*
X396520Y2686950D01*
X397520Y2686670D01*
X398645Y2686577D01*
X399770Y2686670D01*
X400770Y2686950D01*
X401520Y2687323D01*
X402145Y2687883D01*
X402395Y2688630D01*
X402145Y2689377D01*
X401520Y2689937D01*
X400770Y2690310D01*
X399770Y2690590D01*
X398645Y2690683D01*
X397520Y2690590D01*
X396520Y2690310D01*
X395770Y2689937D01*
X395145Y2689377D01*
X394895Y2688630D01*
G01X396145Y2694357D02*
X395395Y2694917D01*
X395020Y2695570D01*
X394895Y2696317D01*
X395145Y2697250D01*
X395770Y2697903D01*
X396520Y2698090D01*
X397270Y2697997D01*
X397895Y2697623D01*
X399145Y2695757D01*
X400020Y2694917D01*
X401270Y2694357D01*
X402395Y2694170D01*
Y2698090D01*
G01X400895Y2701577D02*
X401770Y2702137D01*
X402270Y2702883D01*
X402395Y2703723D01*
X402270Y2704470D01*
X401645Y2705217D01*
X400895Y2705683D01*
X400145Y2705777D01*
X399270Y2705590D01*
X398645Y2704937D01*
X398395Y2704283D01*
Y2703443D01*
G01Y2704283D02*
X398020Y2704843D01*
X397395Y2705310D01*
X396645Y2705497D01*
X395895Y2705310D01*
X395270Y2704843D01*
X394895Y2704003D01*
X395020Y2703163D01*
X395520Y2702323D01*
G01X399270Y2709357D02*
X398395Y2710010D01*
X397895Y2710570D01*
X397645Y2711317D01*
X397895Y2711970D01*
X398395Y2712437D01*
X399145Y2712810D01*
X400020Y2712903D01*
X400770Y2712810D01*
X401520Y2712437D01*
X402145Y2711877D01*
X402395Y2711223D01*
X402145Y2710477D01*
X401395Y2709823D01*
X400270Y2709450D01*
X399020Y2709357D01*
X397395Y2709543D01*
X396520Y2709823D01*
X395645Y2710290D01*
X395020Y2710943D01*
X394895Y2711597D01*
X395145Y2712250D01*
X395770Y2712717D01*
G01X396520Y2717790D02*
X394895Y2718257D01*
G01Y2719470D02*
X396520Y2719003D01*
G01X404895Y2726597D02*
X403645Y2727530D01*
X402395Y2727997D01*
X397395D01*
X396145Y2727530D01*
X394895Y2726597D01*
G01X402645Y2733630D02*
X402520Y2733443D01*
X402270D01*
X402145Y2733630D01*
X402270Y2733817D01*
X402520D01*
X402645Y2733630D01*
G01X414295Y1965910D02*
X414920Y1966657D01*
X415295Y1967497D01*
Y1968243D01*
X414920Y1968990D01*
X414295Y1969550D01*
X413420Y1969830D01*
X412545Y1969643D01*
X411795Y1969177D01*
X411295Y1968337D01*
X411045Y1967217D01*
X410545Y1966563D01*
X409670Y1966283D01*
X408795Y1966470D01*
X408170Y1966937D01*
X407795Y1967590D01*
Y1968243D01*
X408045Y1968897D01*
X408670Y1969457D01*
G01X407795Y1974250D02*
Y1976490D01*
G01Y1975370D02*
X415295D01*
G01Y1974250D02*
Y1976490D01*
G01X407795Y1981003D02*
X415295D01*
Y1984737D01*
G01X407795Y1988037D02*
X415295Y1990370D01*
X407795Y1992703D01*
G01X415295Y1999737D02*
Y1996003D01*
X407795D01*
Y1999737D01*
G01X411420Y1998243D02*
Y1996003D01*
G01X415295Y2003503D02*
X407795D01*
Y2005837D01*
X408170Y2006583D01*
X408670Y2007050D01*
X409670Y2007237D01*
X410670Y2007050D01*
X411295Y2006490D01*
X411670Y2005837D01*
Y2003503D01*
G01Y2005837D02*
X415295Y2007237D01*
G01X417795Y2012403D02*
X416545Y2011470D01*
X415295Y2011003D01*
X410295D01*
X409045Y2011470D01*
X407795Y2012403D01*
G01Y2019250D02*
Y2021490D01*
G01Y2020370D02*
X415295D01*
G01Y2019250D02*
Y2021490D01*
G01Y2025443D02*
X407795D01*
X414045Y2027870D01*
X407795Y2030297D01*
X415295D01*
G01Y2032943D02*
X407795D01*
X414045Y2035370D01*
X407795Y2037797D01*
X415295D01*
G01Y2044737D02*
Y2041003D01*
X407795D01*
Y2044737D01*
G01X411420Y2043243D02*
Y2041003D01*
G01X415295Y2048503D02*
X407795D01*
Y2050837D01*
X408170Y2051583D01*
X408670Y2052050D01*
X409670Y2052237D01*
X410670Y2052050D01*
X411295Y2051490D01*
X411670Y2050837D01*
Y2048503D01*
G01Y2050837D02*
X415295Y2052237D01*
G01X414295Y2055910D02*
X414920Y2056657D01*
X415295Y2057497D01*
Y2058243D01*
X414920Y2058990D01*
X414295Y2059550D01*
X413420Y2059830D01*
X412545Y2059643D01*
X411795Y2059177D01*
X411295Y2058337D01*
X411045Y2057217D01*
X410545Y2056563D01*
X409670Y2056283D01*
X408795Y2056470D01*
X408170Y2056937D01*
X407795Y2057590D01*
Y2058243D01*
X408045Y2058897D01*
X408670Y2059457D01*
G01X407795Y2064250D02*
Y2066490D01*
G01Y2065370D02*
X415295D01*
G01Y2064250D02*
Y2066490D01*
G01Y2072870D02*
X415170Y2072123D01*
X414670Y2071470D01*
X413920Y2070910D01*
X413045Y2070537D01*
X412045Y2070350D01*
X411045D01*
X410045Y2070537D01*
X409170Y2070910D01*
X408420Y2071470D01*
X407920Y2072123D01*
X407795Y2072870D01*
X407920Y2073617D01*
X408420Y2074270D01*
X409170Y2074830D01*
X410045Y2075203D01*
X411045Y2075390D01*
X412045D01*
X413045Y2075203D01*
X413920Y2074830D01*
X414670Y2074270D01*
X415170Y2073617D01*
X415295Y2072870D01*
G01Y2078223D02*
X407795D01*
X415295Y2082517D01*
X407795D01*
G01X417795Y2088337D02*
X416545Y2089270D01*
X415295Y2089737D01*
X410295D01*
X409045Y2089270D01*
X407795Y2088337D01*
G01X415545Y2095370D02*
X415420Y2095183D01*
X415170D01*
X415045Y2095370D01*
X415170Y2095557D01*
X415420D01*
X415545Y2095370D01*
G01X412170D02*
X412045Y2095183D01*
X411795D01*
X411670Y2095370D01*
X411795Y2095557D01*
X412045D01*
X412170Y2095370D01*
G01X415295Y2101003D02*
X407795D01*
Y2103337D01*
X408170Y2104083D01*
X408670Y2104550D01*
X409670Y2104737D01*
X410670Y2104550D01*
X411295Y2103990D01*
X411670Y2103337D01*
Y2101003D01*
G01Y2103337D02*
X415295Y2104737D01*
G01Y2112237D02*
Y2108503D01*
X407795D01*
Y2112237D01*
G01X411420Y2110743D02*
Y2108503D01*
G01X408420Y2119923D02*
X408045Y2119363D01*
X407795Y2118710D01*
Y2117963D01*
X408170Y2117123D01*
X408795Y2116470D01*
X409545Y2116003D01*
X410795Y2115630D01*
X411920Y2115537D01*
X413045Y2115723D01*
X413795Y2116003D01*
X414545Y2116563D01*
X415045Y2117217D01*
X415295Y2117870D01*
Y2118523D01*
X415045Y2119177D01*
X414670Y2119737D01*
X414170Y2120203D01*
G01X415295Y2125370D02*
X415170Y2124623D01*
X414670Y2123970D01*
X413920Y2123410D01*
X413045Y2123037D01*
X412045Y2122850D01*
X411045D01*
X410045Y2123037D01*
X409170Y2123410D01*
X408420Y2123970D01*
X407920Y2124623D01*
X407795Y2125370D01*
X407920Y2126117D01*
X408420Y2126770D01*
X409170Y2127330D01*
X410045Y2127703D01*
X411045Y2127890D01*
X412045D01*
X413045Y2127703D01*
X413920Y2127330D01*
X414670Y2126770D01*
X415170Y2126117D01*
X415295Y2125370D01*
G01Y2130443D02*
X407795D01*
X414045Y2132870D01*
X407795Y2135297D01*
X415295D01*
G01Y2137943D02*
X407795D01*
X414045Y2140370D01*
X407795Y2142797D01*
X415295D01*
G01Y2149737D02*
Y2146003D01*
X407795D01*
Y2149737D01*
G01X411420Y2148243D02*
Y2146003D01*
G01X415295Y2153223D02*
X407795D01*
X415295Y2157517D01*
X407795D01*
G01X415295Y2160817D02*
X407795D01*
Y2162683D01*
X408170Y2163430D01*
X408670Y2163990D01*
X409420Y2164457D01*
X410295Y2164830D01*
X411545Y2164923D01*
X412795Y2164830D01*
X413670Y2164457D01*
X414420Y2163990D01*
X414920Y2163430D01*
X415295Y2162683D01*
Y2160817D01*
G01Y2172237D02*
Y2168503D01*
X407795D01*
Y2172237D01*
G01X411420Y2170743D02*
Y2168503D01*
G01X415295Y2175817D02*
X407795D01*
Y2177683D01*
X408170Y2178430D01*
X408670Y2178990D01*
X409420Y2179457D01*
X410295Y2179830D01*
X411545Y2179923D01*
X412795Y2179830D01*
X413670Y2179457D01*
X414420Y2178990D01*
X414920Y2178430D01*
X415295Y2177683D01*
Y2175817D01*
G01Y2190817D02*
X407795D01*
Y2192683D01*
X408170Y2193430D01*
X408670Y2193990D01*
X409420Y2194457D01*
X410295Y2194830D01*
X411545Y2194923D01*
X412795Y2194830D01*
X413670Y2194457D01*
X414420Y2193990D01*
X414920Y2193430D01*
X415295Y2192683D01*
Y2190817D01*
G01Y2198503D02*
X407795D01*
Y2200837D01*
X408170Y2201583D01*
X408670Y2202050D01*
X409670Y2202237D01*
X410670Y2202050D01*
X411295Y2201490D01*
X411670Y2200837D01*
Y2198503D01*
G01Y2200837D02*
X415295Y2202237D01*
G01X407795Y2206750D02*
Y2208990D01*
G01Y2207870D02*
X415295D01*
G01Y2206750D02*
Y2208990D01*
G01X407795Y2213503D02*
X415295D01*
Y2217237D01*
G01X407795Y2221003D02*
X415295D01*
Y2224737D01*
G01X414295Y2235910D02*
X414920Y2236657D01*
X415295Y2237497D01*
Y2238243D01*
X414920Y2238990D01*
X414295Y2239550D01*
X413420Y2239830D01*
X412545Y2239643D01*
X411795Y2239177D01*
X411295Y2238337D01*
X411045Y2237217D01*
X410545Y2236563D01*
X409670Y2236283D01*
X408795Y2236470D01*
X408170Y2236937D01*
X407795Y2237590D01*
Y2238243D01*
X408045Y2238897D01*
X408670Y2239457D01*
G01X407795Y2244250D02*
Y2246490D01*
G01Y2245370D02*
X415295D01*
G01Y2244250D02*
Y2246490D01*
G01X407795Y2251097D02*
Y2254643D01*
X415295Y2251097D01*
Y2254643D01*
G01Y2262237D02*
Y2258503D01*
X407795D01*
Y2262237D01*
G01X411420Y2260743D02*
Y2258503D01*
G01X415295Y2273597D02*
X407795D01*
Y2277143D01*
G01X411420Y2275837D02*
Y2273597D01*
G01X415295Y2282870D02*
X415170Y2282123D01*
X414670Y2281470D01*
X413920Y2280910D01*
X413045Y2280537D01*
X412045Y2280350D01*
X411045D01*
X410045Y2280537D01*
X409170Y2280910D01*
X408420Y2281470D01*
X407920Y2282123D01*
X407795Y2282870D01*
X407920Y2283617D01*
X408420Y2284270D01*
X409170Y2284830D01*
X410045Y2285203D01*
X411045Y2285390D01*
X412045D01*
X413045Y2285203D01*
X413920Y2284830D01*
X414670Y2284270D01*
X415170Y2283617D01*
X415295Y2282870D01*
G01Y2288503D02*
X407795D01*
Y2290837D01*
X408170Y2291583D01*
X408670Y2292050D01*
X409670Y2292237D01*
X410670Y2292050D01*
X411295Y2291490D01*
X411670Y2290837D01*
Y2288503D01*
G01Y2290837D02*
X415295Y2292237D01*
G01X407795Y2305370D02*
X408045Y2304623D01*
X408670Y2304063D01*
X409420Y2303690D01*
X410420Y2303410D01*
X411545Y2303317D01*
X412670Y2303410D01*
X413670Y2303690D01*
X414420Y2304063D01*
X415045Y2304623D01*
X415295Y2305370D01*
X415045Y2306117D01*
X414420Y2306677D01*
X413670Y2307050D01*
X412670Y2307330D01*
X411545Y2307423D01*
X410420Y2307330D01*
X409420Y2307050D01*
X408670Y2306677D01*
X408045Y2306117D01*
X407795Y2305370D01*
G01X415545Y2312870D02*
X415420Y2312683D01*
X415170D01*
X415045Y2312870D01*
X415170Y2313057D01*
X415420D01*
X415545Y2312870D01*
G01X414170Y2318317D02*
X414795Y2318877D01*
X415170Y2319530D01*
X415295Y2320370D01*
X415045Y2321210D01*
X414545Y2321863D01*
X413670Y2322330D01*
X412670Y2322423D01*
X411670Y2322237D01*
X411045Y2321770D01*
X410545Y2321117D01*
X410420Y2320463D01*
X410545Y2319810D01*
X411045Y2318970D01*
X407795Y2319250D01*
Y2321770D01*
G01X415295Y2325443D02*
X407795D01*
X414045Y2327870D01*
X407795Y2330297D01*
X415295D01*
G01Y2332943D02*
X407795D01*
X414045Y2335370D01*
X407795Y2337797D01*
X415295D01*
G01Y2348597D02*
X407795D01*
Y2352143D01*
G01X411420Y2350837D02*
Y2348597D01*
G01X407795Y2356750D02*
Y2358990D01*
G01Y2357870D02*
X415295D01*
G01Y2356750D02*
Y2358990D01*
G01Y2363223D02*
X407795D01*
X415295Y2367517D01*
X407795D01*
G01Y2371750D02*
Y2373990D01*
G01Y2372870D02*
X415295D01*
G01Y2371750D02*
Y2373990D01*
G01X414295Y2378410D02*
X414920Y2379157D01*
X415295Y2379997D01*
Y2380743D01*
X414920Y2381490D01*
X414295Y2382050D01*
X413420Y2382330D01*
X412545Y2382143D01*
X411795Y2381677D01*
X411295Y2380837D01*
X411045Y2379717D01*
X410545Y2379063D01*
X409670Y2378783D01*
X408795Y2378970D01*
X408170Y2379437D01*
X407795Y2380090D01*
Y2380743D01*
X408045Y2381397D01*
X408670Y2381957D01*
G01X415295Y2385910D02*
X407795D01*
G01Y2389830D02*
X415295D01*
G01X411545D02*
Y2385910D01*
G01X415295Y2397237D02*
Y2393503D01*
X407795D01*
Y2397237D01*
G01X411420Y2395743D02*
Y2393503D01*
G01X415295Y2400817D02*
X407795D01*
Y2402683D01*
X408170Y2403430D01*
X408670Y2403990D01*
X409420Y2404457D01*
X410295Y2404830D01*
X411545Y2404923D01*
X412795Y2404830D01*
X413670Y2404457D01*
X414420Y2403990D01*
X414920Y2403430D01*
X415295Y2402683D01*
Y2400817D01*
G01Y2416003D02*
X407795D01*
Y2418243D01*
X408170Y2418990D01*
X409045Y2419550D01*
X410045Y2419737D01*
X411045Y2419550D01*
X411795Y2419083D01*
X412170Y2418243D01*
Y2416003D01*
G01X407795Y2425370D02*
X415295D01*
G01X407795Y2423223D02*
Y2427517D01*
G01X415295Y2430910D02*
X407795D01*
G01Y2434830D02*
X415295D01*
G01X411545D02*
Y2430910D01*
G01X407795Y2446750D02*
Y2448990D01*
G01Y2447870D02*
X415295D01*
G01Y2446750D02*
Y2448990D01*
G01X414295Y2453410D02*
X414920Y2454157D01*
X415295Y2454997D01*
Y2455743D01*
X414920Y2456490D01*
X414295Y2457050D01*
X413420Y2457330D01*
X412545Y2457143D01*
X411795Y2456677D01*
X411295Y2455837D01*
X411045Y2454717D01*
X410545Y2454063D01*
X409670Y2453783D01*
X408795Y2453970D01*
X408170Y2454437D01*
X407795Y2455090D01*
Y2455743D01*
X408045Y2456397D01*
X408670Y2456957D01*
G01X407795Y2470370D02*
X408045Y2469623D01*
X408670Y2469063D01*
X409420Y2468690D01*
X410420Y2468410D01*
X411545Y2468317D01*
X412670Y2468410D01*
X413670Y2468690D01*
X414420Y2469063D01*
X415045Y2469623D01*
X415295Y2470370D01*
X415045Y2471117D01*
X414420Y2471677D01*
X413670Y2472050D01*
X412670Y2472330D01*
X411545Y2472423D01*
X410420Y2472330D01*
X409420Y2472050D01*
X408670Y2471677D01*
X408045Y2471117D01*
X407795Y2470370D01*
G01X415545Y2477870D02*
X415420Y2477683D01*
X415170D01*
X415045Y2477870D01*
X415170Y2478057D01*
X415420D01*
X415545Y2477870D01*
G01X412170Y2483597D02*
X411295Y2484250D01*
X410795Y2484810D01*
X410545Y2485557D01*
X410795Y2486210D01*
X411295Y2486677D01*
X412045Y2487050D01*
X412920Y2487143D01*
X413670Y2487050D01*
X414420Y2486677D01*
X415045Y2486117D01*
X415295Y2485463D01*
X415045Y2484717D01*
X414295Y2484063D01*
X413170Y2483690D01*
X411920Y2483597D01*
X410295Y2483783D01*
X409420Y2484063D01*
X408545Y2484530D01*
X407920Y2485183D01*
X407795Y2485837D01*
X408045Y2486490D01*
X408670Y2486957D01*
G01X415295Y2490443D02*
X407795D01*
X414045Y2492870D01*
X407795Y2495297D01*
X415295D01*
G01Y2497943D02*
X407795D01*
X414045Y2500370D01*
X407795Y2502797D01*
X415295D01*
G01Y2512943D02*
X407795D01*
X414045Y2515370D01*
X407795Y2517797D01*
X415295D01*
G01Y2524737D02*
Y2521003D01*
X407795D01*
Y2524737D01*
G01X411420Y2523243D02*
Y2521003D01*
G01X407795Y2530370D02*
X415295D01*
G01X407795Y2528223D02*
Y2532517D01*
G01X415295Y2536003D02*
X407795D01*
Y2538337D01*
X408170Y2539083D01*
X408670Y2539550D01*
X409670Y2539737D01*
X410670Y2539550D01*
X411295Y2538990D01*
X411670Y2538337D01*
Y2536003D01*
G01Y2538337D02*
X415295Y2539737D01*
G01X407795Y2544250D02*
Y2546490D01*
G01Y2545370D02*
X415295D01*
G01Y2544250D02*
Y2546490D01*
G01X408420Y2554923D02*
X408045Y2554363D01*
X407795Y2553710D01*
Y2552963D01*
X408170Y2552123D01*
X408795Y2551470D01*
X409545Y2551003D01*
X410795Y2550630D01*
X411920Y2550537D01*
X413045Y2550723D01*
X413795Y2551003D01*
X414545Y2551563D01*
X415045Y2552217D01*
X415295Y2552870D01*
Y2553523D01*
X415045Y2554177D01*
X414670Y2554737D01*
X414170Y2555203D01*
G01X415295Y2565817D02*
X407795D01*
Y2567683D01*
X408170Y2568430D01*
X408670Y2568990D01*
X409420Y2569457D01*
X410295Y2569830D01*
X411545Y2569923D01*
X412795Y2569830D01*
X413670Y2569457D01*
X414420Y2568990D01*
X414920Y2568430D01*
X415295Y2567683D01*
Y2565817D01*
G01Y2573503D02*
X407795D01*
Y2575837D01*
X408170Y2576583D01*
X408670Y2577050D01*
X409670Y2577237D01*
X410670Y2577050D01*
X411295Y2576490D01*
X411670Y2575837D01*
Y2573503D01*
G01Y2575837D02*
X415295Y2577237D01*
G01X407795Y2581750D02*
Y2583990D01*
G01Y2582870D02*
X415295D01*
G01Y2581750D02*
Y2583990D01*
G01X407795Y2588503D02*
X415295D01*
Y2592237D01*
G01X407795Y2596003D02*
X415295D01*
Y2599737D01*
G01X417795Y2604903D02*
X416545Y2603970D01*
X415295Y2603503D01*
X410295D01*
X409045Y2603970D01*
X407795Y2604903D01*
G01Y2612870D02*
X408045Y2612123D01*
X408670Y2611563D01*
X409420Y2611190D01*
X410420Y2610910D01*
X411545Y2610817D01*
X412670Y2610910D01*
X413670Y2611190D01*
X414420Y2611563D01*
X415045Y2612123D01*
X415295Y2612870D01*
X415045Y2613617D01*
X414420Y2614177D01*
X413670Y2614550D01*
X412670Y2614830D01*
X411545Y2614923D01*
X410420Y2614830D01*
X409420Y2614550D01*
X408670Y2614177D01*
X408045Y2613617D01*
X407795Y2612870D01*
G01X415545Y2620370D02*
X415420Y2620183D01*
X415170D01*
X415045Y2620370D01*
X415170Y2620557D01*
X415420D01*
X415545Y2620370D01*
G01X407795Y2627870D02*
X408045Y2627123D01*
X408670Y2626563D01*
X409420Y2626190D01*
X410420Y2625910D01*
X411545Y2625817D01*
X412670Y2625910D01*
X413670Y2626190D01*
X414420Y2626563D01*
X415045Y2627123D01*
X415295Y2627870D01*
X415045Y2628617D01*
X414420Y2629177D01*
X413670Y2629550D01*
X412670Y2629830D01*
X411545Y2629923D01*
X410420Y2629830D01*
X409420Y2629550D01*
X408670Y2629177D01*
X408045Y2628617D01*
X407795Y2627870D01*
G01X409045Y2633597D02*
X408295Y2634157D01*
X407920Y2634810D01*
X407795Y2635557D01*
X408045Y2636490D01*
X408670Y2637143D01*
X409420Y2637330D01*
X410170Y2637237D01*
X410795Y2636863D01*
X412045Y2634997D01*
X412920Y2634157D01*
X414170Y2633597D01*
X415295Y2633410D01*
Y2637330D01*
G01X413795Y2640817D02*
X414670Y2641377D01*
X415170Y2642123D01*
X415295Y2642963D01*
X415170Y2643710D01*
X414545Y2644457D01*
X413795Y2644923D01*
X413045Y2645017D01*
X412170Y2644830D01*
X411545Y2644177D01*
X411295Y2643523D01*
Y2642683D01*
G01Y2643523D02*
X410920Y2644083D01*
X410295Y2644550D01*
X409545Y2644737D01*
X408795Y2644550D01*
X408170Y2644083D01*
X407795Y2643243D01*
X407920Y2642403D01*
X408420Y2641563D01*
G01X412170Y2648597D02*
X411295Y2649250D01*
X410795Y2649810D01*
X410545Y2650557D01*
X410795Y2651210D01*
X411295Y2651677D01*
X412045Y2652050D01*
X412920Y2652143D01*
X413670Y2652050D01*
X414420Y2651677D01*
X415045Y2651117D01*
X415295Y2650463D01*
X415045Y2649717D01*
X414295Y2649063D01*
X413170Y2648690D01*
X411920Y2648597D01*
X410295Y2648783D01*
X409420Y2649063D01*
X408545Y2649530D01*
X407920Y2650183D01*
X407795Y2650837D01*
X408045Y2651490D01*
X408670Y2651957D01*
G01X409420Y2657030D02*
X407795Y2657497D01*
G01Y2658710D02*
X409420Y2658243D01*
G01X417795Y2665837D02*
X416545Y2666770D01*
X415295Y2667237D01*
X410295D01*
X409045Y2666770D01*
X407795Y2665837D01*
G01X415545Y2672870D02*
X415420Y2672683D01*
X415170D01*
X415045Y2672870D01*
X415170Y2673057D01*
X415420D01*
X415545Y2672870D01*
G01X417000Y-630638D02*
Y-622638D01*
X415800Y-624238D01*
G01Y-630638D02*
X418200D01*
G01X423100Y-627305D02*
X423800Y-626371D01*
X424400Y-625838D01*
X425200Y-625571D01*
X425900Y-625838D01*
X426400Y-626371D01*
X426800Y-627171D01*
X426900Y-628105D01*
X426800Y-628905D01*
X426400Y-629705D01*
X425800Y-630371D01*
X425100Y-630638D01*
X424300Y-630371D01*
X423600Y-629572D01*
X423200Y-628371D01*
X423100Y-627038D01*
X423300Y-625305D01*
X423600Y-624371D01*
X424100Y-623438D01*
X424800Y-622771D01*
X425500Y-622638D01*
X426200Y-622905D01*
X426700Y-623571D01*
G01X433000Y-630905D02*
X432800Y-630771D01*
Y-630505D01*
X433000Y-630371D01*
X433200Y-630505D01*
Y-630771D01*
X433000Y-630905D01*
G01X439100Y-627305D02*
X439800Y-626371D01*
X440400Y-625838D01*
X441200Y-625571D01*
X441900Y-625838D01*
X442400Y-626371D01*
X442800Y-627171D01*
X442900Y-628105D01*
X442800Y-628905D01*
X442400Y-629705D01*
X441800Y-630371D01*
X441100Y-630638D01*
X440300Y-630371D01*
X439600Y-629572D01*
X439200Y-628371D01*
X439100Y-627038D01*
X439300Y-625305D01*
X439600Y-624371D01*
X440100Y-623438D01*
X440800Y-622771D01*
X441500Y-622638D01*
X442200Y-622905D01*
X442700Y-623571D01*
G01X433800Y-387360D02*
X435259Y-386430D01*
X436092Y-385190D01*
X436300Y-383795D01*
X436092Y-382555D01*
X435050Y-381315D01*
X433800Y-380540D01*
X432550Y-380385D01*
X431092Y-380695D01*
X430050Y-381780D01*
X429633Y-382865D01*
Y-384260D01*
G01Y-382865D02*
X429008Y-381935D01*
X427967Y-381160D01*
X426717Y-380850D01*
X425467Y-381160D01*
X424425Y-381935D01*
X423800Y-383330D01*
X424008Y-384725D01*
X424842Y-386120D01*
G01X434842Y-374185D02*
X435883Y-373100D01*
X436300Y-371860D01*
X435883Y-370620D01*
X434634Y-369535D01*
X432758Y-368760D01*
X430883Y-368450D01*
X428592D01*
X426717Y-368760D01*
X425050Y-369535D01*
X424217Y-370465D01*
X423800Y-371550D01*
X424217Y-372790D01*
X425050Y-373720D01*
X426300Y-374340D01*
X427967Y-374650D01*
X429425Y-374340D01*
X430883Y-373565D01*
X431717Y-372635D01*
X431925Y-371550D01*
X431509Y-370310D01*
X430467Y-369380D01*
X428592Y-368450D01*
G01X434425Y-362560D02*
X435467Y-361630D01*
X436092Y-360545D01*
X436300Y-359150D01*
X435883Y-357755D01*
X435050Y-356670D01*
X433592Y-355895D01*
X431925Y-355740D01*
X430258Y-356050D01*
X429217Y-356825D01*
X428383Y-357910D01*
X428175Y-358995D01*
X428383Y-360080D01*
X429217Y-361475D01*
X423800Y-361010D01*
Y-356825D01*
G01X431092Y-349695D02*
X429633Y-348610D01*
X428800Y-347680D01*
X428383Y-346440D01*
X428800Y-345355D01*
X429633Y-344580D01*
X430883Y-343960D01*
X432342Y-343805D01*
X433592Y-343960D01*
X434842Y-344580D01*
X435883Y-345510D01*
X436300Y-346595D01*
X435883Y-347835D01*
X434634Y-348920D01*
X432758Y-349540D01*
X430675Y-349695D01*
X427967Y-349385D01*
X426508Y-348920D01*
X425050Y-348145D01*
X424008Y-347060D01*
X423800Y-345975D01*
X424217Y-344890D01*
X425258Y-344115D01*
G01X436717Y-334350D02*
X436508Y-334660D01*
X436092D01*
X435883Y-334350D01*
X436092Y-334040D01*
X436508D01*
X436717Y-334350D01*
G01X436300Y-322260D02*
X433592Y-321950D01*
X431300Y-321485D01*
X429217Y-320865D01*
X426925Y-320090D01*
X423800Y-318850D01*
Y-325050D01*
G01X436300Y-309550D02*
X423800D01*
X426300Y-311410D01*
G01X436300D02*
Y-307690D01*
G01Y-274950D02*
X423800D01*
X426300Y-276810D01*
G01X436300D02*
Y-273090D01*
G01X423800Y-262550D02*
X424217Y-263790D01*
X425258Y-264720D01*
X426508Y-265340D01*
X428175Y-265805D01*
X430050Y-265960D01*
X431925Y-265805D01*
X433592Y-265340D01*
X434842Y-264720D01*
X435883Y-263790D01*
X436300Y-262550D01*
X435883Y-261310D01*
X434842Y-260380D01*
X433592Y-259760D01*
X431925Y-259295D01*
X430050Y-259140D01*
X428175Y-259295D01*
X426508Y-259760D01*
X425258Y-260380D01*
X424217Y-261310D01*
X423800Y-262550D01*
G01Y-250150D02*
X424217Y-251390D01*
X425258Y-252320D01*
X426508Y-252940D01*
X428175Y-253405D01*
X430050Y-253560D01*
X431925Y-253405D01*
X433592Y-252940D01*
X434842Y-252320D01*
X435883Y-251390D01*
X436300Y-250150D01*
X435883Y-248910D01*
X434842Y-247980D01*
X433592Y-247360D01*
X431925Y-246895D01*
X430050Y-246740D01*
X428175Y-246895D01*
X426508Y-247360D01*
X425258Y-247980D01*
X424217Y-248910D01*
X423800Y-250150D01*
G01X436717Y-237750D02*
X436508Y-238060D01*
X436092D01*
X435883Y-237750D01*
X436092Y-237440D01*
X436508D01*
X436717Y-237750D01*
G01X434425Y-228760D02*
X435467Y-227830D01*
X436092Y-226745D01*
X436300Y-225350D01*
X435883Y-223955D01*
X435050Y-222870D01*
X433592Y-222095D01*
X431925Y-221940D01*
X430258Y-222250D01*
X429217Y-223025D01*
X428383Y-224110D01*
X428175Y-225195D01*
X428383Y-226280D01*
X429217Y-227675D01*
X423800Y-227210D01*
Y-223025D01*
G01X429265Y1928155D02*
X421765D01*
X429265Y1932449D01*
X421765D01*
G01X429265Y1937802D02*
X429140Y1937055D01*
X428640Y1936402D01*
X427890Y1935842D01*
X427015Y1935469D01*
X426015Y1935282D01*
X425015D01*
X424015Y1935469D01*
X423140Y1935842D01*
X422390Y1936402D01*
X421890Y1937055D01*
X421765Y1937802D01*
X421890Y1938549D01*
X422390Y1939202D01*
X423140Y1939762D01*
X424015Y1940135D01*
X425015Y1940322D01*
X426015D01*
X427015Y1940135D01*
X427890Y1939762D01*
X428640Y1939202D01*
X429140Y1938549D01*
X429265Y1937802D01*
G01Y1943155D02*
X421765D01*
X429265Y1947449D01*
X421765D01*
G01X426765Y1951589D02*
Y1954015D01*
G01X429265Y1957875D02*
X421765D01*
X428015Y1960302D01*
X421765Y1962729D01*
X429265D01*
G01Y1965469D02*
X421765Y1967802D01*
X429265Y1970135D01*
G01X426640Y1969295D02*
Y1966309D01*
G01X429265Y1973435D02*
X421765D01*
Y1975769D01*
X422140Y1976515D01*
X422640Y1976982D01*
X423640Y1977169D01*
X424640Y1976982D01*
X425265Y1976422D01*
X425640Y1975769D01*
Y1973435D01*
G01Y1975769D02*
X429265Y1977169D01*
G01Y1980749D02*
X421765D01*
G01Y1984295D02*
X426390Y1980749D01*
G01X429265Y1984855D02*
X424265Y1982335D01*
G01X429515Y1990302D02*
X429390Y1990115D01*
X429140D01*
X429015Y1990302D01*
X429140Y1990489D01*
X429390D01*
X429515Y1990302D01*
G01X426140D02*
X426015Y1990115D01*
X425765D01*
X425640Y1990302D01*
X425765Y1990489D01*
X426015D01*
X426140Y1990302D01*
G01X421765Y1997802D02*
X429265D01*
G01X421765Y1995655D02*
Y1999949D01*
G01Y2004182D02*
Y2006422D01*
G01Y2005302D02*
X429265D01*
G01Y2004182D02*
Y2006422D01*
G01Y2010655D02*
X421765D01*
X429265Y2014949D01*
X421765D01*
G01Y2025935D02*
X429265D01*
Y2029669D01*
G01Y2037169D02*
Y2033435D01*
X421765D01*
Y2037169D01*
G01X425390Y2035675D02*
Y2033435D01*
G01X429265Y2040469D02*
X421765Y2042802D01*
X429265Y2045135D01*
G01X426640Y2044295D02*
Y2041309D01*
G01X429265Y2048249D02*
X421765D01*
Y2050115D01*
X422140Y2050862D01*
X422640Y2051422D01*
X423390Y2051889D01*
X424265Y2052262D01*
X425515Y2052355D01*
X426765Y2052262D01*
X427640Y2051889D01*
X428390Y2051422D01*
X428890Y2050862D01*
X429265Y2050115D01*
Y2048249D01*
G01X429515Y2057802D02*
X429390Y2057615D01*
X429140D01*
X429015Y2057802D01*
X429140Y2057989D01*
X429390D01*
X429515Y2057802D01*
G01X426140D02*
X426015Y2057615D01*
X425765D01*
X425640Y2057802D01*
X425765Y2057989D01*
X426015D01*
X426140Y2057802D01*
G01X429265Y2063435D02*
X421765D01*
Y2065769D01*
X422140Y2066515D01*
X422640Y2066982D01*
X423640Y2067169D01*
X424640Y2066982D01*
X425265Y2066422D01*
X425640Y2065769D01*
Y2063435D01*
G01Y2065769D02*
X429265Y2067169D01*
G01Y2074669D02*
Y2070935D01*
X421765D01*
Y2074669D01*
G01X425390Y2073175D02*
Y2070935D01*
G01X422390Y2082355D02*
X422015Y2081795D01*
X421765Y2081142D01*
Y2080395D01*
X422140Y2079555D01*
X422765Y2078902D01*
X423515Y2078435D01*
X424765Y2078062D01*
X425890Y2077969D01*
X427015Y2078155D01*
X427765Y2078435D01*
X428515Y2078995D01*
X429015Y2079649D01*
X429265Y2080302D01*
Y2080955D01*
X429015Y2081609D01*
X428640Y2082169D01*
X428140Y2082635D01*
G01X429265Y2087802D02*
X429140Y2087055D01*
X428640Y2086402D01*
X427890Y2085842D01*
X427015Y2085469D01*
X426015Y2085282D01*
X425015D01*
X424015Y2085469D01*
X423140Y2085842D01*
X422390Y2086402D01*
X421890Y2087055D01*
X421765Y2087802D01*
X421890Y2088549D01*
X422390Y2089202D01*
X423140Y2089762D01*
X424015Y2090135D01*
X425015Y2090322D01*
X426015D01*
X427015Y2090135D01*
X427890Y2089762D01*
X428640Y2089202D01*
X429140Y2088549D01*
X429265Y2087802D01*
G01Y2092875D02*
X421765D01*
X428015Y2095302D01*
X421765Y2097729D01*
X429265D01*
G01Y2100375D02*
X421765D01*
X428015Y2102802D01*
X421765Y2105229D01*
X429265D01*
G01Y2112169D02*
Y2108435D01*
X421765D01*
Y2112169D01*
G01X425390Y2110675D02*
Y2108435D01*
G01X429265Y2115655D02*
X421765D01*
X429265Y2119949D01*
X421765D01*
G01X429265Y2123249D02*
X421765D01*
Y2125115D01*
X422140Y2125862D01*
X422640Y2126422D01*
X423390Y2126889D01*
X424265Y2127262D01*
X425515Y2127355D01*
X426765Y2127262D01*
X427640Y2126889D01*
X428390Y2126422D01*
X428890Y2125862D01*
X429265Y2125115D01*
Y2123249D01*
G01Y2134669D02*
Y2130935D01*
X421765D01*
Y2134669D01*
G01X425390Y2133175D02*
Y2130935D01*
G01X429265Y2138249D02*
X421765D01*
Y2140115D01*
X422140Y2140862D01*
X422640Y2141422D01*
X423390Y2141889D01*
X424265Y2142262D01*
X425515Y2142355D01*
X426765Y2142262D01*
X427640Y2141889D01*
X428390Y2141422D01*
X428890Y2140862D01*
X429265Y2140115D01*
Y2138249D01*
G01Y2153249D02*
X421765D01*
Y2155115D01*
X422140Y2155862D01*
X422640Y2156422D01*
X423390Y2156889D01*
X424265Y2157262D01*
X425515Y2157355D01*
X426765Y2157262D01*
X427640Y2156889D01*
X428390Y2156422D01*
X428890Y2155862D01*
X429265Y2155115D01*
Y2153249D01*
G01Y2160935D02*
X421765D01*
Y2163269D01*
X422140Y2164015D01*
X422640Y2164482D01*
X423640Y2164669D01*
X424640Y2164482D01*
X425265Y2163922D01*
X425640Y2163269D01*
Y2160935D01*
G01Y2163269D02*
X429265Y2164669D01*
G01X421765Y2169182D02*
Y2171422D01*
G01Y2170302D02*
X429265D01*
G01Y2169182D02*
Y2171422D01*
G01X421765Y2175935D02*
X429265D01*
Y2179669D01*
G01X421765Y2183435D02*
X429265D01*
Y2187169D01*
G01X428265Y2198342D02*
X428890Y2199089D01*
X429265Y2199929D01*
Y2200675D01*
X428890Y2201422D01*
X428265Y2201982D01*
X427390Y2202262D01*
X426515Y2202075D01*
X425765Y2201609D01*
X425265Y2200769D01*
X425015Y2199649D01*
X424515Y2198995D01*
X423640Y2198715D01*
X422765Y2198902D01*
X422140Y2199369D01*
X421765Y2200022D01*
Y2200675D01*
X422015Y2201329D01*
X422640Y2201889D01*
G01X421765Y2206682D02*
Y2208922D01*
G01Y2207802D02*
X429265D01*
G01Y2206682D02*
Y2208922D01*
G01X421765Y2213529D02*
Y2217075D01*
X429265Y2213529D01*
Y2217075D01*
G01Y2224669D02*
Y2220935D01*
X421765D01*
Y2224669D01*
G01X425390Y2223175D02*
Y2220935D01*
G01X429265Y2236029D02*
X421765D01*
Y2239575D01*
G01X425390Y2238269D02*
Y2236029D01*
G01X429265Y2245302D02*
X429140Y2244555D01*
X428640Y2243902D01*
X427890Y2243342D01*
X427015Y2242969D01*
X426015Y2242782D01*
X425015D01*
X424015Y2242969D01*
X423140Y2243342D01*
X422390Y2243902D01*
X421890Y2244555D01*
X421765Y2245302D01*
X421890Y2246049D01*
X422390Y2246702D01*
X423140Y2247262D01*
X424015Y2247635D01*
X425015Y2247822D01*
X426015D01*
X427015Y2247635D01*
X427890Y2247262D01*
X428640Y2246702D01*
X429140Y2246049D01*
X429265Y2245302D01*
G01Y2250935D02*
X421765D01*
Y2253269D01*
X422140Y2254015D01*
X422640Y2254482D01*
X423640Y2254669D01*
X424640Y2254482D01*
X425265Y2253922D01*
X425640Y2253269D01*
Y2250935D01*
G01Y2253269D02*
X429265Y2254669D01*
G01X421765Y2267802D02*
X422015Y2267055D01*
X422640Y2266495D01*
X423390Y2266122D01*
X424390Y2265842D01*
X425515Y2265749D01*
X426640Y2265842D01*
X427640Y2266122D01*
X428390Y2266495D01*
X429015Y2267055D01*
X429265Y2267802D01*
X429015Y2268549D01*
X428390Y2269109D01*
X427640Y2269482D01*
X426640Y2269762D01*
X425515Y2269855D01*
X424390Y2269762D01*
X423390Y2269482D01*
X422640Y2269109D01*
X422015Y2268549D01*
X421765Y2267802D01*
G01X429515Y2275302D02*
X429390Y2275115D01*
X429140D01*
X429015Y2275302D01*
X429140Y2275489D01*
X429390D01*
X429515Y2275302D01*
G01X427765Y2280749D02*
X428640Y2281309D01*
X429140Y2282055D01*
X429265Y2282895D01*
X429140Y2283642D01*
X428515Y2284389D01*
X427765Y2284855D01*
X427015Y2284949D01*
X426140Y2284762D01*
X425515Y2284109D01*
X425265Y2283455D01*
Y2282615D01*
G01Y2283455D02*
X424890Y2284015D01*
X424265Y2284482D01*
X423515Y2284669D01*
X422765Y2284482D01*
X422140Y2284015D01*
X421765Y2283175D01*
X421890Y2282335D01*
X422390Y2281495D01*
G01X426140Y2288529D02*
X425265Y2289182D01*
X424765Y2289742D01*
X424515Y2290489D01*
X424765Y2291142D01*
X425265Y2291609D01*
X426015Y2291982D01*
X426890Y2292075D01*
X427640Y2291982D01*
X428390Y2291609D01*
X429015Y2291049D01*
X429265Y2290395D01*
X429015Y2289649D01*
X428265Y2288995D01*
X427140Y2288622D01*
X425890Y2288529D01*
X424265Y2288715D01*
X423390Y2288995D01*
X422515Y2289462D01*
X421890Y2290115D01*
X421765Y2290769D01*
X422015Y2291422D01*
X422640Y2291889D01*
G01X429265Y2295375D02*
X421765D01*
X428015Y2297802D01*
X421765Y2300229D01*
X429265D01*
G01Y2302875D02*
X421765D01*
X428015Y2305302D01*
X421765Y2307729D01*
X429265D01*
G01Y2318529D02*
X421765D01*
Y2322075D01*
G01X425390Y2320769D02*
Y2318529D01*
G01X421765Y2326682D02*
Y2328922D01*
G01Y2327802D02*
X429265D01*
G01Y2326682D02*
Y2328922D01*
G01Y2333155D02*
X421765D01*
X429265Y2337449D01*
X421765D01*
G01Y2341682D02*
Y2343922D01*
G01Y2342802D02*
X429265D01*
G01Y2341682D02*
Y2343922D01*
G01X428265Y2348342D02*
X428890Y2349089D01*
X429265Y2349929D01*
Y2350675D01*
X428890Y2351422D01*
X428265Y2351982D01*
X427390Y2352262D01*
X426515Y2352075D01*
X425765Y2351609D01*
X425265Y2350769D01*
X425015Y2349649D01*
X424515Y2348995D01*
X423640Y2348715D01*
X422765Y2348902D01*
X422140Y2349369D01*
X421765Y2350022D01*
Y2350675D01*
X422015Y2351329D01*
X422640Y2351889D01*
G01X429265Y2355842D02*
X421765D01*
G01Y2359762D02*
X429265D01*
G01X425515D02*
Y2355842D01*
G01X429265Y2367169D02*
Y2363435D01*
X421765D01*
Y2367169D01*
G01X425390Y2365675D02*
Y2363435D01*
G01X429265Y2370749D02*
X421765D01*
Y2372615D01*
X422140Y2373362D01*
X422640Y2373922D01*
X423390Y2374389D01*
X424265Y2374762D01*
X425515Y2374855D01*
X426765Y2374762D01*
X427640Y2374389D01*
X428390Y2373922D01*
X428890Y2373362D01*
X429265Y2372615D01*
Y2370749D01*
G01Y2385935D02*
X421765D01*
Y2388175D01*
X422140Y2388922D01*
X423015Y2389482D01*
X424015Y2389669D01*
X425015Y2389482D01*
X425765Y2389015D01*
X426140Y2388175D01*
Y2385935D01*
G01X421765Y2395302D02*
X429265D01*
G01X421765Y2393155D02*
Y2397449D01*
G01X429265Y2400842D02*
X421765D01*
G01Y2404762D02*
X429265D01*
G01X425515D02*
Y2400842D01*
G01X421765Y2416682D02*
Y2418922D01*
G01Y2417802D02*
X429265D01*
G01Y2416682D02*
Y2418922D01*
G01X428265Y2423342D02*
X428890Y2424089D01*
X429265Y2424929D01*
Y2425675D01*
X428890Y2426422D01*
X428265Y2426982D01*
X427390Y2427262D01*
X426515Y2427075D01*
X425765Y2426609D01*
X425265Y2425769D01*
X425015Y2424649D01*
X424515Y2423995D01*
X423640Y2423715D01*
X422765Y2423902D01*
X422140Y2424369D01*
X421765Y2425022D01*
Y2425675D01*
X422015Y2426329D01*
X422640Y2426889D01*
G01X421765Y2440302D02*
X422015Y2439555D01*
X422640Y2438995D01*
X423390Y2438622D01*
X424390Y2438342D01*
X425515Y2438249D01*
X426640Y2438342D01*
X427640Y2438622D01*
X428390Y2438995D01*
X429015Y2439555D01*
X429265Y2440302D01*
X429015Y2441049D01*
X428390Y2441609D01*
X427640Y2441982D01*
X426640Y2442262D01*
X425515Y2442355D01*
X424390Y2442262D01*
X423390Y2441982D01*
X422640Y2441609D01*
X422015Y2441049D01*
X421765Y2440302D01*
G01X429515Y2447802D02*
X429390Y2447615D01*
X429140D01*
X429015Y2447802D01*
X429140Y2447989D01*
X429390D01*
X429515Y2447802D01*
G01X429265Y2456422D02*
X421765D01*
X427140Y2452969D01*
Y2457635D01*
G01X428140Y2460749D02*
X428765Y2461309D01*
X429140Y2461962D01*
X429265Y2462802D01*
X429015Y2463642D01*
X428515Y2464295D01*
X427640Y2464762D01*
X426640Y2464855D01*
X425640Y2464669D01*
X425015Y2464202D01*
X424515Y2463549D01*
X424390Y2462895D01*
X424515Y2462242D01*
X425015Y2461402D01*
X421765Y2461682D01*
Y2464202D01*
G01X429265Y2467875D02*
X421765D01*
X428015Y2470302D01*
X421765Y2472729D01*
X429265D01*
G01Y2475375D02*
X421765D01*
X428015Y2477802D01*
X421765Y2480229D01*
X429265D01*
G01Y2490375D02*
X421765D01*
X428015Y2492802D01*
X421765Y2495229D01*
X429265D01*
G01Y2502169D02*
Y2498435D01*
X421765D01*
Y2502169D01*
G01X425390Y2500675D02*
Y2498435D01*
G01X421765Y2507802D02*
X429265D01*
G01X421765Y2505655D02*
Y2509949D01*
G01X429265Y2513435D02*
X421765D01*
Y2515769D01*
X422140Y2516515D01*
X422640Y2516982D01*
X423640Y2517169D01*
X424640Y2516982D01*
X425265Y2516422D01*
X425640Y2515769D01*
Y2513435D01*
G01Y2515769D02*
X429265Y2517169D01*
G01X421765Y2521682D02*
Y2523922D01*
G01Y2522802D02*
X429265D01*
G01Y2521682D02*
Y2523922D01*
G01X422390Y2532355D02*
X422015Y2531795D01*
X421765Y2531142D01*
Y2530395D01*
X422140Y2529555D01*
X422765Y2528902D01*
X423515Y2528435D01*
X424765Y2528062D01*
X425890Y2527969D01*
X427015Y2528155D01*
X427765Y2528435D01*
X428515Y2528995D01*
X429015Y2529649D01*
X429265Y2530302D01*
Y2530955D01*
X429015Y2531609D01*
X428640Y2532169D01*
X428140Y2532635D01*
G01X429265Y2543249D02*
X421765D01*
Y2545115D01*
X422140Y2545862D01*
X422640Y2546422D01*
X423390Y2546889D01*
X424265Y2547262D01*
X425515Y2547355D01*
X426765Y2547262D01*
X427640Y2546889D01*
X428390Y2546422D01*
X428890Y2545862D01*
X429265Y2545115D01*
Y2543249D01*
G01Y2550935D02*
X421765D01*
Y2553269D01*
X422140Y2554015D01*
X422640Y2554482D01*
X423640Y2554669D01*
X424640Y2554482D01*
X425265Y2553922D01*
X425640Y2553269D01*
Y2550935D01*
G01Y2553269D02*
X429265Y2554669D01*
G01X421765Y2559182D02*
Y2561422D01*
G01Y2560302D02*
X429265D01*
G01Y2559182D02*
Y2561422D01*
G01X421765Y2565935D02*
X429265D01*
Y2569669D01*
G01X421765Y2573435D02*
X429265D01*
Y2577169D01*
G01X431765Y2582335D02*
X430515Y2581402D01*
X429265Y2580935D01*
X424265D01*
X423015Y2581402D01*
X421765Y2582335D01*
G01Y2590302D02*
X422015Y2589555D01*
X422640Y2588995D01*
X423390Y2588622D01*
X424390Y2588342D01*
X425515Y2588249D01*
X426640Y2588342D01*
X427640Y2588622D01*
X428390Y2588995D01*
X429015Y2589555D01*
X429265Y2590302D01*
X429015Y2591049D01*
X428390Y2591609D01*
X427640Y2591982D01*
X426640Y2592262D01*
X425515Y2592355D01*
X424390Y2592262D01*
X423390Y2591982D01*
X422640Y2591609D01*
X422015Y2591049D01*
X421765Y2590302D01*
G01X429515Y2597802D02*
X429390Y2597615D01*
X429140D01*
X429015Y2597802D01*
X429140Y2597989D01*
X429390D01*
X429515Y2597802D01*
G01X421765Y2605302D02*
X422015Y2604555D01*
X422640Y2603995D01*
X423390Y2603622D01*
X424390Y2603342D01*
X425515Y2603249D01*
X426640Y2603342D01*
X427640Y2603622D01*
X428390Y2603995D01*
X429015Y2604555D01*
X429265Y2605302D01*
X429015Y2606049D01*
X428390Y2606609D01*
X427640Y2606982D01*
X426640Y2607262D01*
X425515Y2607355D01*
X424390Y2607262D01*
X423390Y2606982D01*
X422640Y2606609D01*
X422015Y2606049D01*
X421765Y2605302D01*
G01X429265Y2612802D02*
X421765D01*
X423265Y2611682D01*
G01X429265D02*
Y2613922D01*
G01Y2620115D02*
X427640Y2620302D01*
X426265Y2620582D01*
X425015Y2620955D01*
X423640Y2621422D01*
X421765Y2622169D01*
Y2618435D01*
G01X429265Y2627615D02*
X427640Y2627802D01*
X426265Y2628082D01*
X425015Y2628455D01*
X423640Y2628922D01*
X421765Y2629669D01*
Y2625935D01*
G01X423390Y2634462D02*
X421765Y2634929D01*
G01Y2636142D02*
X423390Y2635675D01*
G01X431765Y2643269D02*
X430515Y2644202D01*
X429265Y2644669D01*
X424265D01*
X423015Y2644202D01*
X421765Y2643269D01*
G01X429515Y2650302D02*
X429390Y2650115D01*
X429140D01*
X429015Y2650302D01*
X429140Y2650489D01*
X429390D01*
X429515Y2650302D01*
G01X436190Y1962105D02*
X435815Y1961545D01*
X435565Y1960892D01*
Y1960145D01*
X435940Y1959305D01*
X436565Y1958652D01*
X437315Y1958185D01*
X438565Y1957812D01*
X439690Y1957719D01*
X440815Y1957905D01*
X441565Y1958185D01*
X442315Y1958745D01*
X442815Y1959399D01*
X443065Y1960052D01*
Y1960705D01*
X442815Y1961359D01*
X442440Y1961919D01*
X441940Y1962385D01*
G01X443065Y1967552D02*
X442940Y1966805D01*
X442440Y1966152D01*
X441690Y1965592D01*
X440815Y1965219D01*
X439815Y1965032D01*
X438815D01*
X437815Y1965219D01*
X436940Y1965592D01*
X436190Y1966152D01*
X435690Y1966805D01*
X435565Y1967552D01*
X435690Y1968299D01*
X436190Y1968952D01*
X436940Y1969512D01*
X437815Y1969885D01*
X438815Y1970072D01*
X439815D01*
X440815Y1969885D01*
X441690Y1969512D01*
X442440Y1968952D01*
X442940Y1968299D01*
X443065Y1967552D01*
G01Y1973185D02*
X435565D01*
Y1975425D01*
X435940Y1976172D01*
X436815Y1976732D01*
X437815Y1976919D01*
X438815Y1976732D01*
X439565Y1976265D01*
X439940Y1975425D01*
Y1973185D01*
G01X443065Y1980685D02*
X435565D01*
Y1982925D01*
X435940Y1983672D01*
X436815Y1984232D01*
X437815Y1984419D01*
X438815Y1984232D01*
X439565Y1983765D01*
X439940Y1982925D01*
Y1980685D01*
G01X443065Y1991919D02*
Y1988185D01*
X435565D01*
Y1991919D01*
G01X439190Y1990425D02*
Y1988185D01*
G01X443065Y1995685D02*
X435565D01*
Y1998019D01*
X435940Y1998765D01*
X436440Y1999232D01*
X437440Y1999419D01*
X438440Y1999232D01*
X439065Y1998672D01*
X439440Y1998019D01*
Y1995685D01*
G01Y1998019D02*
X443065Y1999419D01*
G01Y2012552D02*
X442940Y2011805D01*
X442440Y2011152D01*
X441690Y2010592D01*
X440815Y2010219D01*
X439815Y2010032D01*
X438815D01*
X437815Y2010219D01*
X436940Y2010592D01*
X436190Y2011152D01*
X435690Y2011805D01*
X435565Y2012552D01*
X435690Y2013299D01*
X436190Y2013952D01*
X436940Y2014512D01*
X437815Y2014885D01*
X438815Y2015072D01*
X439815D01*
X440815Y2014885D01*
X441690Y2014512D01*
X442440Y2013952D01*
X442940Y2013299D01*
X443065Y2012552D01*
G01X442065Y2018092D02*
X442690Y2018839D01*
X443065Y2019679D01*
Y2020425D01*
X442690Y2021172D01*
X442065Y2021732D01*
X441190Y2022012D01*
X440315Y2021825D01*
X439565Y2021359D01*
X439065Y2020519D01*
X438815Y2019399D01*
X438315Y2018745D01*
X437440Y2018465D01*
X436565Y2018652D01*
X435940Y2019119D01*
X435565Y2019772D01*
Y2020425D01*
X435815Y2021079D01*
X436440Y2021639D01*
G01X443065Y2025685D02*
X435565D01*
Y2027925D01*
X435940Y2028672D01*
X436815Y2029232D01*
X437815Y2029419D01*
X438815Y2029232D01*
X439565Y2028765D01*
X439940Y2027925D01*
Y2025685D01*
G01X443315Y2033372D02*
X435565Y2036732D01*
G01Y2042552D02*
X443065D01*
G01X435565Y2040405D02*
Y2044699D01*
G01Y2048932D02*
Y2051172D01*
G01Y2050052D02*
X443065D01*
G01Y2048932D02*
Y2051172D01*
G01Y2055405D02*
X435565D01*
X443065Y2059699D01*
X435565D01*
G01X445565Y2064585D02*
X444315Y2063652D01*
X443065Y2063185D01*
X438065D01*
X436815Y2063652D01*
X435565Y2064585D01*
G01Y2071432D02*
Y2073672D01*
G01Y2072552D02*
X443065D01*
G01Y2071432D02*
Y2073672D01*
G01Y2077625D02*
X435565D01*
X441815Y2080052D01*
X435565Y2082479D01*
X443065D01*
G01Y2085125D02*
X435565D01*
X441815Y2087552D01*
X435565Y2089979D01*
X443065D01*
G01Y2096919D02*
Y2093185D01*
X435565D01*
Y2096919D01*
G01X439190Y2095425D02*
Y2093185D01*
G01X443065Y2100685D02*
X435565D01*
Y2103019D01*
X435940Y2103765D01*
X436440Y2104232D01*
X437440Y2104419D01*
X438440Y2104232D01*
X439065Y2103672D01*
X439440Y2103019D01*
Y2100685D01*
G01Y2103019D02*
X443065Y2104419D01*
G01X442065Y2108092D02*
X442690Y2108839D01*
X443065Y2109679D01*
Y2110425D01*
X442690Y2111172D01*
X442065Y2111732D01*
X441190Y2112012D01*
X440315Y2111825D01*
X439565Y2111359D01*
X439065Y2110519D01*
X438815Y2109399D01*
X438315Y2108745D01*
X437440Y2108465D01*
X436565Y2108652D01*
X435940Y2109119D01*
X435565Y2109772D01*
Y2110425D01*
X435815Y2111079D01*
X436440Y2111639D01*
G01X435565Y2116432D02*
Y2118672D01*
G01Y2117552D02*
X443065D01*
G01Y2116432D02*
Y2118672D01*
G01Y2125052D02*
X442940Y2124305D01*
X442440Y2123652D01*
X441690Y2123092D01*
X440815Y2122719D01*
X439815Y2122532D01*
X438815D01*
X437815Y2122719D01*
X436940Y2123092D01*
X436190Y2123652D01*
X435690Y2124305D01*
X435565Y2125052D01*
X435690Y2125799D01*
X436190Y2126452D01*
X436940Y2127012D01*
X437815Y2127385D01*
X438815Y2127572D01*
X439815D01*
X440815Y2127385D01*
X441690Y2127012D01*
X442440Y2126452D01*
X442940Y2125799D01*
X443065Y2125052D01*
G01Y2130405D02*
X435565D01*
X443065Y2134699D01*
X435565D01*
G01X445565Y2140519D02*
X444315Y2141452D01*
X443065Y2141919D01*
X438065D01*
X436815Y2141452D01*
X435565Y2140519D01*
G01X443315Y2147552D02*
X443190Y2147365D01*
X442940D01*
X442815Y2147552D01*
X442940Y2147739D01*
X443190D01*
X443315Y2147552D01*
G01X439940D02*
X439815Y2147365D01*
X439565D01*
X439440Y2147552D01*
X439565Y2147739D01*
X439815D01*
X439940Y2147552D01*
G01X443065Y2153185D02*
X435565D01*
Y2155519D01*
X435940Y2156265D01*
X436440Y2156732D01*
X437440Y2156919D01*
X438440Y2156732D01*
X439065Y2156172D01*
X439440Y2155519D01*
Y2153185D01*
G01Y2155519D02*
X443065Y2156919D01*
G01Y2164419D02*
Y2160685D01*
X435565D01*
Y2164419D01*
G01X439190Y2162925D02*
Y2160685D01*
G01X436190Y2172105D02*
X435815Y2171545D01*
X435565Y2170892D01*
Y2170145D01*
X435940Y2169305D01*
X436565Y2168652D01*
X437315Y2168185D01*
X438565Y2167812D01*
X439690Y2167719D01*
X440815Y2167905D01*
X441565Y2168185D01*
X442315Y2168745D01*
X442815Y2169399D01*
X443065Y2170052D01*
Y2170705D01*
X442815Y2171359D01*
X442440Y2171919D01*
X441940Y2172385D01*
G01X443065Y2177552D02*
X442940Y2176805D01*
X442440Y2176152D01*
X441690Y2175592D01*
X440815Y2175219D01*
X439815Y2175032D01*
X438815D01*
X437815Y2175219D01*
X436940Y2175592D01*
X436190Y2176152D01*
X435690Y2176805D01*
X435565Y2177552D01*
X435690Y2178299D01*
X436190Y2178952D01*
X436940Y2179512D01*
X437815Y2179885D01*
X438815Y2180072D01*
X439815D01*
X440815Y2179885D01*
X441690Y2179512D01*
X442440Y2178952D01*
X442940Y2178299D01*
X443065Y2177552D01*
G01Y2182625D02*
X435565D01*
X441815Y2185052D01*
X435565Y2187479D01*
X443065D01*
G01Y2190125D02*
X435565D01*
X441815Y2192552D01*
X435565Y2194979D01*
X443065D01*
G01Y2201919D02*
Y2198185D01*
X435565D01*
Y2201919D01*
G01X439190Y2200425D02*
Y2198185D01*
G01X443065Y2205405D02*
X435565D01*
X443065Y2209699D01*
X435565D01*
G01X443065Y2212999D02*
X435565D01*
Y2214865D01*
X435940Y2215612D01*
X436440Y2216172D01*
X437190Y2216639D01*
X438065Y2217012D01*
X439315Y2217105D01*
X440565Y2217012D01*
X441440Y2216639D01*
X442190Y2216172D01*
X442690Y2215612D01*
X443065Y2214865D01*
Y2212999D01*
G01Y2224419D02*
Y2220685D01*
X435565D01*
Y2224419D01*
G01X439190Y2222925D02*
Y2220685D01*
G01X443065Y2227999D02*
X435565D01*
Y2229865D01*
X435940Y2230612D01*
X436440Y2231172D01*
X437190Y2231639D01*
X438065Y2232012D01*
X439315Y2232105D01*
X440565Y2232012D01*
X441440Y2231639D01*
X442190Y2231172D01*
X442690Y2230612D01*
X443065Y2229865D01*
Y2227999D01*
G01Y2242999D02*
X435565D01*
Y2244865D01*
X435940Y2245612D01*
X436440Y2246172D01*
X437190Y2246639D01*
X438065Y2247012D01*
X439315Y2247105D01*
X440565Y2247012D01*
X441440Y2246639D01*
X442190Y2246172D01*
X442690Y2245612D01*
X443065Y2244865D01*
Y2242999D01*
G01Y2250685D02*
X435565D01*
Y2253019D01*
X435940Y2253765D01*
X436440Y2254232D01*
X437440Y2254419D01*
X438440Y2254232D01*
X439065Y2253672D01*
X439440Y2253019D01*
Y2250685D01*
G01Y2253019D02*
X443065Y2254419D01*
G01X435565Y2258932D02*
Y2261172D01*
G01Y2260052D02*
X443065D01*
G01Y2258932D02*
Y2261172D01*
G01X435565Y2265685D02*
X443065D01*
Y2269419D01*
G01X435565Y2273185D02*
X443065D01*
Y2276919D01*
G01X442065Y2288092D02*
X442690Y2288839D01*
X443065Y2289679D01*
Y2290425D01*
X442690Y2291172D01*
X442065Y2291732D01*
X441190Y2292012D01*
X440315Y2291825D01*
X439565Y2291359D01*
X439065Y2290519D01*
X438815Y2289399D01*
X438315Y2288745D01*
X437440Y2288465D01*
X436565Y2288652D01*
X435940Y2289119D01*
X435565Y2289772D01*
Y2290425D01*
X435815Y2291079D01*
X436440Y2291639D01*
G01X435565Y2296432D02*
Y2298672D01*
G01Y2297552D02*
X443065D01*
G01Y2296432D02*
Y2298672D01*
G01X435565Y2303279D02*
Y2306825D01*
X443065Y2303279D01*
Y2306825D01*
G01Y2314419D02*
Y2310685D01*
X435565D01*
Y2314419D01*
G01X439190Y2312925D02*
Y2310685D01*
G01X443065Y2325779D02*
X435565D01*
Y2329325D01*
G01X439190Y2328019D02*
Y2325779D01*
G01X443065Y2335052D02*
X442940Y2334305D01*
X442440Y2333652D01*
X441690Y2333092D01*
X440815Y2332719D01*
X439815Y2332532D01*
X438815D01*
X437815Y2332719D01*
X436940Y2333092D01*
X436190Y2333652D01*
X435690Y2334305D01*
X435565Y2335052D01*
X435690Y2335799D01*
X436190Y2336452D01*
X436940Y2337012D01*
X437815Y2337385D01*
X438815Y2337572D01*
X439815D01*
X440815Y2337385D01*
X441690Y2337012D01*
X442440Y2336452D01*
X442940Y2335799D01*
X443065Y2335052D01*
G01Y2340685D02*
X435565D01*
Y2343019D01*
X435940Y2343765D01*
X436440Y2344232D01*
X437440Y2344419D01*
X438440Y2344232D01*
X439065Y2343672D01*
X439440Y2343019D01*
Y2340685D01*
G01Y2343019D02*
X443065Y2344419D01*
G01X435565Y2357552D02*
X435815Y2356805D01*
X436440Y2356245D01*
X437190Y2355872D01*
X438190Y2355592D01*
X439315Y2355499D01*
X440440Y2355592D01*
X441440Y2355872D01*
X442190Y2356245D01*
X442815Y2356805D01*
X443065Y2357552D01*
X442815Y2358299D01*
X442190Y2358859D01*
X441440Y2359232D01*
X440440Y2359512D01*
X439315Y2359605D01*
X438190Y2359512D01*
X437190Y2359232D01*
X436440Y2358859D01*
X435815Y2358299D01*
X435565Y2357552D01*
G01X443315Y2365052D02*
X443190Y2364865D01*
X442940D01*
X442815Y2365052D01*
X442940Y2365239D01*
X443190D01*
X443315Y2365052D01*
G01X441565Y2370499D02*
X442440Y2371059D01*
X442940Y2371805D01*
X443065Y2372645D01*
X442940Y2373392D01*
X442315Y2374139D01*
X441565Y2374605D01*
X440815Y2374699D01*
X439940Y2374512D01*
X439315Y2373859D01*
X439065Y2373205D01*
Y2372365D01*
G01Y2373205D02*
X438690Y2373765D01*
X438065Y2374232D01*
X437315Y2374419D01*
X436565Y2374232D01*
X435940Y2373765D01*
X435565Y2372925D01*
X435690Y2372085D01*
X436190Y2371245D01*
G01X439940Y2378279D02*
X439065Y2378932D01*
X438565Y2379492D01*
X438315Y2380239D01*
X438565Y2380892D01*
X439065Y2381359D01*
X439815Y2381732D01*
X440690Y2381825D01*
X441440Y2381732D01*
X442190Y2381359D01*
X442815Y2380799D01*
X443065Y2380145D01*
X442815Y2379399D01*
X442065Y2378745D01*
X440940Y2378372D01*
X439690Y2378279D01*
X438065Y2378465D01*
X437190Y2378745D01*
X436315Y2379212D01*
X435690Y2379865D01*
X435565Y2380519D01*
X435815Y2381172D01*
X436440Y2381639D01*
G01X443065Y2385125D02*
X435565D01*
X441815Y2387552D01*
X435565Y2389979D01*
X443065D01*
G01Y2392625D02*
X435565D01*
X441815Y2395052D01*
X435565Y2397479D01*
X443065D01*
G01Y2408279D02*
X435565D01*
Y2411825D01*
G01X439190Y2410519D02*
Y2408279D01*
G01X435565Y2416432D02*
Y2418672D01*
G01Y2417552D02*
X443065D01*
G01Y2416432D02*
Y2418672D01*
G01Y2422905D02*
X435565D01*
X443065Y2427199D01*
X435565D01*
G01Y2431432D02*
Y2433672D01*
G01Y2432552D02*
X443065D01*
G01Y2431432D02*
Y2433672D01*
G01X442065Y2438092D02*
X442690Y2438839D01*
X443065Y2439679D01*
Y2440425D01*
X442690Y2441172D01*
X442065Y2441732D01*
X441190Y2442012D01*
X440315Y2441825D01*
X439565Y2441359D01*
X439065Y2440519D01*
X438815Y2439399D01*
X438315Y2438745D01*
X437440Y2438465D01*
X436565Y2438652D01*
X435940Y2439119D01*
X435565Y2439772D01*
Y2440425D01*
X435815Y2441079D01*
X436440Y2441639D01*
G01X443065Y2445592D02*
X435565D01*
G01Y2449512D02*
X443065D01*
G01X439315D02*
Y2445592D01*
G01X443065Y2456919D02*
Y2453185D01*
X435565D01*
Y2456919D01*
G01X439190Y2455425D02*
Y2453185D01*
G01X443065Y2460499D02*
X435565D01*
Y2462365D01*
X435940Y2463112D01*
X436440Y2463672D01*
X437190Y2464139D01*
X438065Y2464512D01*
X439315Y2464605D01*
X440565Y2464512D01*
X441440Y2464139D01*
X442190Y2463672D01*
X442690Y2463112D01*
X443065Y2462365D01*
Y2460499D01*
G01Y2475685D02*
X435565D01*
Y2477925D01*
X435940Y2478672D01*
X436815Y2479232D01*
X437815Y2479419D01*
X438815Y2479232D01*
X439565Y2478765D01*
X439940Y2477925D01*
Y2475685D01*
G01X435565Y2485052D02*
X443065D01*
G01X435565Y2482905D02*
Y2487199D01*
G01X443065Y2490592D02*
X435565D01*
G01Y2494512D02*
X443065D01*
G01X439315D02*
Y2490592D01*
G01X435565Y2506432D02*
Y2508672D01*
G01Y2507552D02*
X443065D01*
G01Y2506432D02*
Y2508672D01*
G01X442065Y2513092D02*
X442690Y2513839D01*
X443065Y2514679D01*
Y2515425D01*
X442690Y2516172D01*
X442065Y2516732D01*
X441190Y2517012D01*
X440315Y2516825D01*
X439565Y2516359D01*
X439065Y2515519D01*
X438815Y2514399D01*
X438315Y2513745D01*
X437440Y2513465D01*
X436565Y2513652D01*
X435940Y2514119D01*
X435565Y2514772D01*
Y2515425D01*
X435815Y2516079D01*
X436440Y2516639D01*
G01X435565Y2530052D02*
X435815Y2529305D01*
X436440Y2528745D01*
X437190Y2528372D01*
X438190Y2528092D01*
X439315Y2527999D01*
X440440Y2528092D01*
X441440Y2528372D01*
X442190Y2528745D01*
X442815Y2529305D01*
X443065Y2530052D01*
X442815Y2530799D01*
X442190Y2531359D01*
X441440Y2531732D01*
X440440Y2532012D01*
X439315Y2532105D01*
X438190Y2532012D01*
X437190Y2531732D01*
X436440Y2531359D01*
X435815Y2530799D01*
X435565Y2530052D01*
G01X443315Y2537552D02*
X443190Y2537365D01*
X442940D01*
X442815Y2537552D01*
X442940Y2537739D01*
X443190D01*
X443315Y2537552D01*
G01X443065Y2546172D02*
X435565D01*
X440940Y2542719D01*
Y2547385D01*
G01X441940Y2550499D02*
X442565Y2551059D01*
X442940Y2551712D01*
X443065Y2552552D01*
X442815Y2553392D01*
X442315Y2554045D01*
X441440Y2554512D01*
X440440Y2554605D01*
X439440Y2554419D01*
X438815Y2553952D01*
X438315Y2553299D01*
X438190Y2552645D01*
X438315Y2551992D01*
X438815Y2551152D01*
X435565Y2551432D01*
Y2553952D01*
G01X443065Y2557625D02*
X435565D01*
X441815Y2560052D01*
X435565Y2562479D01*
X443065D01*
G01Y2565125D02*
X435565D01*
X441815Y2567552D01*
X435565Y2569979D01*
X443065D01*
G01Y2580125D02*
X435565D01*
X441815Y2582552D01*
X435565Y2584979D01*
X443065D01*
G01Y2591919D02*
Y2588185D01*
X435565D01*
Y2591919D01*
G01X439190Y2590425D02*
Y2588185D01*
G01X435565Y2597552D02*
X443065D01*
G01X435565Y2595405D02*
Y2599699D01*
G01X443065Y2603185D02*
X435565D01*
Y2605519D01*
X435940Y2606265D01*
X436440Y2606732D01*
X437440Y2606919D01*
X438440Y2606732D01*
X439065Y2606172D01*
X439440Y2605519D01*
Y2603185D01*
G01Y2605519D02*
X443065Y2606919D01*
G01X435565Y2611432D02*
Y2613672D01*
G01Y2612552D02*
X443065D01*
G01Y2611432D02*
Y2613672D01*
G01X436190Y2622105D02*
X435815Y2621545D01*
X435565Y2620892D01*
Y2620145D01*
X435940Y2619305D01*
X436565Y2618652D01*
X437315Y2618185D01*
X438565Y2617812D01*
X439690Y2617719D01*
X440815Y2617905D01*
X441565Y2618185D01*
X442315Y2618745D01*
X442815Y2619399D01*
X443065Y2620052D01*
Y2620705D01*
X442815Y2621359D01*
X442440Y2621919D01*
X441940Y2622385D01*
G01X443065Y2632999D02*
X435565D01*
Y2634865D01*
X435940Y2635612D01*
X436440Y2636172D01*
X437190Y2636639D01*
X438065Y2637012D01*
X439315Y2637105D01*
X440565Y2637012D01*
X441440Y2636639D01*
X442190Y2636172D01*
X442690Y2635612D01*
X443065Y2634865D01*
Y2632999D01*
G01Y2640685D02*
X435565D01*
Y2643019D01*
X435940Y2643765D01*
X436440Y2644232D01*
X437440Y2644419D01*
X438440Y2644232D01*
X439065Y2643672D01*
X439440Y2643019D01*
Y2640685D01*
G01Y2643019D02*
X443065Y2644419D01*
G01X435565Y2648932D02*
Y2651172D01*
G01Y2650052D02*
X443065D01*
G01Y2648932D02*
Y2651172D01*
G01X435565Y2655685D02*
X443065D01*
Y2659419D01*
G01X435565Y2663185D02*
X443065D01*
Y2666919D01*
G01X445565Y2672085D02*
X444315Y2671152D01*
X443065Y2670685D01*
X438065D01*
X436815Y2671152D01*
X435565Y2672085D01*
G01Y2680052D02*
X435815Y2679305D01*
X436440Y2678745D01*
X437190Y2678372D01*
X438190Y2678092D01*
X439315Y2677999D01*
X440440Y2678092D01*
X441440Y2678372D01*
X442190Y2678745D01*
X442815Y2679305D01*
X443065Y2680052D01*
X442815Y2680799D01*
X442190Y2681359D01*
X441440Y2681732D01*
X440440Y2682012D01*
X439315Y2682105D01*
X438190Y2682012D01*
X437190Y2681732D01*
X436440Y2681359D01*
X435815Y2680799D01*
X435565Y2680052D01*
G01X443315Y2687552D02*
X443190Y2687365D01*
X442940D01*
X442815Y2687552D01*
X442940Y2687739D01*
X443190D01*
X443315Y2687552D01*
G01X435565Y2695052D02*
X435815Y2694305D01*
X436440Y2693745D01*
X437190Y2693372D01*
X438190Y2693092D01*
X439315Y2692999D01*
X440440Y2693092D01*
X441440Y2693372D01*
X442190Y2693745D01*
X442815Y2694305D01*
X443065Y2695052D01*
X442815Y2695799D01*
X442190Y2696359D01*
X441440Y2696732D01*
X440440Y2697012D01*
X439315Y2697105D01*
X438190Y2697012D01*
X437190Y2696732D01*
X436440Y2696359D01*
X435815Y2695799D01*
X435565Y2695052D01*
G01X443065Y2702552D02*
X435565D01*
X437065Y2701432D01*
G01X443065D02*
Y2703672D01*
G01Y2709865D02*
X441440Y2710052D01*
X440065Y2710332D01*
X438815Y2710705D01*
X437440Y2711172D01*
X435565Y2711919D01*
Y2708185D01*
G01X443065Y2717365D02*
X441440Y2717552D01*
X440065Y2717832D01*
X438815Y2718205D01*
X437440Y2718672D01*
X435565Y2719419D01*
Y2715685D01*
G01X437190Y2724212D02*
X435565Y2724679D01*
G01Y2725892D02*
X437190Y2725425D01*
G01X445565Y2733019D02*
X444315Y2733952D01*
X443065Y2734419D01*
X438065D01*
X436815Y2733952D01*
X435565Y2733019D01*
G01X443315Y2740052D02*
X443190Y2739865D01*
X442940D01*
X442815Y2740052D01*
X442940Y2740239D01*
X443190D01*
X443315Y2740052D01*
G01X462700Y-388290D02*
X450200D01*
X459158Y-394025D01*
Y-386275D01*
G01X452283Y-380695D02*
X451034Y-379765D01*
X450408Y-378680D01*
X450200Y-377440D01*
X450617Y-375890D01*
X451658Y-374805D01*
X452908Y-374495D01*
X454159Y-374650D01*
X455200Y-375270D01*
X457283Y-378370D01*
X458742Y-379765D01*
X460825Y-380695D01*
X462700Y-381005D01*
Y-374495D01*
G01X450200Y-365350D02*
X450617Y-366590D01*
X451658Y-367520D01*
X452908Y-368140D01*
X454575Y-368605D01*
X456450Y-368760D01*
X458325Y-368605D01*
X459992Y-368140D01*
X461242Y-367520D01*
X462283Y-366590D01*
X462700Y-365350D01*
X462283Y-364110D01*
X461242Y-363180D01*
X459992Y-362560D01*
X458325Y-362095D01*
X456450Y-361940D01*
X454575Y-362095D01*
X452908Y-362560D01*
X451658Y-363180D01*
X450617Y-364110D01*
X450200Y-365350D01*
G01X462700Y-352950D02*
X450200D01*
X452700Y-354810D01*
G01X462700D02*
Y-351090D01*
G01X463117Y-340550D02*
X462908Y-340860D01*
X462492D01*
X462283Y-340550D01*
X462492Y-340240D01*
X462908D01*
X463117Y-340550D01*
G01X452283Y-331095D02*
X451034Y-330165D01*
X450408Y-329080D01*
X450200Y-327840D01*
X450617Y-326290D01*
X451658Y-325205D01*
X452908Y-324895D01*
X454159Y-325050D01*
X455200Y-325670D01*
X457283Y-328770D01*
X458742Y-330165D01*
X460825Y-331095D01*
X462700Y-331405D01*
Y-324895D01*
G01X460825Y-319160D02*
X461867Y-318230D01*
X462492Y-317145D01*
X462700Y-315750D01*
X462283Y-314355D01*
X461450Y-313270D01*
X459992Y-312495D01*
X458325Y-312340D01*
X456658Y-312650D01*
X455617Y-313425D01*
X454783Y-314510D01*
X454575Y-315595D01*
X454783Y-316680D01*
X455617Y-318075D01*
X450200Y-317610D01*
Y-313425D01*
G01X462700Y-281150D02*
X450200D01*
X452700Y-283010D01*
G01X462700D02*
Y-279290D01*
G01X450200Y-268750D02*
X450617Y-269990D01*
X451658Y-270920D01*
X452908Y-271540D01*
X454575Y-272005D01*
X456450Y-272160D01*
X458325Y-272005D01*
X459992Y-271540D01*
X461242Y-270920D01*
X462283Y-269990D01*
X462700Y-268750D01*
X462283Y-267510D01*
X461242Y-266580D01*
X459992Y-265960D01*
X458325Y-265495D01*
X456450Y-265340D01*
X454575Y-265495D01*
X452908Y-265960D01*
X451658Y-266580D01*
X450617Y-267510D01*
X450200Y-268750D01*
G01X457492Y-259295D02*
X456033Y-258210D01*
X455200Y-257280D01*
X454783Y-256040D01*
X455200Y-254955D01*
X456033Y-254180D01*
X457283Y-253560D01*
X458742Y-253405D01*
X459992Y-253560D01*
X461242Y-254180D01*
X462283Y-255110D01*
X462700Y-256195D01*
X462283Y-257435D01*
X461034Y-258520D01*
X459158Y-259140D01*
X457075Y-259295D01*
X454367Y-258985D01*
X452908Y-258520D01*
X451450Y-257745D01*
X450408Y-256660D01*
X450200Y-255575D01*
X450617Y-254490D01*
X451658Y-253715D01*
G01X463117Y-243950D02*
X462908Y-244260D01*
X462492D01*
X462283Y-243950D01*
X462492Y-243640D01*
X462908D01*
X463117Y-243950D01*
G01X462700Y-231860D02*
X459992Y-231550D01*
X457700Y-231085D01*
X455617Y-230465D01*
X453325Y-229690D01*
X450200Y-228450D01*
Y-234650D01*
G01X462700Y-219150D02*
X450200D01*
X452700Y-221010D01*
G01X462700D02*
Y-217290D01*
G01X454045Y1956920D02*
X454670Y1957667D01*
X455045Y1958507D01*
Y1959253D01*
X454670Y1960000D01*
X454045Y1960560D01*
X453170Y1960840D01*
X452295Y1960653D01*
X451545Y1960187D01*
X451045Y1959347D01*
X450795Y1958227D01*
X450295Y1957573D01*
X449420Y1957293D01*
X448545Y1957480D01*
X447920Y1957947D01*
X447545Y1958600D01*
Y1959253D01*
X447795Y1959907D01*
X448420Y1960467D01*
G01X447545Y1965260D02*
Y1967500D01*
G01Y1966380D02*
X455045D01*
G01Y1965260D02*
Y1967500D01*
G01X447545Y1972013D02*
X455045D01*
Y1975747D01*
G01X447545Y1979047D02*
X455045Y1981380D01*
X447545Y1983713D01*
G01X455045Y1990747D02*
Y1987013D01*
X447545D01*
Y1990747D01*
G01X451170Y1989253D02*
Y1987013D01*
G01X455045Y1994513D02*
X447545D01*
Y1996847D01*
X447920Y1997593D01*
X448420Y1998060D01*
X449420Y1998247D01*
X450420Y1998060D01*
X451045Y1997500D01*
X451420Y1996847D01*
Y1994513D01*
G01Y1996847D02*
X455045Y1998247D01*
G01X457545Y2003413D02*
X456295Y2002480D01*
X455045Y2002013D01*
X450045D01*
X448795Y2002480D01*
X447545Y2003413D01*
G01Y2010260D02*
Y2012500D01*
G01Y2011380D02*
X455045D01*
G01Y2010260D02*
Y2012500D01*
G01Y2016453D02*
X447545D01*
X453795Y2018880D01*
X447545Y2021307D01*
X455045D01*
G01Y2023953D02*
X447545D01*
X453795Y2026380D01*
X447545Y2028807D01*
X455045D01*
G01Y2035747D02*
Y2032013D01*
X447545D01*
Y2035747D01*
G01X451170Y2034253D02*
Y2032013D01*
G01X455045Y2039513D02*
X447545D01*
Y2041847D01*
X447920Y2042593D01*
X448420Y2043060D01*
X449420Y2043247D01*
X450420Y2043060D01*
X451045Y2042500D01*
X451420Y2041847D01*
Y2039513D01*
G01Y2041847D02*
X455045Y2043247D01*
G01X454045Y2046920D02*
X454670Y2047667D01*
X455045Y2048507D01*
Y2049253D01*
X454670Y2050000D01*
X454045Y2050560D01*
X453170Y2050840D01*
X452295Y2050653D01*
X451545Y2050187D01*
X451045Y2049347D01*
X450795Y2048227D01*
X450295Y2047573D01*
X449420Y2047293D01*
X448545Y2047480D01*
X447920Y2047947D01*
X447545Y2048600D01*
Y2049253D01*
X447795Y2049907D01*
X448420Y2050467D01*
G01X447545Y2055260D02*
Y2057500D01*
G01Y2056380D02*
X455045D01*
G01Y2055260D02*
Y2057500D01*
G01Y2063880D02*
X454920Y2063133D01*
X454420Y2062480D01*
X453670Y2061920D01*
X452795Y2061547D01*
X451795Y2061360D01*
X450795D01*
X449795Y2061547D01*
X448920Y2061920D01*
X448170Y2062480D01*
X447670Y2063133D01*
X447545Y2063880D01*
X447670Y2064627D01*
X448170Y2065280D01*
X448920Y2065840D01*
X449795Y2066213D01*
X450795Y2066400D01*
X451795D01*
X452795Y2066213D01*
X453670Y2065840D01*
X454420Y2065280D01*
X454920Y2064627D01*
X455045Y2063880D01*
G01Y2069233D02*
X447545D01*
X455045Y2073527D01*
X447545D01*
G01X457545Y2079347D02*
X456295Y2080280D01*
X455045Y2080747D01*
X450045D01*
X448795Y2080280D01*
X447545Y2079347D01*
G01X455295Y2086380D02*
X455170Y2086193D01*
X454920D01*
X454795Y2086380D01*
X454920Y2086567D01*
X455170D01*
X455295Y2086380D01*
G01X451920D02*
X451795Y2086193D01*
X451545D01*
X451420Y2086380D01*
X451545Y2086567D01*
X451795D01*
X451920Y2086380D01*
G01X455045Y2092013D02*
X447545D01*
Y2094347D01*
X447920Y2095093D01*
X448420Y2095560D01*
X449420Y2095747D01*
X450420Y2095560D01*
X451045Y2095000D01*
X451420Y2094347D01*
Y2092013D01*
G01Y2094347D02*
X455045Y2095747D01*
G01Y2103247D02*
Y2099513D01*
X447545D01*
Y2103247D01*
G01X451170Y2101753D02*
Y2099513D01*
G01X448170Y2110933D02*
X447795Y2110373D01*
X447545Y2109720D01*
Y2108973D01*
X447920Y2108133D01*
X448545Y2107480D01*
X449295Y2107013D01*
X450545Y2106640D01*
X451670Y2106547D01*
X452795Y2106733D01*
X453545Y2107013D01*
X454295Y2107573D01*
X454795Y2108227D01*
X455045Y2108880D01*
Y2109533D01*
X454795Y2110187D01*
X454420Y2110747D01*
X453920Y2111213D01*
G01X455045Y2116380D02*
X454920Y2115633D01*
X454420Y2114980D01*
X453670Y2114420D01*
X452795Y2114047D01*
X451795Y2113860D01*
X450795D01*
X449795Y2114047D01*
X448920Y2114420D01*
X448170Y2114980D01*
X447670Y2115633D01*
X447545Y2116380D01*
X447670Y2117127D01*
X448170Y2117780D01*
X448920Y2118340D01*
X449795Y2118713D01*
X450795Y2118900D01*
X451795D01*
X452795Y2118713D01*
X453670Y2118340D01*
X454420Y2117780D01*
X454920Y2117127D01*
X455045Y2116380D01*
G01Y2121453D02*
X447545D01*
X453795Y2123880D01*
X447545Y2126307D01*
X455045D01*
G01Y2128953D02*
X447545D01*
X453795Y2131380D01*
X447545Y2133807D01*
X455045D01*
G01Y2140747D02*
Y2137013D01*
X447545D01*
Y2140747D01*
G01X451170Y2139253D02*
Y2137013D01*
G01X455045Y2144233D02*
X447545D01*
X455045Y2148527D01*
X447545D01*
G01X455045Y2151827D02*
X447545D01*
Y2153693D01*
X447920Y2154440D01*
X448420Y2155000D01*
X449170Y2155467D01*
X450045Y2155840D01*
X451295Y2155933D01*
X452545Y2155840D01*
X453420Y2155467D01*
X454170Y2155000D01*
X454670Y2154440D01*
X455045Y2153693D01*
Y2151827D01*
G01Y2163247D02*
Y2159513D01*
X447545D01*
Y2163247D01*
G01X451170Y2161753D02*
Y2159513D01*
G01X455045Y2166827D02*
X447545D01*
Y2168693D01*
X447920Y2169440D01*
X448420Y2170000D01*
X449170Y2170467D01*
X450045Y2170840D01*
X451295Y2170933D01*
X452545Y2170840D01*
X453420Y2170467D01*
X454170Y2170000D01*
X454670Y2169440D01*
X455045Y2168693D01*
Y2166827D01*
G01Y2181827D02*
X447545D01*
Y2183693D01*
X447920Y2184440D01*
X448420Y2185000D01*
X449170Y2185467D01*
X450045Y2185840D01*
X451295Y2185933D01*
X452545Y2185840D01*
X453420Y2185467D01*
X454170Y2185000D01*
X454670Y2184440D01*
X455045Y2183693D01*
Y2181827D01*
G01Y2189513D02*
X447545D01*
Y2191847D01*
X447920Y2192593D01*
X448420Y2193060D01*
X449420Y2193247D01*
X450420Y2193060D01*
X451045Y2192500D01*
X451420Y2191847D01*
Y2189513D01*
G01Y2191847D02*
X455045Y2193247D01*
G01X447545Y2197760D02*
Y2200000D01*
G01Y2198880D02*
X455045D01*
G01Y2197760D02*
Y2200000D01*
G01X447545Y2204513D02*
X455045D01*
Y2208247D01*
G01X447545Y2212013D02*
X455045D01*
Y2215747D01*
G01X454045Y2226920D02*
X454670Y2227667D01*
X455045Y2228507D01*
Y2229253D01*
X454670Y2230000D01*
X454045Y2230560D01*
X453170Y2230840D01*
X452295Y2230653D01*
X451545Y2230187D01*
X451045Y2229347D01*
X450795Y2228227D01*
X450295Y2227573D01*
X449420Y2227293D01*
X448545Y2227480D01*
X447920Y2227947D01*
X447545Y2228600D01*
Y2229253D01*
X447795Y2229907D01*
X448420Y2230467D01*
G01X447545Y2235260D02*
Y2237500D01*
G01Y2236380D02*
X455045D01*
G01Y2235260D02*
Y2237500D01*
G01X447545Y2242107D02*
Y2245653D01*
X455045Y2242107D01*
Y2245653D01*
G01Y2253247D02*
Y2249513D01*
X447545D01*
Y2253247D01*
G01X451170Y2251753D02*
Y2249513D01*
G01X455045Y2264607D02*
X447545D01*
Y2268153D01*
G01X451170Y2266847D02*
Y2264607D01*
G01X455045Y2273880D02*
X454920Y2273133D01*
X454420Y2272480D01*
X453670Y2271920D01*
X452795Y2271547D01*
X451795Y2271360D01*
X450795D01*
X449795Y2271547D01*
X448920Y2271920D01*
X448170Y2272480D01*
X447670Y2273133D01*
X447545Y2273880D01*
X447670Y2274627D01*
X448170Y2275280D01*
X448920Y2275840D01*
X449795Y2276213D01*
X450795Y2276400D01*
X451795D01*
X452795Y2276213D01*
X453670Y2275840D01*
X454420Y2275280D01*
X454920Y2274627D01*
X455045Y2273880D01*
G01Y2279513D02*
X447545D01*
Y2281847D01*
X447920Y2282593D01*
X448420Y2283060D01*
X449420Y2283247D01*
X450420Y2283060D01*
X451045Y2282500D01*
X451420Y2281847D01*
Y2279513D01*
G01Y2281847D02*
X455045Y2283247D01*
G01X447545Y2296380D02*
X447795Y2295633D01*
X448420Y2295073D01*
X449170Y2294700D01*
X450170Y2294420D01*
X451295Y2294327D01*
X452420Y2294420D01*
X453420Y2294700D01*
X454170Y2295073D01*
X454795Y2295633D01*
X455045Y2296380D01*
X454795Y2297127D01*
X454170Y2297687D01*
X453420Y2298060D01*
X452420Y2298340D01*
X451295Y2298433D01*
X450170Y2298340D01*
X449170Y2298060D01*
X448420Y2297687D01*
X447795Y2297127D01*
X447545Y2296380D01*
G01X455295Y2303880D02*
X455170Y2303693D01*
X454920D01*
X454795Y2303880D01*
X454920Y2304067D01*
X455170D01*
X455295Y2303880D01*
G01X453545Y2309327D02*
X454420Y2309887D01*
X454920Y2310633D01*
X455045Y2311473D01*
X454920Y2312220D01*
X454295Y2312967D01*
X453545Y2313433D01*
X452795Y2313527D01*
X451920Y2313340D01*
X451295Y2312687D01*
X451045Y2312033D01*
Y2311193D01*
G01Y2312033D02*
X450670Y2312593D01*
X450045Y2313060D01*
X449295Y2313247D01*
X448545Y2313060D01*
X447920Y2312593D01*
X447545Y2311753D01*
X447670Y2310913D01*
X448170Y2310073D01*
G01X451920Y2317107D02*
X451045Y2317760D01*
X450545Y2318320D01*
X450295Y2319067D01*
X450545Y2319720D01*
X451045Y2320187D01*
X451795Y2320560D01*
X452670Y2320653D01*
X453420Y2320560D01*
X454170Y2320187D01*
X454795Y2319627D01*
X455045Y2318973D01*
X454795Y2318227D01*
X454045Y2317573D01*
X452920Y2317200D01*
X451670Y2317107D01*
X450045Y2317293D01*
X449170Y2317573D01*
X448295Y2318040D01*
X447670Y2318693D01*
X447545Y2319347D01*
X447795Y2320000D01*
X448420Y2320467D01*
G01X455045Y2323953D02*
X447545D01*
X453795Y2326380D01*
X447545Y2328807D01*
X455045D01*
G01Y2331453D02*
X447545D01*
X453795Y2333880D01*
X447545Y2336307D01*
X455045D01*
G01Y2347107D02*
X447545D01*
Y2350653D01*
G01X451170Y2349347D02*
Y2347107D01*
G01X447545Y2355260D02*
Y2357500D01*
G01Y2356380D02*
X455045D01*
G01Y2355260D02*
Y2357500D01*
G01Y2361733D02*
X447545D01*
X455045Y2366027D01*
X447545D01*
G01Y2370260D02*
Y2372500D01*
G01Y2371380D02*
X455045D01*
G01Y2370260D02*
Y2372500D01*
G01X454045Y2376920D02*
X454670Y2377667D01*
X455045Y2378507D01*
Y2379253D01*
X454670Y2380000D01*
X454045Y2380560D01*
X453170Y2380840D01*
X452295Y2380653D01*
X451545Y2380187D01*
X451045Y2379347D01*
X450795Y2378227D01*
X450295Y2377573D01*
X449420Y2377293D01*
X448545Y2377480D01*
X447920Y2377947D01*
X447545Y2378600D01*
Y2379253D01*
X447795Y2379907D01*
X448420Y2380467D01*
G01X455045Y2384420D02*
X447545D01*
G01Y2388340D02*
X455045D01*
G01X451295D02*
Y2384420D01*
G01X455045Y2395747D02*
Y2392013D01*
X447545D01*
Y2395747D01*
G01X451170Y2394253D02*
Y2392013D01*
G01X455045Y2399327D02*
X447545D01*
Y2401193D01*
X447920Y2401940D01*
X448420Y2402500D01*
X449170Y2402967D01*
X450045Y2403340D01*
X451295Y2403433D01*
X452545Y2403340D01*
X453420Y2402967D01*
X454170Y2402500D01*
X454670Y2401940D01*
X455045Y2401193D01*
Y2399327D01*
G01Y2414513D02*
X447545D01*
Y2416753D01*
X447920Y2417500D01*
X448795Y2418060D01*
X449795Y2418247D01*
X450795Y2418060D01*
X451545Y2417593D01*
X451920Y2416753D01*
Y2414513D01*
G01X447545Y2423880D02*
X455045D01*
G01X447545Y2421733D02*
Y2426027D01*
G01X455045Y2429420D02*
X447545D01*
G01Y2433340D02*
X455045D01*
G01X451295D02*
Y2429420D01*
G01X447545Y2445260D02*
Y2447500D01*
G01Y2446380D02*
X455045D01*
G01Y2445260D02*
Y2447500D01*
G01X454045Y2451920D02*
X454670Y2452667D01*
X455045Y2453507D01*
Y2454253D01*
X454670Y2455000D01*
X454045Y2455560D01*
X453170Y2455840D01*
X452295Y2455653D01*
X451545Y2455187D01*
X451045Y2454347D01*
X450795Y2453227D01*
X450295Y2452573D01*
X449420Y2452293D01*
X448545Y2452480D01*
X447920Y2452947D01*
X447545Y2453600D01*
Y2454253D01*
X447795Y2454907D01*
X448420Y2455467D01*
G01X447545Y2468880D02*
X447795Y2468133D01*
X448420Y2467573D01*
X449170Y2467200D01*
X450170Y2466920D01*
X451295Y2466827D01*
X452420Y2466920D01*
X453420Y2467200D01*
X454170Y2467573D01*
X454795Y2468133D01*
X455045Y2468880D01*
X454795Y2469627D01*
X454170Y2470187D01*
X453420Y2470560D01*
X452420Y2470840D01*
X451295Y2470933D01*
X450170Y2470840D01*
X449170Y2470560D01*
X448420Y2470187D01*
X447795Y2469627D01*
X447545Y2468880D01*
G01X455295Y2476380D02*
X455170Y2476193D01*
X454920D01*
X454795Y2476380D01*
X454920Y2476567D01*
X455170D01*
X455295Y2476380D01*
G01X455045Y2485000D02*
X447545D01*
X452920Y2481547D01*
Y2486213D01*
G01X453920Y2489327D02*
X454545Y2489887D01*
X454920Y2490540D01*
X455045Y2491380D01*
X454795Y2492220D01*
X454295Y2492873D01*
X453420Y2493340D01*
X452420Y2493433D01*
X451420Y2493247D01*
X450795Y2492780D01*
X450295Y2492127D01*
X450170Y2491473D01*
X450295Y2490820D01*
X450795Y2489980D01*
X447545Y2490260D01*
Y2492780D01*
G01X455045Y2496453D02*
X447545D01*
X453795Y2498880D01*
X447545Y2501307D01*
X455045D01*
G01Y2503953D02*
X447545D01*
X453795Y2506380D01*
X447545Y2508807D01*
X455045D01*
G01Y2518953D02*
X447545D01*
X453795Y2521380D01*
X447545Y2523807D01*
X455045D01*
G01Y2530747D02*
Y2527013D01*
X447545D01*
Y2530747D01*
G01X451170Y2529253D02*
Y2527013D01*
G01X447545Y2536380D02*
X455045D01*
G01X447545Y2534233D02*
Y2538527D01*
G01X455045Y2542013D02*
X447545D01*
Y2544347D01*
X447920Y2545093D01*
X448420Y2545560D01*
X449420Y2545747D01*
X450420Y2545560D01*
X451045Y2545000D01*
X451420Y2544347D01*
Y2542013D01*
G01Y2544347D02*
X455045Y2545747D01*
G01X447545Y2550260D02*
Y2552500D01*
G01Y2551380D02*
X455045D01*
G01Y2550260D02*
Y2552500D01*
G01X448170Y2560933D02*
X447795Y2560373D01*
X447545Y2559720D01*
Y2558973D01*
X447920Y2558133D01*
X448545Y2557480D01*
X449295Y2557013D01*
X450545Y2556640D01*
X451670Y2556547D01*
X452795Y2556733D01*
X453545Y2557013D01*
X454295Y2557573D01*
X454795Y2558227D01*
X455045Y2558880D01*
Y2559533D01*
X454795Y2560187D01*
X454420Y2560747D01*
X453920Y2561213D01*
G01X455045Y2571827D02*
X447545D01*
Y2573693D01*
X447920Y2574440D01*
X448420Y2575000D01*
X449170Y2575467D01*
X450045Y2575840D01*
X451295Y2575933D01*
X452545Y2575840D01*
X453420Y2575467D01*
X454170Y2575000D01*
X454670Y2574440D01*
X455045Y2573693D01*
Y2571827D01*
G01Y2579513D02*
X447545D01*
Y2581847D01*
X447920Y2582593D01*
X448420Y2583060D01*
X449420Y2583247D01*
X450420Y2583060D01*
X451045Y2582500D01*
X451420Y2581847D01*
Y2579513D01*
G01Y2581847D02*
X455045Y2583247D01*
G01X447545Y2587760D02*
Y2590000D01*
G01Y2588880D02*
X455045D01*
G01Y2587760D02*
Y2590000D01*
G01X447545Y2594513D02*
X455045D01*
Y2598247D01*
G01X447545Y2602013D02*
X455045D01*
Y2605747D01*
G01X457545Y2610913D02*
X456295Y2609980D01*
X455045Y2609513D01*
X450045D01*
X448795Y2609980D01*
X447545Y2610913D01*
G01Y2618880D02*
X447795Y2618133D01*
X448420Y2617573D01*
X449170Y2617200D01*
X450170Y2616920D01*
X451295Y2616827D01*
X452420Y2616920D01*
X453420Y2617200D01*
X454170Y2617573D01*
X454795Y2618133D01*
X455045Y2618880D01*
X454795Y2619627D01*
X454170Y2620187D01*
X453420Y2620560D01*
X452420Y2620840D01*
X451295Y2620933D01*
X450170Y2620840D01*
X449170Y2620560D01*
X448420Y2620187D01*
X447795Y2619627D01*
X447545Y2618880D01*
G01X455295Y2626380D02*
X455170Y2626193D01*
X454920D01*
X454795Y2626380D01*
X454920Y2626567D01*
X455170D01*
X455295Y2626380D01*
G01X447545Y2633880D02*
X447795Y2633133D01*
X448420Y2632573D01*
X449170Y2632200D01*
X450170Y2631920D01*
X451295Y2631827D01*
X452420Y2631920D01*
X453420Y2632200D01*
X454170Y2632573D01*
X454795Y2633133D01*
X455045Y2633880D01*
X454795Y2634627D01*
X454170Y2635187D01*
X453420Y2635560D01*
X452420Y2635840D01*
X451295Y2635933D01*
X450170Y2635840D01*
X449170Y2635560D01*
X448420Y2635187D01*
X447795Y2634627D01*
X447545Y2633880D01*
G01X455045Y2641380D02*
X447545D01*
X449045Y2640260D01*
G01X455045D02*
Y2642500D01*
G01Y2648693D02*
X453420Y2648880D01*
X452045Y2649160D01*
X450795Y2649533D01*
X449420Y2650000D01*
X447545Y2650747D01*
Y2647013D01*
G01X455045Y2656193D02*
X453420Y2656380D01*
X452045Y2656660D01*
X450795Y2657033D01*
X449420Y2657500D01*
X447545Y2658247D01*
Y2654513D01*
G01X449170Y2663040D02*
X447545Y2663507D01*
G01Y2664720D02*
X449170Y2664253D01*
G01X457545Y2671847D02*
X456295Y2672780D01*
X455045Y2673247D01*
X450045D01*
X448795Y2672780D01*
X447545Y2671847D01*
G01X455295Y2678880D02*
X455170Y2678693D01*
X454920D01*
X454795Y2678880D01*
X454920Y2679067D01*
X455170D01*
X455295Y2678880D01*
G01X462000Y-630638D02*
Y-622638D01*
X460800Y-624238D01*
G01Y-630638D02*
X463200D01*
G01X469800D02*
X470000Y-628905D01*
X470300Y-627438D01*
X470700Y-626105D01*
X471200Y-624638D01*
X472000Y-622638D01*
X468000D01*
G01X478000Y-630905D02*
X477800Y-630771D01*
Y-630505D01*
X478000Y-630371D01*
X478200Y-630505D01*
Y-630771D01*
X478000Y-630905D01*
G01X484100Y-623971D02*
X484700Y-623171D01*
X485400Y-622771D01*
X486200Y-622638D01*
X487200Y-622905D01*
X487900Y-623571D01*
X488100Y-624371D01*
X488000Y-625172D01*
X487600Y-625838D01*
X485600Y-627171D01*
X484700Y-628105D01*
X484100Y-629438D01*
X483900Y-630638D01*
X488100D01*
G01X486200Y-598305D02*
X485600Y-597905D01*
X484900Y-597638D01*
X484100D01*
X483200Y-598038D01*
X482500Y-598705D01*
X482000Y-599505D01*
X481600Y-600838D01*
X481500Y-602038D01*
X481700Y-603238D01*
X482000Y-604038D01*
X482600Y-604838D01*
X483300Y-605371D01*
X484000Y-605638D01*
X484700D01*
X485400Y-605371D01*
X486000Y-604971D01*
X486500Y-604438D01*
G01X486590Y-388290D02*
X474090D01*
X483048Y-394025D01*
Y-386275D01*
G01X486590Y-375890D02*
X474090D01*
X483048Y-381625D01*
Y-373875D01*
G01X486590Y-365350D02*
X474090D01*
X476590Y-367210D01*
G01X486590D02*
Y-363490D01*
G01X474090Y-352950D02*
X474507Y-354190D01*
X475548Y-355120D01*
X476798Y-355740D01*
X478465Y-356205D01*
X480340Y-356360D01*
X482215Y-356205D01*
X483882Y-355740D01*
X485132Y-355120D01*
X486173Y-354190D01*
X486590Y-352950D01*
X486173Y-351710D01*
X485132Y-350780D01*
X483882Y-350160D01*
X482215Y-349695D01*
X480340Y-349540D01*
X478465Y-349695D01*
X476798Y-350160D01*
X475548Y-350780D01*
X474507Y-351710D01*
X474090Y-352950D01*
G01X487007Y-340550D02*
X486798Y-340860D01*
X486382D01*
X486173Y-340550D01*
X486382Y-340240D01*
X486798D01*
X487007Y-340550D01*
G01X486590Y-326290D02*
X474090D01*
X483048Y-332025D01*
Y-324275D01*
G01X484090Y-319160D02*
X485549Y-318230D01*
X486382Y-316990D01*
X486590Y-315595D01*
X486382Y-314355D01*
X485340Y-313115D01*
X484090Y-312340D01*
X482840Y-312185D01*
X481382Y-312495D01*
X480340Y-313580D01*
X479923Y-314665D01*
Y-316060D01*
G01Y-314665D02*
X479298Y-313735D01*
X478257Y-312960D01*
X477007Y-312650D01*
X475757Y-312960D01*
X474715Y-313735D01*
X474090Y-315130D01*
X474298Y-316525D01*
X475132Y-317920D01*
G01X486590Y-281150D02*
X474090D01*
X476590Y-283010D01*
G01X486590D02*
Y-279290D01*
G01Y-268750D02*
X474090D01*
X476590Y-270610D01*
G01X486590D02*
Y-266890D01*
G01X476173Y-259295D02*
X474924Y-258365D01*
X474298Y-257280D01*
X474090Y-256040D01*
X474507Y-254490D01*
X475548Y-253405D01*
X476798Y-253095D01*
X478049Y-253250D01*
X479090Y-253870D01*
X481173Y-256970D01*
X482632Y-258365D01*
X484715Y-259295D01*
X486590Y-259605D01*
Y-253095D01*
G01X487007Y-243950D02*
X486798Y-244260D01*
X486382D01*
X486173Y-243950D01*
X486382Y-243640D01*
X486798D01*
X487007Y-243950D01*
G01X474090Y-231550D02*
X474507Y-232790D01*
X475548Y-233720D01*
X476798Y-234340D01*
X478465Y-234805D01*
X480340Y-234960D01*
X482215Y-234805D01*
X483882Y-234340D01*
X485132Y-233720D01*
X486173Y-232790D01*
X486590Y-231550D01*
X486173Y-230310D01*
X485132Y-229380D01*
X483882Y-228760D01*
X482215Y-228295D01*
X480340Y-228140D01*
X478465Y-228295D01*
X476798Y-228760D01*
X475548Y-229380D01*
X474507Y-230310D01*
X474090Y-231550D01*
G01X476173Y-222095D02*
X474924Y-221165D01*
X474298Y-220080D01*
X474090Y-218840D01*
X474507Y-217290D01*
X475548Y-216205D01*
X476798Y-215895D01*
X478049Y-216050D01*
X479090Y-216670D01*
X481173Y-219770D01*
X482632Y-221165D01*
X484715Y-222095D01*
X486590Y-222405D01*
Y-215895D01*
G01X497578Y1672795D02*
G03I-2500J0D01*
G01Y1686968D02*
G03I-2500J0D01*
G01Y1701141D02*
G03I-2500J0D01*
G01Y1715314D02*
G03I-2500J0D01*
G01Y1729488D02*
G03I-2500J0D01*
G01X514330Y-386750D02*
X501830D01*
X510788Y-392485D01*
Y-384735D01*
G01X514330Y-374350D02*
X501830D01*
X510788Y-380085D01*
Y-372335D01*
G01X511830Y-367220D02*
X513289Y-366290D01*
X514122Y-365050D01*
X514330Y-363655D01*
X514122Y-362415D01*
X513080Y-361175D01*
X511830Y-360400D01*
X510580Y-360245D01*
X509122Y-360555D01*
X508080Y-361640D01*
X507663Y-362725D01*
Y-364120D01*
G01Y-362725D02*
X507038Y-361795D01*
X505997Y-361020D01*
X504747Y-360710D01*
X503497Y-361020D01*
X502455Y-361795D01*
X501830Y-363190D01*
X502038Y-364585D01*
X502872Y-365980D01*
G01X514330Y-351720D02*
X511622Y-351410D01*
X509330Y-350945D01*
X507247Y-350325D01*
X504955Y-349550D01*
X501830Y-348310D01*
Y-354510D01*
G01X514747Y-339010D02*
X514538Y-339320D01*
X514122D01*
X513913Y-339010D01*
X514122Y-338700D01*
X514538D01*
X514747Y-339010D01*
G01X509122Y-329555D02*
X507663Y-328470D01*
X506830Y-327540D01*
X506413Y-326300D01*
X506830Y-325215D01*
X507663Y-324440D01*
X508913Y-323820D01*
X510372Y-323665D01*
X511622Y-323820D01*
X512872Y-324440D01*
X513913Y-325370D01*
X514330Y-326455D01*
X513913Y-327695D01*
X512664Y-328780D01*
X510788Y-329400D01*
X508705Y-329555D01*
X505997Y-329245D01*
X504538Y-328780D01*
X503080Y-328005D01*
X502038Y-326920D01*
X501830Y-325835D01*
X502247Y-324750D01*
X503288Y-323975D01*
G01X514330Y-312350D02*
X501830D01*
X510788Y-318085D01*
Y-310335D01*
G01X514330Y-279610D02*
X501830D01*
X504330Y-281470D01*
G01X514330D02*
Y-277750D01*
G01Y-267210D02*
X501830D01*
X504330Y-269070D01*
G01X514330D02*
Y-265350D01*
G01X503913Y-257755D02*
X502664Y-256825D01*
X502038Y-255740D01*
X501830Y-254500D01*
X502247Y-252950D01*
X503288Y-251865D01*
X504538Y-251555D01*
X505789Y-251710D01*
X506830Y-252330D01*
X508913Y-255430D01*
X510372Y-256825D01*
X512455Y-257755D01*
X514330Y-258065D01*
Y-251555D01*
G01X514747Y-242410D02*
X514538Y-242720D01*
X514122D01*
X513913Y-242410D01*
X514122Y-242100D01*
X514538D01*
X514747Y-242410D01*
G01X514330Y-230320D02*
X511622Y-230010D01*
X509330Y-229545D01*
X507247Y-228925D01*
X504955Y-228150D01*
X501830Y-226910D01*
Y-233110D01*
G01X503913Y-220555D02*
X502664Y-219625D01*
X502038Y-218540D01*
X501830Y-217300D01*
X502247Y-215750D01*
X503288Y-214665D01*
X504538Y-214355D01*
X505789Y-214510D01*
X506830Y-215130D01*
X508913Y-218230D01*
X510372Y-219625D01*
X512455Y-220555D01*
X514330Y-220865D01*
Y-214355D01*
G01X513326Y1672795D02*
G03I-2500J0D01*
G01Y1686968D02*
G03I-2500J0D01*
G01X505452Y1676732D02*
G03I-2500J0D01*
G01X513326Y1701141D02*
G03I-2500J0D01*
G01X505452Y1690905D02*
G03I-2500J0D01*
G01X513326Y1715314D02*
G03I-2500J0D01*
G01X505452Y1705078D02*
G03I-2500J0D01*
G01X513326Y1729488D02*
G03I-2500J0D01*
G01X505452Y1719251D02*
G03I-2500J0D01*
G01Y1733425D02*
G03I-2500J0D01*
G01X537115Y-390480D02*
X538157Y-389550D01*
X538782Y-388465D01*
X538990Y-387070D01*
X538573Y-385675D01*
X537740Y-384590D01*
X536282Y-383815D01*
X534615Y-383660D01*
X532948Y-383970D01*
X531907Y-384745D01*
X531073Y-385830D01*
X530865Y-386915D01*
X531073Y-388000D01*
X531907Y-389395D01*
X526490Y-388930D01*
Y-384745D01*
G01X528573Y-377615D02*
X527324Y-376685D01*
X526698Y-375600D01*
X526490Y-374360D01*
X526907Y-372810D01*
X527948Y-371725D01*
X529198Y-371415D01*
X530449Y-371570D01*
X531490Y-372190D01*
X533573Y-375290D01*
X535032Y-376685D01*
X537115Y-377615D01*
X538990Y-377925D01*
Y-371415D01*
G01X536490Y-365680D02*
X537949Y-364750D01*
X538782Y-363510D01*
X538990Y-362115D01*
X538782Y-360875D01*
X537740Y-359635D01*
X536490Y-358860D01*
X535240Y-358705D01*
X533782Y-359015D01*
X532740Y-360100D01*
X532323Y-361185D01*
Y-362580D01*
G01Y-361185D02*
X531698Y-360255D01*
X530657Y-359480D01*
X529407Y-359170D01*
X528157Y-359480D01*
X527115Y-360255D01*
X526490Y-361650D01*
X526698Y-363045D01*
X527532Y-364440D01*
G01X538990Y-349870D02*
X526490D01*
X528990Y-351730D01*
G01X538990D02*
Y-348010D01*
G01X539407Y-337470D02*
X539198Y-337780D01*
X538782D01*
X538573Y-337470D01*
X538782Y-337160D01*
X539198D01*
X539407Y-337470D01*
G01X538990Y-325380D02*
X536282Y-325070D01*
X533990Y-324605D01*
X531907Y-323985D01*
X529615Y-323210D01*
X526490Y-321970D01*
Y-328170D01*
G01X536490Y-316080D02*
X537949Y-315150D01*
X538782Y-313910D01*
X538990Y-312515D01*
X538782Y-311275D01*
X537740Y-310035D01*
X536490Y-309260D01*
X535240Y-309105D01*
X533782Y-309415D01*
X532740Y-310500D01*
X532323Y-311585D01*
Y-312980D01*
G01Y-311585D02*
X531698Y-310655D01*
X530657Y-309880D01*
X529407Y-309570D01*
X528157Y-309880D01*
X527115Y-310655D01*
X526490Y-312050D01*
X526698Y-313445D01*
X527532Y-314840D01*
G01X538990Y-278070D02*
X526490D01*
X528990Y-279930D01*
G01X538990D02*
Y-276210D01*
G01X536490Y-269080D02*
X537949Y-268150D01*
X538782Y-266910D01*
X538990Y-265515D01*
X538782Y-264275D01*
X537740Y-263035D01*
X536490Y-262260D01*
X535240Y-262105D01*
X533782Y-262415D01*
X532740Y-263500D01*
X532323Y-264585D01*
Y-265980D01*
G01Y-264585D02*
X531698Y-263655D01*
X530657Y-262880D01*
X529407Y-262570D01*
X528157Y-262880D01*
X527115Y-263655D01*
X526490Y-265050D01*
X526698Y-266445D01*
X527532Y-267840D01*
G01X528573Y-256215D02*
X527324Y-255285D01*
X526698Y-254200D01*
X526490Y-252960D01*
X526907Y-251410D01*
X527948Y-250325D01*
X529198Y-250015D01*
X530449Y-250170D01*
X531490Y-250790D01*
X533573Y-253890D01*
X535032Y-255285D01*
X537115Y-256215D01*
X538990Y-256525D01*
Y-250015D01*
G01X539407Y-240870D02*
X539198Y-241180D01*
X538782D01*
X538573Y-240870D01*
X538782Y-240560D01*
X539198D01*
X539407Y-240870D01*
G01X538990Y-228470D02*
X538782Y-227385D01*
X538157Y-226145D01*
X537115Y-225370D01*
X535657Y-225060D01*
X534199Y-225370D01*
X532948Y-226300D01*
X532323Y-227695D01*
Y-229245D01*
X531907Y-230175D01*
X530865Y-230950D01*
X529407Y-231260D01*
X527948Y-230795D01*
X526907Y-229710D01*
X526490Y-228470D01*
X526907Y-227230D01*
X527948Y-226145D01*
X529407Y-225680D01*
X530865Y-225990D01*
X531907Y-226765D01*
X532323Y-227695D01*
Y-229245D01*
X532948Y-230640D01*
X534199Y-231570D01*
X535657Y-231880D01*
X537115Y-231570D01*
X538157Y-230795D01*
X538782Y-229555D01*
X538990Y-228470D01*
G01X537532Y-218705D02*
X538573Y-217620D01*
X538990Y-216380D01*
X538573Y-215140D01*
X537324Y-214055D01*
X535448Y-213280D01*
X533573Y-212970D01*
X531282D01*
X529407Y-213280D01*
X527740Y-214055D01*
X526907Y-214985D01*
X526490Y-216070D01*
X526907Y-217310D01*
X527740Y-218240D01*
X528990Y-218860D01*
X530657Y-219170D01*
X532115Y-218860D01*
X533573Y-218085D01*
X534407Y-217155D01*
X534615Y-216070D01*
X534199Y-214830D01*
X533157Y-213900D01*
X531282Y-212970D01*
G01X529074Y1672795D02*
G03I-2500J0D01*
G01X521200Y1676732D02*
G03I-2500J0D01*
G01X529074Y1686968D02*
G03I-2500J0D01*
G01X521200Y1690905D02*
G03I-2500J0D01*
G01X529074Y1701141D02*
G03I-2500J0D01*
G01X521200Y1705078D02*
G03I-2500J0D01*
G01X529074Y1715314D02*
G03I-2500J0D01*
G01X521200Y1719251D02*
G03I-2500J0D01*
G01X529074Y1729488D02*
G03I-2500J0D01*
G01X521200Y1733425D02*
G03I-2500J0D01*
G01X544822Y1672795D02*
G03I-2500J0D01*
G01X536948Y1676732D02*
G03I-2500J0D01*
G01X544822Y1686968D02*
G03I-2500J0D01*
G01X536948Y1690905D02*
G03I-2500J0D01*
G01X544822Y1701141D02*
G03I-2500J0D01*
G01X536948Y1705078D02*
G03I-2500J0D01*
G01X544822Y1715314D02*
G03I-2500J0D01*
G01X536948Y1719251D02*
G03I-2500J0D01*
G01X544822Y1729488D02*
G03I-2500J0D01*
G01X536948Y1733425D02*
G03I-2500J0D01*
G01X565508Y-392790D02*
X566550Y-391860D01*
X567175Y-390775D01*
X567383Y-389380D01*
X566966Y-387985D01*
X566133Y-386900D01*
X564675Y-386125D01*
X563008Y-385970D01*
X561341Y-386280D01*
X560300Y-387055D01*
X559466Y-388140D01*
X559258Y-389225D01*
X559466Y-390310D01*
X560300Y-391705D01*
X554883Y-391240D01*
Y-387055D01*
G01X562175Y-379925D02*
X560716Y-378840D01*
X559883Y-377910D01*
X559466Y-376670D01*
X559883Y-375585D01*
X560716Y-374810D01*
X561966Y-374190D01*
X563425Y-374035D01*
X564675Y-374190D01*
X565925Y-374810D01*
X566966Y-375740D01*
X567383Y-376825D01*
X566966Y-378065D01*
X565717Y-379150D01*
X563841Y-379770D01*
X561758Y-379925D01*
X559050Y-379615D01*
X557591Y-379150D01*
X556133Y-378375D01*
X555091Y-377290D01*
X554883Y-376205D01*
X555300Y-375120D01*
X556341Y-374345D01*
G01X567383Y-364580D02*
X554883D01*
X557383Y-366440D01*
G01X567383D02*
Y-362720D01*
G01Y-352180D02*
X554883D01*
X557383Y-354040D01*
G01X567383D02*
Y-350320D01*
G01X567800Y-339780D02*
X567591Y-340090D01*
X567175D01*
X566966Y-339780D01*
X567175Y-339470D01*
X567591D01*
X567800Y-339780D01*
G01X564883Y-330790D02*
X566342Y-329860D01*
X567175Y-328620D01*
X567383Y-327225D01*
X567175Y-325985D01*
X566133Y-324745D01*
X564883Y-323970D01*
X563633Y-323815D01*
X562175Y-324125D01*
X561133Y-325210D01*
X560716Y-326295D01*
Y-327690D01*
G01Y-326295D02*
X560091Y-325365D01*
X559050Y-324590D01*
X557800Y-324280D01*
X556550Y-324590D01*
X555508Y-325365D01*
X554883Y-326760D01*
X555091Y-328155D01*
X555925Y-329550D01*
G01X564883Y-318390D02*
X566342Y-317460D01*
X567175Y-316220D01*
X567383Y-314825D01*
X567175Y-313585D01*
X566133Y-312345D01*
X564883Y-311570D01*
X563633Y-311415D01*
X562175Y-311725D01*
X561133Y-312810D01*
X560716Y-313895D01*
Y-315290D01*
G01Y-313895D02*
X560091Y-312965D01*
X559050Y-312190D01*
X557800Y-311880D01*
X556550Y-312190D01*
X555508Y-312965D01*
X554883Y-314360D01*
X555091Y-315755D01*
X555925Y-317150D01*
G01X567383Y-280380D02*
X554883D01*
X557383Y-282240D01*
G01X567383D02*
Y-278520D01*
G01Y-266120D02*
X554883D01*
X563841Y-271855D01*
Y-264105D01*
G01X556966Y-258525D02*
X555717Y-257595D01*
X555091Y-256510D01*
X554883Y-255270D01*
X555300Y-253720D01*
X556341Y-252635D01*
X557591Y-252325D01*
X558842Y-252480D01*
X559883Y-253100D01*
X561966Y-256200D01*
X563425Y-257595D01*
X565508Y-258525D01*
X567383Y-258835D01*
Y-252325D01*
G01X567800Y-243180D02*
X567591Y-243490D01*
X567175D01*
X566966Y-243180D01*
X567175Y-242870D01*
X567591D01*
X567800Y-243180D01*
G01X565508Y-234190D02*
X566550Y-233260D01*
X567175Y-232175D01*
X567383Y-230780D01*
X566966Y-229385D01*
X566133Y-228300D01*
X564675Y-227525D01*
X563008Y-227370D01*
X561341Y-227680D01*
X560300Y-228455D01*
X559466Y-229540D01*
X559258Y-230625D01*
X559466Y-231710D01*
X560300Y-233105D01*
X554883Y-232640D01*
Y-228455D01*
G01X564883Y-221790D02*
X566342Y-220860D01*
X567175Y-219620D01*
X567383Y-218225D01*
X567175Y-216985D01*
X566133Y-215745D01*
X564883Y-214970D01*
X563633Y-214815D01*
X562175Y-215125D01*
X561133Y-216210D01*
X560716Y-217295D01*
Y-218690D01*
G01Y-217295D02*
X560091Y-216365D01*
X559050Y-215590D01*
X557800Y-215280D01*
X556550Y-215590D01*
X555508Y-216365D01*
X554883Y-217760D01*
X555091Y-219155D01*
X555925Y-220550D01*
G01X556705Y1405730D02*
Y1408830D01*
X557471D01*
X557778Y1408675D01*
X558008Y1408468D01*
X558200Y1408158D01*
X558353Y1407797D01*
X558391Y1407280D01*
X558353Y1406763D01*
X558200Y1406402D01*
X558008Y1406092D01*
X557778Y1405885D01*
X557471Y1405730D01*
X556705D01*
G01X559690D02*
X560648Y1408830D01*
X561606Y1405730D01*
G01X561261Y1406815D02*
X560035D01*
G01X563748Y1408830D02*
Y1405730D01*
G01X562866Y1408830D02*
X564630D01*
G01X567615Y1405730D02*
X566081D01*
Y1408830D01*
X567615D01*
G01X567001Y1407332D02*
X566081D01*
G01X573891Y1408572D02*
X573661Y1408727D01*
X573393Y1408830D01*
X573086D01*
X572741Y1408675D01*
X572473Y1408417D01*
X572281Y1408107D01*
X572128Y1407590D01*
X572090Y1407125D01*
X572166Y1406660D01*
X572281Y1406350D01*
X572511Y1406040D01*
X572780Y1405833D01*
X573048Y1405730D01*
X573316D01*
X573585Y1405833D01*
X573815Y1405988D01*
X574006Y1406195D01*
G01X576148Y1405730D02*
X575841Y1405782D01*
X575573Y1405988D01*
X575343Y1406298D01*
X575190Y1406660D01*
X575113Y1407073D01*
Y1407487D01*
X575190Y1407900D01*
X575343Y1408262D01*
X575573Y1408572D01*
X575841Y1408778D01*
X576148Y1408830D01*
X576455Y1408778D01*
X576723Y1408572D01*
X576953Y1408262D01*
X577106Y1407900D01*
X577183Y1407487D01*
Y1407073D01*
X577106Y1406660D01*
X576953Y1406298D01*
X576723Y1405988D01*
X576455Y1405782D01*
X576148Y1405730D01*
G01X578405D02*
Y1408830D01*
X579171D01*
X579478Y1408675D01*
X579708Y1408468D01*
X579900Y1408158D01*
X580053Y1407797D01*
X580091Y1407280D01*
X580053Y1406763D01*
X579900Y1406402D01*
X579708Y1406092D01*
X579478Y1405885D01*
X579171Y1405730D01*
X578405D01*
G01X583115D02*
X581581D01*
Y1408830D01*
X583115D01*
G01X582501Y1407332D02*
X581581D01*
G01X556705Y1417830D02*
Y1415608D01*
X556858Y1415143D01*
X557165Y1414833D01*
X557548Y1414730D01*
X557931Y1414833D01*
X558238Y1415143D01*
X558391Y1415608D01*
Y1417830D01*
G01X559881D02*
Y1414730D01*
X561415D01*
G01X565851D02*
Y1417830D01*
X566848Y1415247D01*
X567845Y1417830D01*
Y1414730D01*
G01X568990D02*
X569948Y1417830D01*
X570906Y1414730D01*
G01X570561Y1415815D02*
X569335D01*
G01X572281Y1414730D02*
Y1417830D01*
X573240D01*
X573546Y1417675D01*
X573738Y1417468D01*
X573815Y1417055D01*
X573738Y1416642D01*
X573508Y1416383D01*
X573240Y1416228D01*
X572281D01*
G01X573240D02*
X573815Y1414730D01*
G01X575305D02*
Y1417830D01*
G01X576761D02*
X575305Y1415918D01*
G01X576991Y1414730D02*
X575956Y1416797D01*
G01X556781Y1424230D02*
Y1427330D01*
X557701D01*
X558008Y1427175D01*
X558238Y1426813D01*
X558315Y1426400D01*
X558238Y1425987D01*
X558046Y1425677D01*
X557701Y1425522D01*
X556781D01*
G01X561491Y1427072D02*
X561261Y1427227D01*
X560993Y1427330D01*
X560686D01*
X560341Y1427175D01*
X560073Y1426917D01*
X559881Y1426607D01*
X559728Y1426090D01*
X559690Y1425625D01*
X559766Y1425160D01*
X559881Y1424850D01*
X560111Y1424540D01*
X560380Y1424333D01*
X560648Y1424230D01*
X560916D01*
X561185Y1424333D01*
X561415Y1424488D01*
X561606Y1424695D01*
G01X564055Y1425883D02*
X564208Y1426038D01*
X564323Y1426297D01*
X564400Y1426658D01*
X564323Y1426968D01*
X564170Y1427175D01*
X563901Y1427330D01*
X562866D01*
Y1424230D01*
X564131D01*
X564400Y1424437D01*
X564553Y1424747D01*
X564630Y1425108D01*
X564553Y1425470D01*
X564323Y1425780D01*
X564055Y1425883D01*
X562866D01*
G01X568990Y1427330D02*
X569948Y1424230D01*
X570906Y1427330D01*
G01X573815Y1424230D02*
X572281D01*
Y1427330D01*
X573815D01*
G01X573201Y1425832D02*
X572281D01*
G01X575266Y1424230D02*
Y1427330D01*
X577030Y1424230D01*
Y1427330D01*
G01X578405Y1424230D02*
Y1427330D01*
X579171D01*
X579478Y1427175D01*
X579708Y1426968D01*
X579900Y1426658D01*
X580053Y1426297D01*
X580091Y1425780D01*
X580053Y1425263D01*
X579900Y1424902D01*
X579708Y1424592D01*
X579478Y1424385D01*
X579171Y1424230D01*
X578405D01*
G01X582348D02*
X582041Y1424282D01*
X581773Y1424488D01*
X581543Y1424798D01*
X581390Y1425160D01*
X581313Y1425573D01*
Y1425987D01*
X581390Y1426400D01*
X581543Y1426762D01*
X581773Y1427072D01*
X582041Y1427278D01*
X582348Y1427330D01*
X582655Y1427278D01*
X582923Y1427072D01*
X583153Y1426762D01*
X583306Y1426400D01*
X583383Y1425987D01*
Y1425573D01*
X583306Y1425160D01*
X583153Y1424798D01*
X582923Y1424488D01*
X582655Y1424282D01*
X582348Y1424230D01*
G01X584681D02*
Y1427330D01*
X585640D01*
X585946Y1427175D01*
X586138Y1426968D01*
X586215Y1426555D01*
X586138Y1426142D01*
X585908Y1425883D01*
X585640Y1425728D01*
X584681D01*
G01X585640D02*
X586215Y1424230D01*
G01X590881Y1427330D02*
Y1424230D01*
X592415D01*
G01X594748D02*
X594441Y1424282D01*
X594173Y1424488D01*
X593943Y1424798D01*
X593790Y1425160D01*
X593713Y1425573D01*
Y1425987D01*
X593790Y1426400D01*
X593943Y1426762D01*
X594173Y1427072D01*
X594441Y1427278D01*
X594748Y1427330D01*
X595055Y1427278D01*
X595323Y1427072D01*
X595553Y1426762D01*
X595706Y1426400D01*
X595783Y1425987D01*
Y1425573D01*
X595706Y1425160D01*
X595553Y1424798D01*
X595323Y1424488D01*
X595055Y1424282D01*
X594748Y1424230D01*
G01X598078Y1425780D02*
X598845D01*
Y1424850D01*
X598615Y1424540D01*
X598346Y1424333D01*
X597963Y1424230D01*
X597580Y1424333D01*
X597311Y1424540D01*
X597081Y1424850D01*
X596928Y1425212D01*
X596851Y1425625D01*
Y1425987D01*
X596928Y1426297D01*
X597081Y1426658D01*
X597311Y1426968D01*
X597541Y1427175D01*
X597848Y1427330D01*
X598116D01*
X598423Y1427227D01*
X598653Y1427020D01*
G01X600948Y1424230D02*
X600641Y1424282D01*
X600373Y1424488D01*
X600143Y1424798D01*
X599990Y1425160D01*
X599913Y1425573D01*
Y1425987D01*
X599990Y1426400D01*
X600143Y1426762D01*
X600373Y1427072D01*
X600641Y1427278D01*
X600948Y1427330D01*
X601255Y1427278D01*
X601523Y1427072D01*
X601753Y1426762D01*
X601906Y1426400D01*
X601983Y1425987D01*
Y1425573D01*
X601906Y1425160D01*
X601753Y1424798D01*
X601523Y1424488D01*
X601255Y1424282D01*
X600948Y1424230D01*
G01X552696Y1676732D02*
G03I-2500J0D01*
G01Y1690905D02*
G03I-2500J0D01*
G01Y1705078D02*
G03I-2500J0D01*
G01Y1719251D02*
G03I-2500J0D01*
G01Y1733425D02*
G03I-2500J0D01*
G01X564508Y1672795D02*
G03I-2500J0D01*
G01X572382Y1676732D02*
G03I-2500J0D01*
G01X564508Y1686968D02*
G03I-2500J0D01*
G01X572382Y1690905D02*
G03I-2500J0D01*
G01X564508Y1701141D02*
G03I-2500J0D01*
G01X572382Y1705078D02*
G03I-2500J0D01*
G01X564508Y1715314D02*
G03I-2500J0D01*
G01X572382Y1719251D02*
G03I-2500J0D01*
G01X564508Y1729488D02*
G03I-2500J0D01*
G01X572382Y1733425D02*
G03I-2500J0D01*
G01X580256Y1672795D02*
G03I-2500J0D01*
G01X588130Y1676732D02*
G03I-2500J0D01*
G01X580256Y1686968D02*
G03I-2500J0D01*
G01X588130Y1690905D02*
G03I-2500J0D01*
G01X580256Y1701141D02*
G03I-2500J0D01*
G01X588130Y1705078D02*
G03I-2500J0D01*
G01X580256Y1715314D02*
G03I-2500J0D01*
G01X588130Y1719251D02*
G03I-2500J0D01*
G01X580256Y1729488D02*
G03I-2500J0D01*
G01X588130Y1733425D02*
G03I-2500J0D01*
G01X607451Y-393865D02*
X605992Y-392780D01*
X605159Y-391850D01*
X604742Y-390610D01*
X605159Y-389525D01*
X605992Y-388750D01*
X607242Y-388130D01*
X608701Y-387975D01*
X609951Y-388130D01*
X611201Y-388750D01*
X612242Y-389680D01*
X612659Y-390765D01*
X612242Y-392005D01*
X610993Y-393090D01*
X609117Y-393710D01*
X607034Y-393865D01*
X604326Y-393555D01*
X602867Y-393090D01*
X601409Y-392315D01*
X600367Y-391230D01*
X600159Y-390145D01*
X600576Y-389060D01*
X601617Y-388285D01*
G01X600159Y-378520D02*
X600576Y-379760D01*
X601617Y-380690D01*
X602867Y-381310D01*
X604534Y-381775D01*
X606409Y-381930D01*
X608284Y-381775D01*
X609951Y-381310D01*
X611201Y-380690D01*
X612242Y-379760D01*
X612659Y-378520D01*
X612242Y-377280D01*
X611201Y-376350D01*
X609951Y-375730D01*
X608284Y-375265D01*
X606409Y-375110D01*
X604534Y-375265D01*
X602867Y-375730D01*
X601617Y-376350D01*
X600576Y-377280D01*
X600159Y-378520D01*
G01X607451Y-369065D02*
X605992Y-367980D01*
X605159Y-367050D01*
X604742Y-365810D01*
X605159Y-364725D01*
X605992Y-363950D01*
X607242Y-363330D01*
X608701Y-363175D01*
X609951Y-363330D01*
X611201Y-363950D01*
X612242Y-364880D01*
X612659Y-365965D01*
X612242Y-367205D01*
X610993Y-368290D01*
X609117Y-368910D01*
X607034Y-369065D01*
X604326Y-368755D01*
X602867Y-368290D01*
X601409Y-367515D01*
X600367Y-366430D01*
X600159Y-365345D01*
X600576Y-364260D01*
X601617Y-363485D01*
G01X612659Y-351860D02*
X600159D01*
X609117Y-357595D01*
Y-349845D01*
G01X613076Y-341320D02*
X612867Y-341630D01*
X612451D01*
X612242Y-341320D01*
X612451Y-341010D01*
X612867D01*
X613076Y-341320D01*
G01X600159Y-328920D02*
X600576Y-330160D01*
X601617Y-331090D01*
X602867Y-331710D01*
X604534Y-332175D01*
X606409Y-332330D01*
X608284Y-332175D01*
X609951Y-331710D01*
X611201Y-331090D01*
X612242Y-330160D01*
X612659Y-328920D01*
X612242Y-327680D01*
X611201Y-326750D01*
X609951Y-326130D01*
X608284Y-325665D01*
X606409Y-325510D01*
X604534Y-325665D01*
X602867Y-326130D01*
X601617Y-326750D01*
X600576Y-327680D01*
X600159Y-328920D01*
G01X611201Y-319155D02*
X612242Y-318070D01*
X612659Y-316830D01*
X612242Y-315590D01*
X610993Y-314505D01*
X609117Y-313730D01*
X607242Y-313420D01*
X604951D01*
X603076Y-313730D01*
X601409Y-314505D01*
X600576Y-315435D01*
X600159Y-316520D01*
X600576Y-317760D01*
X601409Y-318690D01*
X602659Y-319310D01*
X604326Y-319620D01*
X605784Y-319310D01*
X607242Y-318535D01*
X608076Y-317605D01*
X608284Y-316520D01*
X607868Y-315280D01*
X606826Y-314350D01*
X604951Y-313420D01*
G01X612659Y-281920D02*
X600159D01*
X602659Y-283780D01*
G01X612659D02*
Y-280060D01*
G01X610784Y-272930D02*
X611826Y-272000D01*
X612451Y-270915D01*
X612659Y-269520D01*
X612242Y-268125D01*
X611409Y-267040D01*
X609951Y-266265D01*
X608284Y-266110D01*
X606617Y-266420D01*
X605576Y-267195D01*
X604742Y-268280D01*
X604534Y-269365D01*
X604742Y-270450D01*
X605576Y-271845D01*
X600159Y-271380D01*
Y-267195D01*
G01X612659Y-255260D02*
X600159D01*
X609117Y-260995D01*
Y-253245D01*
G01X613076Y-244720D02*
X612867Y-245030D01*
X612451D01*
X612242Y-244720D01*
X612451Y-244410D01*
X612867D01*
X613076Y-244720D01*
G01X600159Y-232320D02*
X600576Y-233560D01*
X601617Y-234490D01*
X602867Y-235110D01*
X604534Y-235575D01*
X606409Y-235730D01*
X608284Y-235575D01*
X609951Y-235110D01*
X611201Y-234490D01*
X612242Y-233560D01*
X612659Y-232320D01*
X612242Y-231080D01*
X611201Y-230150D01*
X609951Y-229530D01*
X608284Y-229065D01*
X606409Y-228910D01*
X604534Y-229065D01*
X602867Y-229530D01*
X601617Y-230150D01*
X600576Y-231080D01*
X600159Y-232320D01*
G01X610159Y-223330D02*
X611618Y-222400D01*
X612451Y-221160D01*
X612659Y-219765D01*
X612451Y-218525D01*
X611409Y-217285D01*
X610159Y-216510D01*
X608909Y-216355D01*
X607451Y-216665D01*
X606409Y-217750D01*
X605992Y-218835D01*
Y-220230D01*
G01Y-218835D02*
X605367Y-217905D01*
X604326Y-217130D01*
X603076Y-216820D01*
X601826Y-217130D01*
X600784Y-217905D01*
X600159Y-219300D01*
X600367Y-220695D01*
X601201Y-222090D01*
G01X596004Y1672795D02*
G03I-2500J0D01*
G01X603878Y1676732D02*
G03I-2500J0D01*
G01X596004Y1686968D02*
G03I-2500J0D01*
G01X603878Y1690905D02*
G03I-2500J0D01*
G01X596004Y1701141D02*
G03I-2500J0D01*
G01X603878Y1705078D02*
G03I-2500J0D01*
G01X596004Y1715314D02*
G03I-2500J0D01*
G01X603878Y1719251D02*
G03I-2500J0D01*
G01X596004Y1729488D02*
G03I-2500J0D01*
G01X603878Y1733425D02*
G03I-2500J0D01*
G01X611752Y1672795D02*
G03I-2500J0D01*
G01X619626Y1676732D02*
G03I-2500J0D01*
G01X611752Y1686968D02*
G03I-2500J0D01*
G01X619626Y1690905D02*
G03I-2500J0D01*
G01X611752Y1701141D02*
G03I-2500J0D01*
G01X619626Y1705078D02*
G03I-2500J0D01*
G01X611752Y1715314D02*
G03I-2500J0D01*
G01X619626Y1719251D02*
G03I-2500J0D01*
G01X611752Y1729488D02*
G03I-2500J0D01*
G01X619626Y1733425D02*
G03I-2500J0D01*
G01X662066Y-386125D02*
X660607Y-385040D01*
X659774Y-384110D01*
X659357Y-382870D01*
X659774Y-381785D01*
X660607Y-381010D01*
X661857Y-380390D01*
X663316Y-380235D01*
X664566Y-380390D01*
X665816Y-381010D01*
X666857Y-381940D01*
X667274Y-383025D01*
X666857Y-384265D01*
X665608Y-385350D01*
X663732Y-385970D01*
X661649Y-386125D01*
X658941Y-385815D01*
X657482Y-385350D01*
X656024Y-384575D01*
X654982Y-383490D01*
X654774Y-382405D01*
X655191Y-381320D01*
X656232Y-380545D01*
G01X662066Y-373725D02*
X660607Y-372640D01*
X659774Y-371710D01*
X659357Y-370470D01*
X659774Y-369385D01*
X660607Y-368610D01*
X661857Y-367990D01*
X663316Y-367835D01*
X664566Y-367990D01*
X665816Y-368610D01*
X666857Y-369540D01*
X667274Y-370625D01*
X666857Y-371865D01*
X665608Y-372950D01*
X663732Y-373570D01*
X661649Y-373725D01*
X658941Y-373415D01*
X657482Y-372950D01*
X656024Y-372175D01*
X654982Y-371090D01*
X654774Y-370005D01*
X655191Y-368920D01*
X656232Y-368145D01*
G01X667274Y-358380D02*
X654774D01*
X657274Y-360240D01*
G01X667274D02*
Y-356520D01*
G01X654774Y-345980D02*
X655191Y-347220D01*
X656232Y-348150D01*
X657482Y-348770D01*
X659149Y-349235D01*
X661024Y-349390D01*
X662899Y-349235D01*
X664566Y-348770D01*
X665816Y-348150D01*
X666857Y-347220D01*
X667274Y-345980D01*
X666857Y-344740D01*
X665816Y-343810D01*
X664566Y-343190D01*
X662899Y-342725D01*
X661024Y-342570D01*
X659149Y-342725D01*
X657482Y-343190D01*
X656232Y-343810D01*
X655191Y-344740D01*
X654774Y-345980D01*
G01X667691Y-333580D02*
X667482Y-333890D01*
X667066D01*
X666857Y-333580D01*
X667066Y-333270D01*
X667482D01*
X667691Y-333580D01*
G01X656857Y-324125D02*
X655608Y-323195D01*
X654982Y-322110D01*
X654774Y-320870D01*
X655191Y-319320D01*
X656232Y-318235D01*
X657482Y-317925D01*
X658733Y-318080D01*
X659774Y-318700D01*
X661857Y-321800D01*
X663316Y-323195D01*
X665399Y-324125D01*
X667274Y-324435D01*
Y-317925D01*
G01Y-306920D02*
X654774D01*
X663732Y-312655D01*
Y-304905D01*
G01X667274Y-274180D02*
X654774D01*
X657274Y-276040D01*
G01X667274D02*
Y-272320D01*
G01X662066Y-264725D02*
X660607Y-263640D01*
X659774Y-262710D01*
X659357Y-261470D01*
X659774Y-260385D01*
X660607Y-259610D01*
X661857Y-258990D01*
X663316Y-258835D01*
X664566Y-258990D01*
X665816Y-259610D01*
X666857Y-260540D01*
X667274Y-261625D01*
X666857Y-262865D01*
X665608Y-263950D01*
X663732Y-264570D01*
X661649Y-264725D01*
X658941Y-264415D01*
X657482Y-263950D01*
X656024Y-263175D01*
X654982Y-262090D01*
X654774Y-261005D01*
X655191Y-259920D01*
X656232Y-259145D01*
G01X667274Y-249690D02*
X664566Y-249380D01*
X662274Y-248915D01*
X660191Y-248295D01*
X657899Y-247520D01*
X654774Y-246280D01*
Y-252480D01*
G01X667691Y-236980D02*
X667482Y-237290D01*
X667066D01*
X666857Y-236980D01*
X667066Y-236670D01*
X667482D01*
X667691Y-236980D01*
G01X665816Y-227215D02*
X666857Y-226130D01*
X667274Y-224890D01*
X666857Y-223650D01*
X665608Y-222565D01*
X663732Y-221790D01*
X661857Y-221480D01*
X659566D01*
X657691Y-221790D01*
X656024Y-222565D01*
X655191Y-223495D01*
X654774Y-224580D01*
X655191Y-225820D01*
X656024Y-226750D01*
X657274Y-227370D01*
X658941Y-227680D01*
X660399Y-227370D01*
X661857Y-226595D01*
X662691Y-225665D01*
X662899Y-224580D01*
X662483Y-223340D01*
X661441Y-222410D01*
X659566Y-221480D01*
G01X691012Y-401575D02*
X689553Y-400490D01*
X688720Y-399560D01*
X688303Y-398320D01*
X688720Y-397235D01*
X689553Y-396460D01*
X690803Y-395840D01*
X692262Y-395685D01*
X693512Y-395840D01*
X694762Y-396460D01*
X695803Y-397390D01*
X696220Y-398475D01*
X695803Y-399715D01*
X694554Y-400800D01*
X692678Y-401420D01*
X690595Y-401575D01*
X687887Y-401265D01*
X686428Y-400800D01*
X684970Y-400025D01*
X683928Y-398940D01*
X683720Y-397855D01*
X684137Y-396770D01*
X685178Y-395995D01*
G01X696220Y-386230D02*
X696012Y-385145D01*
X695387Y-383905D01*
X694345Y-383130D01*
X692887Y-382820D01*
X691429Y-383130D01*
X690178Y-384060D01*
X689553Y-385455D01*
Y-387005D01*
X689137Y-387935D01*
X688095Y-388710D01*
X686637Y-389020D01*
X685178Y-388555D01*
X684137Y-387470D01*
X683720Y-386230D01*
X684137Y-384990D01*
X685178Y-383905D01*
X686637Y-383440D01*
X688095Y-383750D01*
X689137Y-384525D01*
X689553Y-385455D01*
Y-387005D01*
X690178Y-388400D01*
X691429Y-389330D01*
X692887Y-389640D01*
X694345Y-389330D01*
X695387Y-388555D01*
X696012Y-387315D01*
X696220Y-386230D01*
G01Y-373830D02*
X683720D01*
X686220Y-375690D01*
G01X696220D02*
Y-371970D01*
G01Y-359570D02*
X683720D01*
X692678Y-365305D01*
Y-357555D01*
G01X696637Y-349030D02*
X696428Y-349340D01*
X696012D01*
X695803Y-349030D01*
X696012Y-348720D01*
X696428D01*
X696637Y-349030D01*
G01X696220Y-334770D02*
X683720D01*
X692678Y-340505D01*
Y-332755D01*
G01X683720Y-324230D02*
X684137Y-325470D01*
X685178Y-326400D01*
X686428Y-327020D01*
X688095Y-327485D01*
X689970Y-327640D01*
X691845Y-327485D01*
X693512Y-327020D01*
X694762Y-326400D01*
X695803Y-325470D01*
X696220Y-324230D01*
X695803Y-322990D01*
X694762Y-322060D01*
X693512Y-321440D01*
X691845Y-320975D01*
X689970Y-320820D01*
X688095Y-320975D01*
X686428Y-321440D01*
X685178Y-322060D01*
X684137Y-322990D01*
X683720Y-324230D01*
G01X696220Y-289630D02*
X683720D01*
X686220Y-291490D01*
G01X696220D02*
Y-287770D01*
G01Y-277540D02*
X693512Y-277230D01*
X691220Y-276765D01*
X689137Y-276145D01*
X686845Y-275370D01*
X683720Y-274130D01*
Y-280330D01*
G01X693720Y-268240D02*
X695179Y-267310D01*
X696012Y-266070D01*
X696220Y-264675D01*
X696012Y-263435D01*
X694970Y-262195D01*
X693720Y-261420D01*
X692470Y-261265D01*
X691012Y-261575D01*
X689970Y-262660D01*
X689553Y-263745D01*
Y-265140D01*
G01Y-263745D02*
X688928Y-262815D01*
X687887Y-262040D01*
X686637Y-261730D01*
X685387Y-262040D01*
X684345Y-262815D01*
X683720Y-264210D01*
X683928Y-265605D01*
X684762Y-267000D01*
G01X696637Y-252430D02*
X696428Y-252740D01*
X696012D01*
X695803Y-252430D01*
X696012Y-252120D01*
X696428D01*
X696637Y-252430D01*
G01X683720Y-240030D02*
X684137Y-241270D01*
X685178Y-242200D01*
X686428Y-242820D01*
X688095Y-243285D01*
X689970Y-243440D01*
X691845Y-243285D01*
X693512Y-242820D01*
X694762Y-242200D01*
X695803Y-241270D01*
X696220Y-240030D01*
X695803Y-238790D01*
X694762Y-237860D01*
X693512Y-237240D01*
X691845Y-236775D01*
X689970Y-236620D01*
X688095Y-236775D01*
X686428Y-237240D01*
X685178Y-237860D01*
X684137Y-238790D01*
X683720Y-240030D01*
G01X694762Y-230265D02*
X695803Y-229180D01*
X696220Y-227940D01*
X695803Y-226700D01*
X694554Y-225615D01*
X692678Y-224840D01*
X690803Y-224530D01*
X688512D01*
X686637Y-224840D01*
X684970Y-225615D01*
X684137Y-226545D01*
X683720Y-227630D01*
X684137Y-228870D01*
X684970Y-229800D01*
X686220Y-230420D01*
X687887Y-230730D01*
X689345Y-230420D01*
X690803Y-229645D01*
X691637Y-228715D01*
X691845Y-227630D01*
X691429Y-226390D01*
X690387Y-225460D01*
X688512Y-224530D01*
G01X721650Y-393540D02*
X718942Y-393230D01*
X716650Y-392765D01*
X714567Y-392145D01*
X712275Y-391370D01*
X709150Y-390130D01*
Y-396330D01*
G01Y-380830D02*
X709567Y-382070D01*
X710608Y-383000D01*
X711858Y-383620D01*
X713525Y-384085D01*
X715400Y-384240D01*
X717275Y-384085D01*
X718942Y-383620D01*
X720192Y-383000D01*
X721233Y-382070D01*
X721650Y-380830D01*
X721233Y-379590D01*
X720192Y-378660D01*
X718942Y-378040D01*
X717275Y-377575D01*
X715400Y-377420D01*
X713525Y-377575D01*
X711858Y-378040D01*
X710608Y-378660D01*
X709567Y-379590D01*
X709150Y-380830D01*
G01X721650Y-366570D02*
X709150D01*
X718108Y-372305D01*
Y-364555D01*
G01X721650Y-356030D02*
X709150D01*
X711650Y-357890D01*
G01X721650D02*
Y-354170D01*
G01X722067Y-343630D02*
X721858Y-343940D01*
X721442D01*
X721233Y-343630D01*
X721442Y-343320D01*
X721858D01*
X722067Y-343630D01*
G01X721650Y-331230D02*
X721442Y-330145D01*
X720817Y-328905D01*
X719775Y-328130D01*
X718317Y-327820D01*
X716859Y-328130D01*
X715608Y-329060D01*
X714983Y-330455D01*
Y-332005D01*
X714567Y-332935D01*
X713525Y-333710D01*
X712067Y-334020D01*
X710608Y-333555D01*
X709567Y-332470D01*
X709150Y-331230D01*
X709567Y-329990D01*
X710608Y-328905D01*
X712067Y-328440D01*
X713525Y-328750D01*
X714567Y-329525D01*
X714983Y-330455D01*
Y-332005D01*
X715608Y-333400D01*
X716859Y-334330D01*
X718317Y-334640D01*
X719775Y-334330D01*
X720817Y-333555D01*
X721442Y-332315D01*
X721650Y-331230D01*
G01X719775Y-322240D02*
X720817Y-321310D01*
X721442Y-320225D01*
X721650Y-318830D01*
X721233Y-317435D01*
X720400Y-316350D01*
X718942Y-315575D01*
X717275Y-315420D01*
X715608Y-315730D01*
X714567Y-316505D01*
X713733Y-317590D01*
X713525Y-318675D01*
X713733Y-319760D01*
X714567Y-321155D01*
X709150Y-320690D01*
Y-316505D01*
G01X721650Y-284230D02*
X709150D01*
X711650Y-286090D01*
G01X721650D02*
Y-282370D01*
G01Y-272140D02*
X718942Y-271830D01*
X716650Y-271365D01*
X714567Y-270745D01*
X712275Y-269970D01*
X709150Y-268730D01*
Y-274930D01*
G01X721650Y-259430D02*
X721442Y-258345D01*
X720817Y-257105D01*
X719775Y-256330D01*
X718317Y-256020D01*
X716859Y-256330D01*
X715608Y-257260D01*
X714983Y-258655D01*
Y-260205D01*
X714567Y-261135D01*
X713525Y-261910D01*
X712067Y-262220D01*
X710608Y-261755D01*
X709567Y-260670D01*
X709150Y-259430D01*
X709567Y-258190D01*
X710608Y-257105D01*
X712067Y-256640D01*
X713525Y-256950D01*
X714567Y-257725D01*
X714983Y-258655D01*
Y-260205D01*
X715608Y-261600D01*
X716859Y-262530D01*
X718317Y-262840D01*
X719775Y-262530D01*
X720817Y-261755D01*
X721442Y-260515D01*
X721650Y-259430D01*
G01X722067Y-247030D02*
X721858Y-247340D01*
X721442D01*
X721233Y-247030D01*
X721442Y-246720D01*
X721858D01*
X722067Y-247030D01*
G01X721650Y-234630D02*
X721442Y-233545D01*
X720817Y-232305D01*
X719775Y-231530D01*
X718317Y-231220D01*
X716859Y-231530D01*
X715608Y-232460D01*
X714983Y-233855D01*
Y-235405D01*
X714567Y-236335D01*
X713525Y-237110D01*
X712067Y-237420D01*
X710608Y-236955D01*
X709567Y-235870D01*
X709150Y-234630D01*
X709567Y-233390D01*
X710608Y-232305D01*
X712067Y-231840D01*
X713525Y-232150D01*
X714567Y-232925D01*
X714983Y-233855D01*
Y-235405D01*
X715608Y-236800D01*
X716859Y-237730D01*
X718317Y-238040D01*
X719775Y-237730D01*
X720817Y-236955D01*
X721442Y-235715D01*
X721650Y-234630D01*
G01X716442Y-225175D02*
X714983Y-224090D01*
X714150Y-223160D01*
X713733Y-221920D01*
X714150Y-220835D01*
X714983Y-220060D01*
X716233Y-219440D01*
X717692Y-219285D01*
X718942Y-219440D01*
X720192Y-220060D01*
X721233Y-220990D01*
X721650Y-222075D01*
X721233Y-223315D01*
X719984Y-224400D01*
X718108Y-225020D01*
X716025Y-225175D01*
X713317Y-224865D01*
X711858Y-224400D01*
X710400Y-223625D01*
X709358Y-222540D01*
X709150Y-221455D01*
X709567Y-220370D01*
X710608Y-219595D01*
G01X745540Y-393540D02*
X742832Y-393230D01*
X740540Y-392765D01*
X738457Y-392145D01*
X736165Y-391370D01*
X733040Y-390130D01*
Y-396330D01*
G01Y-380830D02*
X733457Y-382070D01*
X734498Y-383000D01*
X735748Y-383620D01*
X737415Y-384085D01*
X739290Y-384240D01*
X741165Y-384085D01*
X742832Y-383620D01*
X744082Y-383000D01*
X745123Y-382070D01*
X745540Y-380830D01*
X745123Y-379590D01*
X744082Y-378660D01*
X742832Y-378040D01*
X741165Y-377575D01*
X739290Y-377420D01*
X737415Y-377575D01*
X735748Y-378040D01*
X734498Y-378660D01*
X733457Y-379590D01*
X733040Y-380830D01*
G01X745540Y-368740D02*
X742832Y-368430D01*
X740540Y-367965D01*
X738457Y-367345D01*
X736165Y-366570D01*
X733040Y-365330D01*
Y-371530D01*
G01X740332Y-358975D02*
X738873Y-357890D01*
X738040Y-356960D01*
X737623Y-355720D01*
X738040Y-354635D01*
X738873Y-353860D01*
X740123Y-353240D01*
X741582Y-353085D01*
X742832Y-353240D01*
X744082Y-353860D01*
X745123Y-354790D01*
X745540Y-355875D01*
X745123Y-357115D01*
X743874Y-358200D01*
X741998Y-358820D01*
X739915Y-358975D01*
X737207Y-358665D01*
X735748Y-358200D01*
X734290Y-357425D01*
X733248Y-356340D01*
X733040Y-355255D01*
X733457Y-354170D01*
X734498Y-353395D01*
G01X745957Y-343630D02*
X745748Y-343940D01*
X745332D01*
X745123Y-343630D01*
X745332Y-343320D01*
X745748D01*
X745957Y-343630D01*
G01X745540Y-331540D02*
X742832Y-331230D01*
X740540Y-330765D01*
X738457Y-330145D01*
X736165Y-329370D01*
X733040Y-328130D01*
Y-334330D01*
G01X745540Y-319140D02*
X742832Y-318830D01*
X740540Y-318365D01*
X738457Y-317745D01*
X736165Y-316970D01*
X733040Y-315730D01*
Y-321930D01*
G01X745540Y-284230D02*
X733040D01*
X735540Y-286090D01*
G01X745540D02*
Y-282370D01*
G01Y-272140D02*
X742832Y-271830D01*
X740540Y-271365D01*
X738457Y-270745D01*
X736165Y-269970D01*
X733040Y-268730D01*
Y-274930D01*
G01X744082Y-262065D02*
X745123Y-260980D01*
X745540Y-259740D01*
X745123Y-258500D01*
X743874Y-257415D01*
X741998Y-256640D01*
X740123Y-256330D01*
X737832D01*
X735957Y-256640D01*
X734290Y-257415D01*
X733457Y-258345D01*
X733040Y-259430D01*
X733457Y-260670D01*
X734290Y-261600D01*
X735540Y-262220D01*
X737207Y-262530D01*
X738665Y-262220D01*
X740123Y-261445D01*
X740957Y-260515D01*
X741165Y-259430D01*
X740749Y-258190D01*
X739707Y-257260D01*
X737832Y-256330D01*
G01X745957Y-247030D02*
X745748Y-247340D01*
X745332D01*
X745123Y-247030D01*
X745332Y-246720D01*
X745748D01*
X745957Y-247030D01*
G01X745540Y-234940D02*
X742832Y-234630D01*
X740540Y-234165D01*
X738457Y-233545D01*
X736165Y-232770D01*
X733040Y-231530D01*
Y-237730D01*
G01X743665Y-225640D02*
X744707Y-224710D01*
X745332Y-223625D01*
X745540Y-222230D01*
X745123Y-220835D01*
X744290Y-219750D01*
X742832Y-218975D01*
X741165Y-218820D01*
X739498Y-219130D01*
X738457Y-219905D01*
X737623Y-220990D01*
X737415Y-222075D01*
X737623Y-223160D01*
X738457Y-224555D01*
X733040Y-224090D01*
Y-219905D01*
G01X728090Y223200D02*
Y231200D01*
X732690Y223200D01*
Y231200D01*
G01X736390Y223200D02*
Y231200D01*
X738790D01*
X739590Y230800D01*
X740190Y229867D01*
X740390Y228800D01*
X740190Y227733D01*
X739690Y226933D01*
X738790Y226533D01*
X736390D01*
G01X746390Y231200D02*
Y223200D01*
G01X744090Y231200D02*
X748690D01*
G01X752290Y223200D02*
Y231200D01*
G01X756490D02*
Y223200D01*
G01Y227200D02*
X752290D01*
G01X769852Y-393540D02*
X767144Y-393230D01*
X764852Y-392765D01*
X762769Y-392145D01*
X760477Y-391370D01*
X757352Y-390130D01*
Y-396330D01*
G01X764644Y-383775D02*
X763185Y-382690D01*
X762352Y-381760D01*
X761935Y-380520D01*
X762352Y-379435D01*
X763185Y-378660D01*
X764435Y-378040D01*
X765894Y-377885D01*
X767144Y-378040D01*
X768394Y-378660D01*
X769435Y-379590D01*
X769852Y-380675D01*
X769435Y-381915D01*
X768186Y-383000D01*
X766310Y-383620D01*
X764227Y-383775D01*
X761519Y-383465D01*
X760060Y-383000D01*
X758602Y-382225D01*
X757560Y-381140D01*
X757352Y-380055D01*
X757769Y-378970D01*
X758810Y-378195D01*
G01X767352Y-371840D02*
X768811Y-370910D01*
X769644Y-369670D01*
X769852Y-368275D01*
X769644Y-367035D01*
X768602Y-365795D01*
X767352Y-365020D01*
X766102Y-364865D01*
X764644Y-365175D01*
X763602Y-366260D01*
X763185Y-367345D01*
Y-368740D01*
G01Y-367345D02*
X762560Y-366415D01*
X761519Y-365640D01*
X760269Y-365330D01*
X759019Y-365640D01*
X757977Y-366415D01*
X757352Y-367810D01*
X757560Y-369205D01*
X758394Y-370600D01*
G01X764644Y-358975D02*
X763185Y-357890D01*
X762352Y-356960D01*
X761935Y-355720D01*
X762352Y-354635D01*
X763185Y-353860D01*
X764435Y-353240D01*
X765894Y-353085D01*
X767144Y-353240D01*
X768394Y-353860D01*
X769435Y-354790D01*
X769852Y-355875D01*
X769435Y-357115D01*
X768186Y-358200D01*
X766310Y-358820D01*
X764227Y-358975D01*
X761519Y-358665D01*
X760060Y-358200D01*
X758602Y-357425D01*
X757560Y-356340D01*
X757352Y-355255D01*
X757769Y-354170D01*
X758810Y-353395D01*
G01X770269Y-343630D02*
X770060Y-343940D01*
X769644D01*
X769435Y-343630D01*
X769644Y-343320D01*
X770060D01*
X770269Y-343630D01*
G01X757352Y-331230D02*
X757769Y-332470D01*
X758810Y-333400D01*
X760060Y-334020D01*
X761727Y-334485D01*
X763602Y-334640D01*
X765477Y-334485D01*
X767144Y-334020D01*
X768394Y-333400D01*
X769435Y-332470D01*
X769852Y-331230D01*
X769435Y-329990D01*
X768394Y-329060D01*
X767144Y-328440D01*
X765477Y-327975D01*
X763602Y-327820D01*
X761727Y-327975D01*
X760060Y-328440D01*
X758810Y-329060D01*
X757769Y-329990D01*
X757352Y-331230D01*
G01X759435Y-321775D02*
X758186Y-320845D01*
X757560Y-319760D01*
X757352Y-318520D01*
X757769Y-316970D01*
X758810Y-315885D01*
X760060Y-315575D01*
X761311Y-315730D01*
X762352Y-316350D01*
X764435Y-319450D01*
X765894Y-320845D01*
X767977Y-321775D01*
X769852Y-322085D01*
Y-315575D01*
G01Y-284230D02*
X757352D01*
X759852Y-286090D01*
G01X769852D02*
Y-282370D01*
G01X768394Y-274465D02*
X769435Y-273380D01*
X769852Y-272140D01*
X769435Y-270900D01*
X768186Y-269815D01*
X766310Y-269040D01*
X764435Y-268730D01*
X762144D01*
X760269Y-269040D01*
X758602Y-269815D01*
X757769Y-270745D01*
X757352Y-271830D01*
X757769Y-273070D01*
X758602Y-274000D01*
X759852Y-274620D01*
X761519Y-274930D01*
X762977Y-274620D01*
X764435Y-273845D01*
X765269Y-272915D01*
X765477Y-271830D01*
X765061Y-270590D01*
X764019Y-269660D01*
X762144Y-268730D01*
G01X767352Y-262840D02*
X768811Y-261910D01*
X769644Y-260670D01*
X769852Y-259275D01*
X769644Y-258035D01*
X768602Y-256795D01*
X767352Y-256020D01*
X766102Y-255865D01*
X764644Y-256175D01*
X763602Y-257260D01*
X763185Y-258345D01*
Y-259740D01*
G01Y-258345D02*
X762560Y-257415D01*
X761519Y-256640D01*
X760269Y-256330D01*
X759019Y-256640D01*
X757977Y-257415D01*
X757352Y-258810D01*
X757560Y-260205D01*
X758394Y-261600D01*
G01X770269Y-247030D02*
X770060Y-247340D01*
X769644D01*
X769435Y-247030D01*
X769644Y-246720D01*
X770060D01*
X770269Y-247030D01*
G01X768394Y-237265D02*
X769435Y-236180D01*
X769852Y-234940D01*
X769435Y-233700D01*
X768186Y-232615D01*
X766310Y-231840D01*
X764435Y-231530D01*
X762144D01*
X760269Y-231840D01*
X758602Y-232615D01*
X757769Y-233545D01*
X757352Y-234630D01*
X757769Y-235870D01*
X758602Y-236800D01*
X759852Y-237420D01*
X761519Y-237730D01*
X762977Y-237420D01*
X764435Y-236645D01*
X765269Y-235715D01*
X765477Y-234630D01*
X765061Y-233390D01*
X764019Y-232460D01*
X762144Y-231530D01*
G01X767977Y-225640D02*
X769019Y-224710D01*
X769644Y-223625D01*
X769852Y-222230D01*
X769435Y-220835D01*
X768602Y-219750D01*
X767144Y-218975D01*
X765477Y-218820D01*
X763810Y-219130D01*
X762769Y-219905D01*
X761935Y-220990D01*
X761727Y-222075D01*
X761935Y-223160D01*
X762769Y-224555D01*
X757352Y-224090D01*
Y-219905D01*
G01X797928Y-394310D02*
X795220Y-394000D01*
X792928Y-393535D01*
X790845Y-392915D01*
X788553Y-392140D01*
X785428Y-390900D01*
Y-397100D01*
G01X796470Y-384235D02*
X797511Y-383150D01*
X797928Y-381910D01*
X797511Y-380670D01*
X796262Y-379585D01*
X794386Y-378810D01*
X792511Y-378500D01*
X790220D01*
X788345Y-378810D01*
X786678Y-379585D01*
X785845Y-380515D01*
X785428Y-381600D01*
X785845Y-382840D01*
X786678Y-383770D01*
X787928Y-384390D01*
X789595Y-384700D01*
X791053Y-384390D01*
X792511Y-383615D01*
X793345Y-382685D01*
X793553Y-381600D01*
X793137Y-380360D01*
X792095Y-379430D01*
X790220Y-378500D01*
G01X797928Y-369200D02*
X785428D01*
X787928Y-371060D01*
G01X797928D02*
Y-367340D01*
G01X792720Y-359745D02*
X791261Y-358660D01*
X790428Y-357730D01*
X790011Y-356490D01*
X790428Y-355405D01*
X791261Y-354630D01*
X792511Y-354010D01*
X793970Y-353855D01*
X795220Y-354010D01*
X796470Y-354630D01*
X797511Y-355560D01*
X797928Y-356645D01*
X797511Y-357885D01*
X796262Y-358970D01*
X794386Y-359590D01*
X792303Y-359745D01*
X789595Y-359435D01*
X788136Y-358970D01*
X786678Y-358195D01*
X785636Y-357110D01*
X785428Y-356025D01*
X785845Y-354940D01*
X786886Y-354165D01*
G01X798345Y-344400D02*
X798136Y-344710D01*
X797720D01*
X797511Y-344400D01*
X797720Y-344090D01*
X798136D01*
X798345Y-344400D01*
G01X797928Y-332310D02*
X795220Y-332000D01*
X792928Y-331535D01*
X790845Y-330915D01*
X788553Y-330140D01*
X785428Y-328900D01*
Y-335100D01*
G01X797928Y-319600D02*
X797720Y-318515D01*
X797095Y-317275D01*
X796053Y-316500D01*
X794595Y-316190D01*
X793137Y-316500D01*
X791886Y-317430D01*
X791261Y-318825D01*
Y-320375D01*
X790845Y-321305D01*
X789803Y-322080D01*
X788345Y-322390D01*
X786886Y-321925D01*
X785845Y-320840D01*
X785428Y-319600D01*
X785845Y-318360D01*
X786886Y-317275D01*
X788345Y-316810D01*
X789803Y-317120D01*
X790845Y-317895D01*
X791261Y-318825D01*
Y-320375D01*
X791886Y-321770D01*
X793137Y-322700D01*
X794595Y-323010D01*
X796053Y-322700D01*
X797095Y-321925D01*
X797720Y-320685D01*
X797928Y-319600D01*
G01X787511Y-287945D02*
X786262Y-287015D01*
X785636Y-285930D01*
X785428Y-284690D01*
X785845Y-283140D01*
X786886Y-282055D01*
X788136Y-281745D01*
X789387Y-281900D01*
X790428Y-282520D01*
X792511Y-285620D01*
X793970Y-287015D01*
X796053Y-287945D01*
X797928Y-288255D01*
Y-281745D01*
G01X785428Y-272600D02*
X785845Y-273840D01*
X786886Y-274770D01*
X788136Y-275390D01*
X789803Y-275855D01*
X791678Y-276010D01*
X793553Y-275855D01*
X795220Y-275390D01*
X796470Y-274770D01*
X797511Y-273840D01*
X797928Y-272600D01*
X797511Y-271360D01*
X796470Y-270430D01*
X795220Y-269810D01*
X793553Y-269345D01*
X791678Y-269190D01*
X789803Y-269345D01*
X788136Y-269810D01*
X786886Y-270430D01*
X785845Y-271360D01*
X785428Y-272600D01*
G01X797928Y-260200D02*
X785428D01*
X787928Y-262060D01*
G01X797928D02*
Y-258340D01*
G01X798345Y-247800D02*
X798136Y-248110D01*
X797720D01*
X797511Y-247800D01*
X797720Y-247490D01*
X798136D01*
X798345Y-247800D01*
G01X785428Y-235400D02*
X785845Y-236640D01*
X786886Y-237570D01*
X788136Y-238190D01*
X789803Y-238655D01*
X791678Y-238810D01*
X793553Y-238655D01*
X795220Y-238190D01*
X796470Y-237570D01*
X797511Y-236640D01*
X797928Y-235400D01*
X797511Y-234160D01*
X796470Y-233230D01*
X795220Y-232610D01*
X793553Y-232145D01*
X791678Y-231990D01*
X789803Y-232145D01*
X788136Y-232610D01*
X786886Y-233230D01*
X785845Y-234160D01*
X785428Y-235400D01*
G01X796470Y-225635D02*
X797511Y-224550D01*
X797928Y-223310D01*
X797511Y-222070D01*
X796262Y-220985D01*
X794386Y-220210D01*
X792511Y-219900D01*
X790220D01*
X788345Y-220210D01*
X786678Y-220985D01*
X785845Y-221915D01*
X785428Y-223000D01*
X785845Y-224240D01*
X786678Y-225170D01*
X787928Y-225790D01*
X789595Y-226100D01*
X791053Y-225790D01*
X792511Y-225015D01*
X793345Y-224085D01*
X793553Y-223000D01*
X793137Y-221760D01*
X792095Y-220830D01*
X790220Y-219900D01*
G01X820300Y-381640D02*
X820092Y-380555D01*
X819467Y-379315D01*
X818425Y-378540D01*
X816967Y-378230D01*
X815509Y-378540D01*
X814258Y-379470D01*
X813633Y-380865D01*
Y-382415D01*
X813217Y-383345D01*
X812175Y-384120D01*
X810717Y-384430D01*
X809258Y-383965D01*
X808217Y-382880D01*
X807800Y-381640D01*
X808217Y-380400D01*
X809258Y-379315D01*
X810717Y-378850D01*
X812175Y-379160D01*
X813217Y-379935D01*
X813633Y-380865D01*
Y-382415D01*
X814258Y-383810D01*
X815509Y-384740D01*
X816967Y-385050D01*
X818425Y-384740D01*
X819467Y-383965D01*
X820092Y-382725D01*
X820300Y-381640D01*
G01X807800Y-369240D02*
X808217Y-370480D01*
X809258Y-371410D01*
X810508Y-372030D01*
X812175Y-372495D01*
X814050Y-372650D01*
X815925Y-372495D01*
X817592Y-372030D01*
X818842Y-371410D01*
X819883Y-370480D01*
X820300Y-369240D01*
X819883Y-368000D01*
X818842Y-367070D01*
X817592Y-366450D01*
X815925Y-365985D01*
X814050Y-365830D01*
X812175Y-365985D01*
X810508Y-366450D01*
X809258Y-367070D01*
X808217Y-368000D01*
X807800Y-369240D01*
G01Y-356840D02*
X808217Y-358080D01*
X809258Y-359010D01*
X810508Y-359630D01*
X812175Y-360095D01*
X814050Y-360250D01*
X815925Y-360095D01*
X817592Y-359630D01*
X818842Y-359010D01*
X819883Y-358080D01*
X820300Y-356840D01*
X819883Y-355600D01*
X818842Y-354670D01*
X817592Y-354050D01*
X815925Y-353585D01*
X814050Y-353430D01*
X812175Y-353585D01*
X810508Y-354050D01*
X809258Y-354670D01*
X808217Y-355600D01*
X807800Y-356840D01*
G01X820300Y-344750D02*
X817592Y-344440D01*
X815300Y-343975D01*
X813217Y-343355D01*
X810925Y-342580D01*
X807800Y-341340D01*
Y-347540D01*
G01X820717Y-332040D02*
X820508Y-332350D01*
X820092D01*
X819883Y-332040D01*
X820092Y-331730D01*
X820508D01*
X820717Y-332040D01*
G01X820300Y-319640D02*
X820092Y-318555D01*
X819467Y-317315D01*
X818425Y-316540D01*
X816967Y-316230D01*
X815509Y-316540D01*
X814258Y-317470D01*
X813633Y-318865D01*
Y-320415D01*
X813217Y-321345D01*
X812175Y-322120D01*
X810717Y-322430D01*
X809258Y-321965D01*
X808217Y-320880D01*
X807800Y-319640D01*
X808217Y-318400D01*
X809258Y-317315D01*
X810717Y-316850D01*
X812175Y-317160D01*
X813217Y-317935D01*
X813633Y-318865D01*
Y-320415D01*
X814258Y-321810D01*
X815509Y-322740D01*
X816967Y-323050D01*
X818425Y-322740D01*
X819467Y-321965D01*
X820092Y-320725D01*
X820300Y-319640D01*
G01Y-307550D02*
X817592Y-307240D01*
X815300Y-306775D01*
X813217Y-306155D01*
X810925Y-305380D01*
X807800Y-304140D01*
Y-310340D01*
G01X809883Y-275585D02*
X808634Y-274655D01*
X808008Y-273570D01*
X807800Y-272330D01*
X808217Y-270780D01*
X809258Y-269695D01*
X810508Y-269385D01*
X811759Y-269540D01*
X812800Y-270160D01*
X814883Y-273260D01*
X816342Y-274655D01*
X818425Y-275585D01*
X820300Y-275895D01*
Y-269385D01*
G01X807800Y-260240D02*
X808217Y-261480D01*
X809258Y-262410D01*
X810508Y-263030D01*
X812175Y-263495D01*
X814050Y-263650D01*
X815925Y-263495D01*
X817592Y-263030D01*
X818842Y-262410D01*
X819883Y-261480D01*
X820300Y-260240D01*
X819883Y-259000D01*
X818842Y-258070D01*
X817592Y-257450D01*
X815925Y-256985D01*
X814050Y-256830D01*
X812175Y-256985D01*
X810508Y-257450D01*
X809258Y-258070D01*
X808217Y-259000D01*
X807800Y-260240D01*
G01X817800Y-251250D02*
X819259Y-250320D01*
X820092Y-249080D01*
X820300Y-247685D01*
X820092Y-246445D01*
X819050Y-245205D01*
X817800Y-244430D01*
X816550Y-244275D01*
X815092Y-244585D01*
X814050Y-245670D01*
X813633Y-246755D01*
Y-248150D01*
G01Y-246755D02*
X813008Y-245825D01*
X811967Y-245050D01*
X810717Y-244740D01*
X809467Y-245050D01*
X808425Y-245825D01*
X807800Y-247220D01*
X808008Y-248615D01*
X808842Y-250010D01*
G01X820717Y-235440D02*
X820508Y-235750D01*
X820092D01*
X819883Y-235440D01*
X820092Y-235130D01*
X820508D01*
X820717Y-235440D01*
G01X820300Y-221180D02*
X807800D01*
X816758Y-226915D01*
Y-219165D01*
G01X841880Y-394770D02*
X841672Y-393685D01*
X841047Y-392445D01*
X840005Y-391670D01*
X838547Y-391360D01*
X837089Y-391670D01*
X835838Y-392600D01*
X835213Y-393995D01*
Y-395545D01*
X834797Y-396475D01*
X833755Y-397250D01*
X832297Y-397560D01*
X830838Y-397095D01*
X829797Y-396010D01*
X829380Y-394770D01*
X829797Y-393530D01*
X830838Y-392445D01*
X832297Y-391980D01*
X833755Y-392290D01*
X834797Y-393065D01*
X835213Y-393995D01*
Y-395545D01*
X835838Y-396940D01*
X837089Y-397870D01*
X838547Y-398180D01*
X840005Y-397870D01*
X841047Y-397095D01*
X841672Y-395855D01*
X841880Y-394770D01*
G01X829380Y-382370D02*
X829797Y-383610D01*
X830838Y-384540D01*
X832088Y-385160D01*
X833755Y-385625D01*
X835630Y-385780D01*
X837505Y-385625D01*
X839172Y-385160D01*
X840422Y-384540D01*
X841463Y-383610D01*
X841880Y-382370D01*
X841463Y-381130D01*
X840422Y-380200D01*
X839172Y-379580D01*
X837505Y-379115D01*
X835630Y-378960D01*
X833755Y-379115D01*
X832088Y-379580D01*
X830838Y-380200D01*
X829797Y-381130D01*
X829380Y-382370D01*
G01X840005Y-373380D02*
X841047Y-372450D01*
X841672Y-371365D01*
X841880Y-369970D01*
X841463Y-368575D01*
X840630Y-367490D01*
X839172Y-366715D01*
X837505Y-366560D01*
X835838Y-366870D01*
X834797Y-367645D01*
X833963Y-368730D01*
X833755Y-369815D01*
X833963Y-370900D01*
X834797Y-372295D01*
X829380Y-371830D01*
Y-367645D01*
G01X836672Y-360515D02*
X835213Y-359430D01*
X834380Y-358500D01*
X833963Y-357260D01*
X834380Y-356175D01*
X835213Y-355400D01*
X836463Y-354780D01*
X837922Y-354625D01*
X839172Y-354780D01*
X840422Y-355400D01*
X841463Y-356330D01*
X841880Y-357415D01*
X841463Y-358655D01*
X840214Y-359740D01*
X838338Y-360360D01*
X836255Y-360515D01*
X833547Y-360205D01*
X832088Y-359740D01*
X830630Y-358965D01*
X829588Y-357880D01*
X829380Y-356795D01*
X829797Y-355710D01*
X830838Y-354935D01*
G01X842297Y-345170D02*
X842088Y-345480D01*
X841672D01*
X841463Y-345170D01*
X841672Y-344860D01*
X842088D01*
X842297Y-345170D01*
G01X840422Y-335405D02*
X841463Y-334320D01*
X841880Y-333080D01*
X841463Y-331840D01*
X840214Y-330755D01*
X838338Y-329980D01*
X836463Y-329670D01*
X834172D01*
X832297Y-329980D01*
X830630Y-330755D01*
X829797Y-331685D01*
X829380Y-332770D01*
X829797Y-334010D01*
X830630Y-334940D01*
X831880Y-335560D01*
X833547Y-335870D01*
X835005Y-335560D01*
X836463Y-334785D01*
X837297Y-333855D01*
X837505Y-332770D01*
X837089Y-331530D01*
X836047Y-330600D01*
X834172Y-329670D01*
G01X829380Y-320370D02*
X829797Y-321610D01*
X830838Y-322540D01*
X832088Y-323160D01*
X833755Y-323625D01*
X835630Y-323780D01*
X837505Y-323625D01*
X839172Y-323160D01*
X840422Y-322540D01*
X841463Y-321610D01*
X841880Y-320370D01*
X841463Y-319130D01*
X840422Y-318200D01*
X839172Y-317580D01*
X837505Y-317115D01*
X835630Y-316960D01*
X833755Y-317115D01*
X832088Y-317580D01*
X830838Y-318200D01*
X829797Y-319130D01*
X829380Y-320370D01*
G01X831463Y-288715D02*
X830214Y-287785D01*
X829588Y-286700D01*
X829380Y-285460D01*
X829797Y-283910D01*
X830838Y-282825D01*
X832088Y-282515D01*
X833339Y-282670D01*
X834380Y-283290D01*
X836463Y-286390D01*
X837922Y-287785D01*
X840005Y-288715D01*
X841880Y-289025D01*
Y-282515D01*
G01X829380Y-273370D02*
X829797Y-274610D01*
X830838Y-275540D01*
X832088Y-276160D01*
X833755Y-276625D01*
X835630Y-276780D01*
X837505Y-276625D01*
X839172Y-276160D01*
X840422Y-275540D01*
X841463Y-274610D01*
X841880Y-273370D01*
X841463Y-272130D01*
X840422Y-271200D01*
X839172Y-270580D01*
X837505Y-270115D01*
X835630Y-269960D01*
X833755Y-270115D01*
X832088Y-270580D01*
X830838Y-271200D01*
X829797Y-272130D01*
X829380Y-273370D01*
G01X841880Y-259110D02*
X829380D01*
X838338Y-264845D01*
Y-257095D01*
G01X842297Y-248570D02*
X842088Y-248880D01*
X841672D01*
X841463Y-248570D01*
X841672Y-248260D01*
X842088D01*
X842297Y-248570D01*
G01X836672Y-239115D02*
X835213Y-238030D01*
X834380Y-237100D01*
X833963Y-235860D01*
X834380Y-234775D01*
X835213Y-234000D01*
X836463Y-233380D01*
X837922Y-233225D01*
X839172Y-233380D01*
X840422Y-234000D01*
X841463Y-234930D01*
X841880Y-236015D01*
X841463Y-237255D01*
X840214Y-238340D01*
X838338Y-238960D01*
X836255Y-239115D01*
X833547Y-238805D01*
X832088Y-238340D01*
X830630Y-237565D01*
X829588Y-236480D01*
X829380Y-235395D01*
X829797Y-234310D01*
X830838Y-233535D01*
G01X840005Y-227180D02*
X841047Y-226250D01*
X841672Y-225165D01*
X841880Y-223770D01*
X841463Y-222375D01*
X840630Y-221290D01*
X839172Y-220515D01*
X837505Y-220360D01*
X835838Y-220670D01*
X834797Y-221445D01*
X833963Y-222530D01*
X833755Y-223615D01*
X833963Y-224700D01*
X834797Y-226095D01*
X829380Y-225630D01*
Y-221445D01*
G01X845340Y1786368D02*
Y1798868D01*
X843480Y1796368D01*
G01Y1786368D02*
X847200D01*
G01X857740D02*
X858825Y1786576D01*
X860065Y1787201D01*
X860840Y1788243D01*
X861150Y1789701D01*
X860840Y1791159D01*
X859910Y1792410D01*
X858515Y1793035D01*
X856965D01*
X856035Y1793451D01*
X855260Y1794493D01*
X854950Y1795951D01*
X855415Y1797410D01*
X856500Y1798451D01*
X857740Y1798868D01*
X858980Y1798451D01*
X860065Y1797410D01*
X860530Y1795951D01*
X860220Y1794493D01*
X859445Y1793451D01*
X858515Y1793035D01*
X856965D01*
X855570Y1792410D01*
X854640Y1791159D01*
X854330Y1789701D01*
X854640Y1788243D01*
X855415Y1787201D01*
X856655Y1786576D01*
X857740Y1786368D01*
G01X866730Y1788243D02*
X867660Y1787201D01*
X868745Y1786576D01*
X870140Y1786368D01*
X871535Y1786785D01*
X872620Y1787618D01*
X873395Y1789076D01*
X873550Y1790743D01*
X873240Y1792410D01*
X872465Y1793451D01*
X871380Y1794285D01*
X870295Y1794493D01*
X869210Y1794285D01*
X867815Y1793451D01*
X868280Y1798868D01*
X872465D01*
G01X882230Y1786368D02*
X882540Y1789076D01*
X883005Y1791368D01*
X883625Y1793451D01*
X884400Y1795743D01*
X885640Y1798868D01*
X879440D01*
G01X896800Y1786368D02*
Y1798868D01*
X891065Y1789910D01*
X898815D01*
G01X907340Y1785951D02*
X907030Y1786160D01*
Y1786576D01*
X907340Y1786785D01*
X907650Y1786576D01*
Y1786160D01*
X907340Y1785951D01*
G01X919740Y1786368D02*
X920825Y1786576D01*
X922065Y1787201D01*
X922840Y1788243D01*
X923150Y1789701D01*
X922840Y1791159D01*
X921910Y1792410D01*
X920515Y1793035D01*
X918965D01*
X918035Y1793451D01*
X917260Y1794493D01*
X916950Y1795951D01*
X917415Y1797410D01*
X918500Y1798451D01*
X919740Y1798868D01*
X920980Y1798451D01*
X922065Y1797410D01*
X922530Y1795951D01*
X922220Y1794493D01*
X921445Y1793451D01*
X920515Y1793035D01*
X918965D01*
X917570Y1792410D01*
X916640Y1791159D01*
X916330Y1789701D01*
X916640Y1788243D01*
X917415Y1787201D01*
X918655Y1786576D01*
X919740Y1786368D01*
G01X932140Y1798868D02*
X930900Y1798451D01*
X929970Y1797410D01*
X929350Y1796160D01*
X928885Y1794493D01*
X928730Y1792618D01*
X928885Y1790743D01*
X929350Y1789076D01*
X929970Y1787826D01*
X930900Y1786785D01*
X932140Y1786368D01*
X933380Y1786785D01*
X934310Y1787826D01*
X934930Y1789076D01*
X935395Y1790743D01*
X935550Y1792618D01*
X935395Y1794493D01*
X934930Y1796160D01*
X934310Y1797410D01*
X933380Y1798451D01*
X932140Y1798868D01*
G01X865770Y-393230D02*
X865562Y-392145D01*
X864937Y-390905D01*
X863895Y-390130D01*
X862437Y-389820D01*
X860979Y-390130D01*
X859728Y-391060D01*
X859103Y-392455D01*
Y-394005D01*
X858687Y-394935D01*
X857645Y-395710D01*
X856187Y-396020D01*
X854728Y-395555D01*
X853687Y-394470D01*
X853270Y-393230D01*
X853687Y-391990D01*
X854728Y-390905D01*
X856187Y-390440D01*
X857645Y-390750D01*
X858687Y-391525D01*
X859103Y-392455D01*
Y-394005D01*
X859728Y-395400D01*
X860979Y-396330D01*
X862437Y-396640D01*
X863895Y-396330D01*
X864937Y-395555D01*
X865562Y-394315D01*
X865770Y-393230D01*
G01Y-378970D02*
X853270D01*
X862228Y-384705D01*
Y-376955D01*
G01X865770Y-368430D02*
X853270D01*
X855770Y-370290D01*
G01X865770D02*
Y-366570D01*
G01X855353Y-358975D02*
X854104Y-358045D01*
X853478Y-356960D01*
X853270Y-355720D01*
X853687Y-354170D01*
X854728Y-353085D01*
X855978Y-352775D01*
X857229Y-352930D01*
X858270Y-353550D01*
X860353Y-356650D01*
X861812Y-358045D01*
X863895Y-358975D01*
X865770Y-359285D01*
Y-352775D01*
G01X866187Y-343630D02*
X865978Y-343940D01*
X865562D01*
X865353Y-343630D01*
X865562Y-343320D01*
X865978D01*
X866187Y-343630D01*
G01X865770Y-329370D02*
X853270D01*
X862228Y-335105D01*
Y-327355D01*
G01X853270Y-318830D02*
X853687Y-320070D01*
X854728Y-321000D01*
X855978Y-321620D01*
X857645Y-322085D01*
X859520Y-322240D01*
X861395Y-322085D01*
X863062Y-321620D01*
X864312Y-321000D01*
X865353Y-320070D01*
X865770Y-318830D01*
X865353Y-317590D01*
X864312Y-316660D01*
X863062Y-316040D01*
X861395Y-315575D01*
X859520Y-315420D01*
X857645Y-315575D01*
X855978Y-316040D01*
X854728Y-316660D01*
X853687Y-317590D01*
X853270Y-318830D01*
G01X855353Y-287175D02*
X854104Y-286245D01*
X853478Y-285160D01*
X853270Y-283920D01*
X853687Y-282370D01*
X854728Y-281285D01*
X855978Y-280975D01*
X857229Y-281130D01*
X858270Y-281750D01*
X860353Y-284850D01*
X861812Y-286245D01*
X863895Y-287175D01*
X865770Y-287485D01*
Y-280975D01*
G01Y-271830D02*
X853270D01*
X855770Y-273690D01*
G01X865770D02*
Y-269970D01*
G01X863270Y-262840D02*
X864729Y-261910D01*
X865562Y-260670D01*
X865770Y-259275D01*
X865562Y-258035D01*
X864520Y-256795D01*
X863270Y-256020D01*
X862020Y-255865D01*
X860562Y-256175D01*
X859520Y-257260D01*
X859103Y-258345D01*
Y-259740D01*
G01Y-258345D02*
X858478Y-257415D01*
X857437Y-256640D01*
X856187Y-256330D01*
X854937Y-256640D01*
X853895Y-257415D01*
X853270Y-258810D01*
X853478Y-260205D01*
X854312Y-261600D01*
G01X866187Y-247030D02*
X865978Y-247340D01*
X865562D01*
X865353Y-247030D01*
X865562Y-246720D01*
X865978D01*
X866187Y-247030D01*
G01X860562Y-237575D02*
X859103Y-236490D01*
X858270Y-235560D01*
X857853Y-234320D01*
X858270Y-233235D01*
X859103Y-232460D01*
X860353Y-231840D01*
X861812Y-231685D01*
X863062Y-231840D01*
X864312Y-232460D01*
X865353Y-233390D01*
X865770Y-234475D01*
X865353Y-235715D01*
X864104Y-236800D01*
X862228Y-237420D01*
X860145Y-237575D01*
X857437Y-237265D01*
X855978Y-236800D01*
X854520Y-236025D01*
X853478Y-234940D01*
X853270Y-233855D01*
X853687Y-232770D01*
X854728Y-231995D01*
G01X865770Y-222540D02*
X863062Y-222230D01*
X860770Y-221765D01*
X858687Y-221145D01*
X856395Y-220370D01*
X853270Y-219130D01*
Y-225330D01*
G01X865950Y1761368D02*
Y1773868D01*
X860215Y1764910D01*
X867965D01*
G01X876180Y1761368D02*
X876490Y1764076D01*
X876955Y1766368D01*
X877575Y1768451D01*
X878350Y1770743D01*
X879590Y1773868D01*
X873390D01*
G01X888890Y1761368D02*
Y1773868D01*
X887030Y1771368D01*
G01Y1761368D02*
X890750D01*
G01X901290Y1760951D02*
X900980Y1761160D01*
Y1761576D01*
X901290Y1761785D01*
X901600Y1761576D01*
Y1761160D01*
X901290Y1760951D01*
G01X913690Y1761368D02*
X914775Y1761576D01*
X916015Y1762201D01*
X916790Y1763243D01*
X917100Y1764701D01*
X916790Y1766159D01*
X915860Y1767410D01*
X914465Y1768035D01*
X912915D01*
X911985Y1768451D01*
X911210Y1769493D01*
X910900Y1770951D01*
X911365Y1772410D01*
X912450Y1773451D01*
X913690Y1773868D01*
X914930Y1773451D01*
X916015Y1772410D01*
X916480Y1770951D01*
X916170Y1769493D01*
X915395Y1768451D01*
X914465Y1768035D01*
X912915D01*
X911520Y1767410D01*
X910590Y1766159D01*
X910280Y1764701D01*
X910590Y1763243D01*
X911365Y1762201D01*
X912605Y1761576D01*
X913690Y1761368D01*
G01X904989Y-395865D02*
X906030Y-394780D01*
X906447Y-393540D01*
X906030Y-392300D01*
X904781Y-391215D01*
X902905Y-390440D01*
X901030Y-390130D01*
X898739D01*
X896864Y-390440D01*
X895197Y-391215D01*
X894364Y-392145D01*
X893947Y-393230D01*
X894364Y-394470D01*
X895197Y-395400D01*
X896447Y-396020D01*
X898114Y-396330D01*
X899572Y-396020D01*
X901030Y-395245D01*
X901864Y-394315D01*
X902072Y-393230D01*
X901656Y-391990D01*
X900614Y-391060D01*
X898739Y-390130D01*
G01X893947Y-380830D02*
X894364Y-382070D01*
X895405Y-383000D01*
X896655Y-383620D01*
X898322Y-384085D01*
X900197Y-384240D01*
X902072Y-384085D01*
X903739Y-383620D01*
X904989Y-383000D01*
X906030Y-382070D01*
X906447Y-380830D01*
X906030Y-379590D01*
X904989Y-378660D01*
X903739Y-378040D01*
X902072Y-377575D01*
X900197Y-377420D01*
X898322Y-377575D01*
X896655Y-378040D01*
X895405Y-378660D01*
X894364Y-379590D01*
X893947Y-380830D01*
G01Y-368430D02*
X894364Y-369670D01*
X895405Y-370600D01*
X896655Y-371220D01*
X898322Y-371685D01*
X900197Y-371840D01*
X902072Y-371685D01*
X903739Y-371220D01*
X904989Y-370600D01*
X906030Y-369670D01*
X906447Y-368430D01*
X906030Y-367190D01*
X904989Y-366260D01*
X903739Y-365640D01*
X902072Y-365175D01*
X900197Y-365020D01*
X898322Y-365175D01*
X896655Y-365640D01*
X895405Y-366260D01*
X894364Y-367190D01*
X893947Y-368430D01*
G01X906447Y-356030D02*
X893947D01*
X896447Y-357890D01*
G01X906447D02*
Y-354170D01*
G01X906864Y-343630D02*
X906655Y-343940D01*
X906239D01*
X906030Y-343630D01*
X906239Y-343320D01*
X906655D01*
X906864Y-343630D01*
G01X904989Y-333865D02*
X906030Y-332780D01*
X906447Y-331540D01*
X906030Y-330300D01*
X904781Y-329215D01*
X902905Y-328440D01*
X901030Y-328130D01*
X898739D01*
X896864Y-328440D01*
X895197Y-329215D01*
X894364Y-330145D01*
X893947Y-331230D01*
X894364Y-332470D01*
X895197Y-333400D01*
X896447Y-334020D01*
X898114Y-334330D01*
X899572Y-334020D01*
X901030Y-333245D01*
X901864Y-332315D01*
X902072Y-331230D01*
X901656Y-329990D01*
X900614Y-329060D01*
X898739Y-328130D01*
G01X906447Y-319140D02*
X903739Y-318830D01*
X901447Y-318365D01*
X899364Y-317745D01*
X897072Y-316970D01*
X893947Y-315730D01*
Y-321930D01*
G01X896030Y-287175D02*
X894781Y-286245D01*
X894155Y-285160D01*
X893947Y-283920D01*
X894364Y-282370D01*
X895405Y-281285D01*
X896655Y-280975D01*
X897906Y-281130D01*
X898947Y-281750D01*
X901030Y-284850D01*
X902489Y-286245D01*
X904572Y-287175D01*
X906447Y-287485D01*
Y-280975D01*
G01X896030Y-274775D02*
X894781Y-273845D01*
X894155Y-272760D01*
X893947Y-271520D01*
X894364Y-269970D01*
X895405Y-268885D01*
X896655Y-268575D01*
X897906Y-268730D01*
X898947Y-269350D01*
X901030Y-272450D01*
X902489Y-273845D01*
X904572Y-274775D01*
X906447Y-275085D01*
Y-268575D01*
G01Y-259430D02*
X906239Y-258345D01*
X905614Y-257105D01*
X904572Y-256330D01*
X903114Y-256020D01*
X901656Y-256330D01*
X900405Y-257260D01*
X899780Y-258655D01*
Y-260205D01*
X899364Y-261135D01*
X898322Y-261910D01*
X896864Y-262220D01*
X895405Y-261755D01*
X894364Y-260670D01*
X893947Y-259430D01*
X894364Y-258190D01*
X895405Y-257105D01*
X896864Y-256640D01*
X898322Y-256950D01*
X899364Y-257725D01*
X899780Y-258655D01*
Y-260205D01*
X900405Y-261600D01*
X901656Y-262530D01*
X903114Y-262840D01*
X904572Y-262530D01*
X905614Y-261755D01*
X906239Y-260515D01*
X906447Y-259430D01*
G01X906864Y-247030D02*
X906655Y-247340D01*
X906239D01*
X906030Y-247030D01*
X906239Y-246720D01*
X906655D01*
X906864Y-247030D01*
G01X901239Y-237575D02*
X899780Y-236490D01*
X898947Y-235560D01*
X898530Y-234320D01*
X898947Y-233235D01*
X899780Y-232460D01*
X901030Y-231840D01*
X902489Y-231685D01*
X903739Y-231840D01*
X904989Y-232460D01*
X906030Y-233390D01*
X906447Y-234475D01*
X906030Y-235715D01*
X904781Y-236800D01*
X902905Y-237420D01*
X900822Y-237575D01*
X898114Y-237265D01*
X896655Y-236800D01*
X895197Y-236025D01*
X894155Y-234940D01*
X893947Y-233855D01*
X894364Y-232770D01*
X895405Y-231995D01*
G01X904572Y-225640D02*
X905614Y-224710D01*
X906239Y-223625D01*
X906447Y-222230D01*
X906030Y-220835D01*
X905197Y-219750D01*
X903739Y-218975D01*
X902072Y-218820D01*
X900405Y-219130D01*
X899364Y-219905D01*
X898530Y-220990D01*
X898322Y-222075D01*
X898530Y-223160D01*
X899364Y-224555D01*
X893947Y-224090D01*
Y-219905D01*
G01X904542Y1927553D02*
X897042D01*
Y1929887D01*
X897417Y1930633D01*
X897917Y1931100D01*
X898917Y1931287D01*
X899917Y1931100D01*
X900542Y1930540D01*
X900917Y1929887D01*
Y1927553D01*
G01Y1929887D02*
X904542Y1931287D01*
G01Y1938787D02*
Y1935053D01*
X897042D01*
Y1938787D01*
G01X900667Y1937293D02*
Y1935053D01*
G01X897667Y1946473D02*
X897292Y1945913D01*
X897042Y1945260D01*
Y1944513D01*
X897417Y1943673D01*
X898042Y1943020D01*
X898792Y1942553D01*
X900042Y1942180D01*
X901167Y1942087D01*
X902292Y1942273D01*
X903042Y1942553D01*
X903792Y1943113D01*
X904292Y1943767D01*
X904542Y1944420D01*
Y1945073D01*
X904292Y1945727D01*
X903917Y1946287D01*
X903417Y1946753D01*
G01X904542Y1951920D02*
X904417Y1951173D01*
X903917Y1950520D01*
X903167Y1949960D01*
X902292Y1949587D01*
X901292Y1949400D01*
X900292D01*
X899292Y1949587D01*
X898417Y1949960D01*
X897667Y1950520D01*
X897167Y1951173D01*
X897042Y1951920D01*
X897167Y1952667D01*
X897667Y1953320D01*
X898417Y1953880D01*
X899292Y1954253D01*
X900292Y1954440D01*
X901292D01*
X902292Y1954253D01*
X903167Y1953880D01*
X903917Y1953320D01*
X904417Y1952667D01*
X904542Y1951920D01*
G01Y1956993D02*
X897042D01*
X903292Y1959420D01*
X897042Y1961847D01*
X904542D01*
G01Y1964493D02*
X897042D01*
X903292Y1966920D01*
X897042Y1969347D01*
X904542D01*
G01Y1976287D02*
Y1972553D01*
X897042D01*
Y1976287D01*
G01X900667Y1974793D02*
Y1972553D01*
G01X904542Y1979773D02*
X897042D01*
X904542Y1984067D01*
X897042D01*
G01X904542Y1987367D02*
X897042D01*
Y1989233D01*
X897417Y1989980D01*
X897917Y1990540D01*
X898667Y1991007D01*
X899542Y1991380D01*
X900792Y1991473D01*
X902042Y1991380D01*
X902917Y1991007D01*
X903667Y1990540D01*
X904167Y1989980D01*
X904542Y1989233D01*
Y1987367D01*
G01Y1998787D02*
Y1995053D01*
X897042D01*
Y1998787D01*
G01X900667Y1997293D02*
Y1995053D01*
G01X904542Y2002367D02*
X897042D01*
Y2004233D01*
X897417Y2004980D01*
X897917Y2005540D01*
X898667Y2006007D01*
X899542Y2006380D01*
X900792Y2006473D01*
X902042Y2006380D01*
X902917Y2006007D01*
X903667Y2005540D01*
X904167Y2004980D01*
X904542Y2004233D01*
Y2002367D01*
G01Y2017367D02*
X897042D01*
Y2019233D01*
X897417Y2019980D01*
X897917Y2020540D01*
X898667Y2021007D01*
X899542Y2021380D01*
X900792Y2021473D01*
X902042Y2021380D01*
X902917Y2021007D01*
X903667Y2020540D01*
X904167Y2019980D01*
X904542Y2019233D01*
Y2017367D01*
G01Y2025053D02*
X897042D01*
Y2027387D01*
X897417Y2028133D01*
X897917Y2028600D01*
X898917Y2028787D01*
X899917Y2028600D01*
X900542Y2028040D01*
X900917Y2027387D01*
Y2025053D01*
G01Y2027387D02*
X904542Y2028787D01*
G01X897042Y2033300D02*
Y2035540D01*
G01Y2034420D02*
X904542D01*
G01Y2033300D02*
Y2035540D01*
G01X897042Y2040053D02*
X904542D01*
Y2043787D01*
G01X897042Y2047553D02*
X904542D01*
Y2051287D01*
G01X903542Y2062460D02*
X904167Y2063207D01*
X904542Y2064047D01*
Y2064793D01*
X904167Y2065540D01*
X903542Y2066100D01*
X902667Y2066380D01*
X901792Y2066193D01*
X901042Y2065727D01*
X900542Y2064887D01*
X900292Y2063767D01*
X899792Y2063113D01*
X898917Y2062833D01*
X898042Y2063020D01*
X897417Y2063487D01*
X897042Y2064140D01*
Y2064793D01*
X897292Y2065447D01*
X897917Y2066007D01*
G01X897042Y2070800D02*
Y2073040D01*
G01Y2071920D02*
X904542D01*
G01Y2070800D02*
Y2073040D01*
G01X897042Y2077647D02*
Y2081193D01*
X904542Y2077647D01*
Y2081193D01*
G01Y2088787D02*
Y2085053D01*
X897042D01*
Y2088787D01*
G01X900667Y2087293D02*
Y2085053D01*
G01X904542Y2100147D02*
X897042D01*
Y2103693D01*
G01X900667Y2102387D02*
Y2100147D01*
G01X904542Y2109420D02*
X904417Y2108673D01*
X903917Y2108020D01*
X903167Y2107460D01*
X902292Y2107087D01*
X901292Y2106900D01*
X900292D01*
X899292Y2107087D01*
X898417Y2107460D01*
X897667Y2108020D01*
X897167Y2108673D01*
X897042Y2109420D01*
X897167Y2110167D01*
X897667Y2110820D01*
X898417Y2111380D01*
X899292Y2111753D01*
X900292Y2111940D01*
X901292D01*
X902292Y2111753D01*
X903167Y2111380D01*
X903917Y2110820D01*
X904417Y2110167D01*
X904542Y2109420D01*
G01Y2115053D02*
X897042D01*
Y2117387D01*
X897417Y2118133D01*
X897917Y2118600D01*
X898917Y2118787D01*
X899917Y2118600D01*
X900542Y2118040D01*
X900917Y2117387D01*
Y2115053D01*
G01Y2117387D02*
X904542Y2118787D01*
G01Y2131920D02*
X897042D01*
X898542Y2130800D01*
G01X904542D02*
Y2133040D01*
G01X904792Y2139420D02*
X904667Y2139233D01*
X904417D01*
X904292Y2139420D01*
X904417Y2139607D01*
X904667D01*
X904792Y2139420D01*
G01X897042Y2146920D02*
X897292Y2146173D01*
X897917Y2145613D01*
X898667Y2145240D01*
X899667Y2144960D01*
X900792Y2144867D01*
X901917Y2144960D01*
X902917Y2145240D01*
X903667Y2145613D01*
X904292Y2146173D01*
X904542Y2146920D01*
X904292Y2147667D01*
X903667Y2148227D01*
X902917Y2148600D01*
X901917Y2148880D01*
X900792Y2148973D01*
X899667Y2148880D01*
X898667Y2148600D01*
X897917Y2148227D01*
X897292Y2147667D01*
X897042Y2146920D01*
G01X898292Y2152647D02*
X897542Y2153207D01*
X897167Y2153860D01*
X897042Y2154607D01*
X897292Y2155540D01*
X897917Y2156193D01*
X898667Y2156380D01*
X899417Y2156287D01*
X900042Y2155913D01*
X901292Y2154047D01*
X902167Y2153207D01*
X903417Y2152647D01*
X904542Y2152460D01*
Y2156380D01*
G01Y2159493D02*
X897042D01*
X903292Y2161920D01*
X897042Y2164347D01*
X904542D01*
G01Y2166993D02*
X897042D01*
X903292Y2169420D01*
X897042Y2171847D01*
X904542D01*
G01Y2182647D02*
X897042D01*
Y2186193D01*
G01X900667Y2184887D02*
Y2182647D01*
G01X897042Y2190800D02*
Y2193040D01*
G01Y2191920D02*
X904542D01*
G01Y2190800D02*
Y2193040D01*
G01Y2197273D02*
X897042D01*
X904542Y2201567D01*
X897042D01*
G01Y2205800D02*
Y2208040D01*
G01Y2206920D02*
X904542D01*
G01Y2205800D02*
Y2208040D01*
G01X903542Y2212460D02*
X904167Y2213207D01*
X904542Y2214047D01*
Y2214793D01*
X904167Y2215540D01*
X903542Y2216100D01*
X902667Y2216380D01*
X901792Y2216193D01*
X901042Y2215727D01*
X900542Y2214887D01*
X900292Y2213767D01*
X899792Y2213113D01*
X898917Y2212833D01*
X898042Y2213020D01*
X897417Y2213487D01*
X897042Y2214140D01*
Y2214793D01*
X897292Y2215447D01*
X897917Y2216007D01*
G01X904542Y2219960D02*
X897042D01*
G01Y2223880D02*
X904542D01*
G01X900792D02*
Y2219960D01*
G01X904542Y2231287D02*
Y2227553D01*
X897042D01*
Y2231287D01*
G01X900667Y2229793D02*
Y2227553D01*
G01X904542Y2234867D02*
X897042D01*
Y2236733D01*
X897417Y2237480D01*
X897917Y2238040D01*
X898667Y2238507D01*
X899542Y2238880D01*
X900792Y2238973D01*
X902042Y2238880D01*
X902917Y2238507D01*
X903667Y2238040D01*
X904167Y2237480D01*
X904542Y2236733D01*
Y2234867D01*
G01Y2250053D02*
X897042D01*
Y2252293D01*
X897417Y2253040D01*
X898292Y2253600D01*
X899292Y2253787D01*
X900292Y2253600D01*
X901042Y2253133D01*
X901417Y2252293D01*
Y2250053D01*
G01X897042Y2259420D02*
X904542D01*
G01X897042Y2257273D02*
Y2261567D01*
G01X904542Y2264960D02*
X897042D01*
G01Y2268880D02*
X904542D01*
G01X900792D02*
Y2264960D01*
G01X897042Y2280800D02*
Y2283040D01*
G01Y2281920D02*
X904542D01*
G01Y2280800D02*
Y2283040D01*
G01X903542Y2287460D02*
X904167Y2288207D01*
X904542Y2289047D01*
Y2289793D01*
X904167Y2290540D01*
X903542Y2291100D01*
X902667Y2291380D01*
X901792Y2291193D01*
X901042Y2290727D01*
X900542Y2289887D01*
X900292Y2288767D01*
X899792Y2288113D01*
X898917Y2287833D01*
X898042Y2288020D01*
X897417Y2288487D01*
X897042Y2289140D01*
Y2289793D01*
X897292Y2290447D01*
X897917Y2291007D01*
G01X904542Y2304420D02*
X897042D01*
X898542Y2303300D01*
G01X904542D02*
Y2305540D01*
G01X904792Y2311920D02*
X904667Y2311733D01*
X904417D01*
X904292Y2311920D01*
X904417Y2312107D01*
X904667D01*
X904792Y2311920D01*
G01X904542Y2319420D02*
X897042D01*
X898542Y2318300D01*
G01X904542D02*
Y2320540D01*
G01X903417Y2324867D02*
X904042Y2325427D01*
X904417Y2326080D01*
X904542Y2326920D01*
X904292Y2327760D01*
X903792Y2328413D01*
X902917Y2328880D01*
X901917Y2328973D01*
X900917Y2328787D01*
X900292Y2328320D01*
X899792Y2327667D01*
X899667Y2327013D01*
X899792Y2326360D01*
X900292Y2325520D01*
X897042Y2325800D01*
Y2328320D01*
G01X902042Y2333393D02*
Y2335633D01*
G01X900417Y2334420D02*
X903667D01*
G01X904792Y2340240D02*
X897042Y2343600D01*
G01X902042Y2348207D02*
Y2350633D01*
G01X897042Y2356920D02*
X897292Y2356173D01*
X897917Y2355613D01*
X898667Y2355240D01*
X899667Y2354960D01*
X900792Y2354867D01*
X901917Y2354960D01*
X902917Y2355240D01*
X903667Y2355613D01*
X904292Y2356173D01*
X904542Y2356920D01*
X904292Y2357667D01*
X903667Y2358227D01*
X902917Y2358600D01*
X901917Y2358880D01*
X900792Y2358973D01*
X899667Y2358880D01*
X898667Y2358600D01*
X897917Y2358227D01*
X897292Y2357667D01*
X897042Y2356920D01*
G01X904792Y2364420D02*
X904667Y2364233D01*
X904417D01*
X904292Y2364420D01*
X904417Y2364607D01*
X904667D01*
X904792Y2364420D01*
G01X897042Y2371920D02*
X897292Y2371173D01*
X897917Y2370613D01*
X898667Y2370240D01*
X899667Y2369960D01*
X900792Y2369867D01*
X901917Y2369960D01*
X902917Y2370240D01*
X903667Y2370613D01*
X904292Y2371173D01*
X904542Y2371920D01*
X904292Y2372667D01*
X903667Y2373227D01*
X902917Y2373600D01*
X901917Y2373880D01*
X900792Y2373973D01*
X899667Y2373880D01*
X898667Y2373600D01*
X897917Y2373227D01*
X897292Y2372667D01*
X897042Y2371920D01*
G01X898292Y2377647D02*
X897542Y2378207D01*
X897167Y2378860D01*
X897042Y2379607D01*
X897292Y2380540D01*
X897917Y2381193D01*
X898667Y2381380D01*
X899417Y2381287D01*
X900042Y2380913D01*
X901292Y2379047D01*
X902167Y2378207D01*
X903417Y2377647D01*
X904542Y2377460D01*
Y2381380D01*
G01X903417Y2384867D02*
X904042Y2385427D01*
X904417Y2386080D01*
X904542Y2386920D01*
X904292Y2387760D01*
X903792Y2388413D01*
X902917Y2388880D01*
X901917Y2388973D01*
X900917Y2388787D01*
X900292Y2388320D01*
X899792Y2387667D01*
X899667Y2387013D01*
X899792Y2386360D01*
X900292Y2385520D01*
X897042Y2385800D01*
Y2388320D01*
G01X904542Y2391993D02*
X897042D01*
X903292Y2394420D01*
X897042Y2396847D01*
X904542D01*
G01Y2399493D02*
X897042D01*
X903292Y2401920D01*
X897042Y2404347D01*
X904542D01*
G01X936485Y-395095D02*
X937526Y-394010D01*
X937943Y-392770D01*
X937526Y-391530D01*
X936277Y-390445D01*
X934401Y-389670D01*
X932526Y-389360D01*
X930235D01*
X928360Y-389670D01*
X926693Y-390445D01*
X925860Y-391375D01*
X925443Y-392460D01*
X925860Y-393700D01*
X926693Y-394630D01*
X927943Y-395250D01*
X929610Y-395560D01*
X931068Y-395250D01*
X932526Y-394475D01*
X933360Y-393545D01*
X933568Y-392460D01*
X933152Y-391220D01*
X932110Y-390290D01*
X930235Y-389360D01*
G01X935443Y-383470D02*
X936902Y-382540D01*
X937735Y-381300D01*
X937943Y-379905D01*
X937735Y-378665D01*
X936693Y-377425D01*
X935443Y-376650D01*
X934193Y-376495D01*
X932735Y-376805D01*
X931693Y-377890D01*
X931276Y-378975D01*
Y-380370D01*
G01Y-378975D02*
X930651Y-378045D01*
X929610Y-377270D01*
X928360Y-376960D01*
X927110Y-377270D01*
X926068Y-378045D01*
X925443Y-379440D01*
X925651Y-380835D01*
X926485Y-382230D01*
G01X937943Y-367660D02*
X925443D01*
X927943Y-369520D01*
G01X937943D02*
Y-365800D01*
G01X932735Y-358205D02*
X931276Y-357120D01*
X930443Y-356190D01*
X930026Y-354950D01*
X930443Y-353865D01*
X931276Y-353090D01*
X932526Y-352470D01*
X933985Y-352315D01*
X935235Y-352470D01*
X936485Y-353090D01*
X937526Y-354020D01*
X937943Y-355105D01*
X937526Y-356345D01*
X936277Y-357430D01*
X934401Y-358050D01*
X932318Y-358205D01*
X929610Y-357895D01*
X928151Y-357430D01*
X926693Y-356655D01*
X925651Y-355570D01*
X925443Y-354485D01*
X925860Y-353400D01*
X926901Y-352625D01*
G01X938360Y-342860D02*
X938151Y-343170D01*
X937735D01*
X937526Y-342860D01*
X937735Y-342550D01*
X938151D01*
X938360Y-342860D01*
G01X936485Y-333095D02*
X937526Y-332010D01*
X937943Y-330770D01*
X937526Y-329530D01*
X936277Y-328445D01*
X934401Y-327670D01*
X932526Y-327360D01*
X930235D01*
X928360Y-327670D01*
X926693Y-328445D01*
X925860Y-329375D01*
X925443Y-330460D01*
X925860Y-331700D01*
X926693Y-332630D01*
X927943Y-333250D01*
X929610Y-333560D01*
X931068Y-333250D01*
X932526Y-332475D01*
X933360Y-331545D01*
X933568Y-330460D01*
X933152Y-329220D01*
X932110Y-328290D01*
X930235Y-327360D01*
G01X935443Y-321470D02*
X936902Y-320540D01*
X937735Y-319300D01*
X937943Y-317905D01*
X937735Y-316665D01*
X936693Y-315425D01*
X935443Y-314650D01*
X934193Y-314495D01*
X932735Y-314805D01*
X931693Y-315890D01*
X931276Y-316975D01*
Y-318370D01*
G01Y-316975D02*
X930651Y-316045D01*
X929610Y-315270D01*
X928360Y-314960D01*
X927110Y-315270D01*
X926068Y-316045D01*
X925443Y-317440D01*
X925651Y-318835D01*
X926485Y-320230D01*
G01X927526Y-286405D02*
X926277Y-285475D01*
X925651Y-284390D01*
X925443Y-283150D01*
X925860Y-281600D01*
X926901Y-280515D01*
X928151Y-280205D01*
X929402Y-280360D01*
X930443Y-280980D01*
X932526Y-284080D01*
X933985Y-285475D01*
X936068Y-286405D01*
X937943Y-286715D01*
Y-280205D01*
G01X935443Y-274470D02*
X936902Y-273540D01*
X937735Y-272300D01*
X937943Y-270905D01*
X937735Y-269665D01*
X936693Y-268425D01*
X935443Y-267650D01*
X934193Y-267495D01*
X932735Y-267805D01*
X931693Y-268890D01*
X931276Y-269975D01*
Y-271370D01*
G01Y-269975D02*
X930651Y-269045D01*
X929610Y-268270D01*
X928360Y-267960D01*
X927110Y-268270D01*
X926068Y-269045D01*
X925443Y-270440D01*
X925651Y-271835D01*
X926485Y-273230D01*
G01X932735Y-261605D02*
X931276Y-260520D01*
X930443Y-259590D01*
X930026Y-258350D01*
X930443Y-257265D01*
X931276Y-256490D01*
X932526Y-255870D01*
X933985Y-255715D01*
X935235Y-255870D01*
X936485Y-256490D01*
X937526Y-257420D01*
X937943Y-258505D01*
X937526Y-259745D01*
X936277Y-260830D01*
X934401Y-261450D01*
X932318Y-261605D01*
X929610Y-261295D01*
X928151Y-260830D01*
X926693Y-260055D01*
X925651Y-258970D01*
X925443Y-257885D01*
X925860Y-256800D01*
X926901Y-256025D01*
G01X938360Y-246260D02*
X938151Y-246570D01*
X937735D01*
X937526Y-246260D01*
X937735Y-245950D01*
X938151D01*
X938360Y-246260D01*
G01X932735Y-236805D02*
X931276Y-235720D01*
X930443Y-234790D01*
X930026Y-233550D01*
X930443Y-232465D01*
X931276Y-231690D01*
X932526Y-231070D01*
X933985Y-230915D01*
X935235Y-231070D01*
X936485Y-231690D01*
X937526Y-232620D01*
X937943Y-233705D01*
X937526Y-234945D01*
X936277Y-236030D01*
X934401Y-236650D01*
X932318Y-236805D01*
X929610Y-236495D01*
X928151Y-236030D01*
X926693Y-235255D01*
X925651Y-234170D01*
X925443Y-233085D01*
X925860Y-232000D01*
X926901Y-231225D01*
G01X936068Y-224870D02*
X937110Y-223940D01*
X937735Y-222855D01*
X937943Y-221460D01*
X937526Y-220065D01*
X936693Y-218980D01*
X935235Y-218205D01*
X933568Y-218050D01*
X931901Y-218360D01*
X930860Y-219135D01*
X930026Y-220220D01*
X929818Y-221305D01*
X930026Y-222390D01*
X930860Y-223785D01*
X925443Y-223320D01*
Y-219135D01*
G01X957137Y292104D02*
Y284604D01*
X952843Y292104D01*
Y284604D01*
G01X949357Y292104D02*
Y284604D01*
X947117D01*
X946370Y284979D01*
X945810Y285854D01*
X945623Y286854D01*
X945810Y287854D01*
X946277Y288604D01*
X947117Y288979D01*
X949357D01*
G01X939990Y284604D02*
Y292104D01*
G01X942137Y284604D02*
X937843D01*
G01X934450Y292104D02*
Y284604D01*
G01X930530D02*
Y292104D01*
G01Y288354D02*
X934450D01*
G01X962192Y-395095D02*
X963233Y-394010D01*
X963650Y-392770D01*
X963233Y-391530D01*
X961984Y-390445D01*
X960108Y-389670D01*
X958233Y-389360D01*
X955942D01*
X954067Y-389670D01*
X952400Y-390445D01*
X951567Y-391375D01*
X951150Y-392460D01*
X951567Y-393700D01*
X952400Y-394630D01*
X953650Y-395250D01*
X955317Y-395560D01*
X956775Y-395250D01*
X958233Y-394475D01*
X959067Y-393545D01*
X959275Y-392460D01*
X958859Y-391220D01*
X957817Y-390290D01*
X955942Y-389360D01*
G01X963650Y-378200D02*
X951150D01*
X960108Y-383935D01*
Y-376185D01*
G01X963650Y-365800D02*
X951150D01*
X960108Y-371535D01*
Y-363785D01*
G01X958442Y-358205D02*
X956983Y-357120D01*
X956150Y-356190D01*
X955733Y-354950D01*
X956150Y-353865D01*
X956983Y-353090D01*
X958233Y-352470D01*
X959692Y-352315D01*
X960942Y-352470D01*
X962192Y-353090D01*
X963233Y-354020D01*
X963650Y-355105D01*
X963233Y-356345D01*
X961984Y-357430D01*
X960108Y-358050D01*
X958025Y-358205D01*
X955317Y-357895D01*
X953858Y-357430D01*
X952400Y-356655D01*
X951358Y-355570D01*
X951150Y-354485D01*
X951567Y-353400D01*
X952608Y-352625D01*
G01X964067Y-342860D02*
X963858Y-343170D01*
X963442D01*
X963233Y-342860D01*
X963442Y-342550D01*
X963858D01*
X964067Y-342860D01*
G01X963650Y-330460D02*
X963442Y-329375D01*
X962817Y-328135D01*
X961775Y-327360D01*
X960317Y-327050D01*
X958859Y-327360D01*
X957608Y-328290D01*
X956983Y-329685D01*
Y-331235D01*
X956567Y-332165D01*
X955525Y-332940D01*
X954067Y-333250D01*
X952608Y-332785D01*
X951567Y-331700D01*
X951150Y-330460D01*
X951567Y-329220D01*
X952608Y-328135D01*
X954067Y-327670D01*
X955525Y-327980D01*
X956567Y-328755D01*
X956983Y-329685D01*
Y-331235D01*
X957608Y-332630D01*
X958859Y-333560D01*
X960317Y-333870D01*
X961775Y-333560D01*
X962817Y-332785D01*
X963442Y-331545D01*
X963650Y-330460D01*
G01X961775Y-321470D02*
X962817Y-320540D01*
X963442Y-319455D01*
X963650Y-318060D01*
X963233Y-316665D01*
X962400Y-315580D01*
X960942Y-314805D01*
X959275Y-314650D01*
X957608Y-314960D01*
X956567Y-315735D01*
X955733Y-316820D01*
X955525Y-317905D01*
X955733Y-318990D01*
X956567Y-320385D01*
X951150Y-319920D01*
Y-315735D01*
G01X953233Y-286405D02*
X951984Y-285475D01*
X951358Y-284390D01*
X951150Y-283150D01*
X951567Y-281600D01*
X952608Y-280515D01*
X953858Y-280205D01*
X955109Y-280360D01*
X956150Y-280980D01*
X958233Y-284080D01*
X959692Y-285475D01*
X961775Y-286405D01*
X963650Y-286715D01*
Y-280205D01*
G01X961150Y-274470D02*
X962609Y-273540D01*
X963442Y-272300D01*
X963650Y-270905D01*
X963442Y-269665D01*
X962400Y-268425D01*
X961150Y-267650D01*
X959900Y-267495D01*
X958442Y-267805D01*
X957400Y-268890D01*
X956983Y-269975D01*
Y-271370D01*
G01Y-269975D02*
X956358Y-269045D01*
X955317Y-268270D01*
X954067Y-267960D01*
X952817Y-268270D01*
X951775Y-269045D01*
X951150Y-270440D01*
X951358Y-271835D01*
X952192Y-273230D01*
G01X962192Y-261295D02*
X963233Y-260210D01*
X963650Y-258970D01*
X963233Y-257730D01*
X961984Y-256645D01*
X960108Y-255870D01*
X958233Y-255560D01*
X955942D01*
X954067Y-255870D01*
X952400Y-256645D01*
X951567Y-257575D01*
X951150Y-258660D01*
X951567Y-259900D01*
X952400Y-260830D01*
X953650Y-261450D01*
X955317Y-261760D01*
X956775Y-261450D01*
X958233Y-260675D01*
X959067Y-259745D01*
X959275Y-258660D01*
X958859Y-257420D01*
X957817Y-256490D01*
X955942Y-255560D01*
G01X964067Y-246260D02*
X963858Y-246570D01*
X963442D01*
X963233Y-246260D01*
X963442Y-245950D01*
X963858D01*
X964067Y-246260D01*
G01X962192Y-236495D02*
X963233Y-235410D01*
X963650Y-234170D01*
X963233Y-232930D01*
X961984Y-231845D01*
X960108Y-231070D01*
X958233Y-230760D01*
X955942D01*
X954067Y-231070D01*
X952400Y-231845D01*
X951567Y-232775D01*
X951150Y-233860D01*
X951567Y-235100D01*
X952400Y-236030D01*
X953650Y-236650D01*
X955317Y-236960D01*
X956775Y-236650D01*
X958233Y-235875D01*
X959067Y-234945D01*
X959275Y-233860D01*
X958859Y-232620D01*
X957817Y-231690D01*
X955942Y-230760D01*
G01X961775Y-224870D02*
X962817Y-223940D01*
X963442Y-222855D01*
X963650Y-221460D01*
X963233Y-220065D01*
X962400Y-218980D01*
X960942Y-218205D01*
X959275Y-218050D01*
X957608Y-218360D01*
X956567Y-219135D01*
X955733Y-220220D01*
X955525Y-221305D01*
X955733Y-222390D01*
X956567Y-223785D01*
X951150Y-223320D01*
Y-219135D01*
G01X1022490Y-406370D02*
X1009990D01*
X1012490Y-408230D01*
G01X1022490D02*
Y-404510D01*
G01X1009990Y-393970D02*
X1010407Y-395210D01*
X1011448Y-396140D01*
X1012698Y-396760D01*
X1014365Y-397225D01*
X1016240Y-397380D01*
X1018115Y-397225D01*
X1019782Y-396760D01*
X1021032Y-396140D01*
X1022073Y-395210D01*
X1022490Y-393970D01*
X1022073Y-392730D01*
X1021032Y-391800D01*
X1019782Y-391180D01*
X1018115Y-390715D01*
X1016240Y-390560D01*
X1014365Y-390715D01*
X1012698Y-391180D01*
X1011448Y-391800D01*
X1010407Y-392730D01*
X1009990Y-393970D01*
G01X1022490Y-381570D02*
X1009990D01*
X1012490Y-383430D01*
G01X1022490D02*
Y-379710D01*
G01X1017282Y-372115D02*
X1015823Y-371030D01*
X1014990Y-370100D01*
X1014573Y-368860D01*
X1014990Y-367775D01*
X1015823Y-367000D01*
X1017073Y-366380D01*
X1018532Y-366225D01*
X1019782Y-366380D01*
X1021032Y-367000D01*
X1022073Y-367930D01*
X1022490Y-369015D01*
X1022073Y-370255D01*
X1020824Y-371340D01*
X1018948Y-371960D01*
X1016865Y-372115D01*
X1014157Y-371805D01*
X1012698Y-371340D01*
X1011240Y-370565D01*
X1010198Y-369480D01*
X1009990Y-368395D01*
X1010407Y-367310D01*
X1011448Y-366535D01*
G01X1012073Y-359715D02*
X1010824Y-358785D01*
X1010198Y-357700D01*
X1009990Y-356460D01*
X1010407Y-354910D01*
X1011448Y-353825D01*
X1012698Y-353515D01*
X1013949Y-353670D01*
X1014990Y-354290D01*
X1017073Y-357390D01*
X1018532Y-358785D01*
X1020615Y-359715D01*
X1022490Y-360025D01*
Y-353515D01*
G01X1022907Y-344370D02*
X1022698Y-344680D01*
X1022282D01*
X1022073Y-344370D01*
X1022282Y-344060D01*
X1022698D01*
X1022907Y-344370D01*
G01X1022490Y-330110D02*
X1009990D01*
X1018948Y-335845D01*
Y-328095D01*
G01X1009990Y-319570D02*
X1010407Y-320810D01*
X1011448Y-321740D01*
X1012698Y-322360D01*
X1014365Y-322825D01*
X1016240Y-322980D01*
X1018115Y-322825D01*
X1019782Y-322360D01*
X1021032Y-321740D01*
X1022073Y-320810D01*
X1022490Y-319570D01*
X1022073Y-318330D01*
X1021032Y-317400D01*
X1019782Y-316780D01*
X1018115Y-316315D01*
X1016240Y-316160D01*
X1014365Y-316315D01*
X1012698Y-316780D01*
X1011448Y-317400D01*
X1010407Y-318330D01*
X1009990Y-319570D01*
G01X1012073Y-287915D02*
X1010824Y-286985D01*
X1010198Y-285900D01*
X1009990Y-284660D01*
X1010407Y-283110D01*
X1011448Y-282025D01*
X1012698Y-281715D01*
X1013949Y-281870D01*
X1014990Y-282490D01*
X1017073Y-285590D01*
X1018532Y-286985D01*
X1020615Y-287915D01*
X1022490Y-288225D01*
Y-281715D01*
G01X1020615Y-275980D02*
X1021657Y-275050D01*
X1022282Y-273965D01*
X1022490Y-272570D01*
X1022073Y-271175D01*
X1021240Y-270090D01*
X1019782Y-269315D01*
X1018115Y-269160D01*
X1016448Y-269470D01*
X1015407Y-270245D01*
X1014573Y-271330D01*
X1014365Y-272415D01*
X1014573Y-273500D01*
X1015407Y-274895D01*
X1009990Y-274430D01*
Y-270245D01*
G01X1022490Y-260170D02*
X1022282Y-259085D01*
X1021657Y-257845D01*
X1020615Y-257070D01*
X1019157Y-256760D01*
X1017699Y-257070D01*
X1016448Y-258000D01*
X1015823Y-259395D01*
Y-260945D01*
X1015407Y-261875D01*
X1014365Y-262650D01*
X1012907Y-262960D01*
X1011448Y-262495D01*
X1010407Y-261410D01*
X1009990Y-260170D01*
X1010407Y-258930D01*
X1011448Y-257845D01*
X1012907Y-257380D01*
X1014365Y-257690D01*
X1015407Y-258465D01*
X1015823Y-259395D01*
Y-260945D01*
X1016448Y-262340D01*
X1017699Y-263270D01*
X1019157Y-263580D01*
X1020615Y-263270D01*
X1021657Y-262495D01*
X1022282Y-261255D01*
X1022490Y-260170D01*
G01X1022907Y-247770D02*
X1022698Y-248080D01*
X1022282D01*
X1022073Y-247770D01*
X1022282Y-247460D01*
X1022698D01*
X1022907Y-247770D01*
G01X1022490Y-235370D02*
X1009990D01*
X1012490Y-237230D01*
G01X1022490D02*
Y-233510D01*
G01X1012073Y-225915D02*
X1010824Y-224985D01*
X1010198Y-223900D01*
X1009990Y-222660D01*
X1010407Y-221110D01*
X1011448Y-220025D01*
X1012698Y-219715D01*
X1013949Y-219870D01*
X1014990Y-220490D01*
X1017073Y-223590D01*
X1018532Y-224985D01*
X1020615Y-225915D01*
X1022490Y-226225D01*
Y-219715D01*
G01X1052116Y-407140D02*
X1039616D01*
X1042116Y-409000D01*
G01X1052116D02*
Y-405280D01*
G01X1039616Y-394740D02*
X1040033Y-395980D01*
X1041074Y-396910D01*
X1042324Y-397530D01*
X1043991Y-397995D01*
X1045866Y-398150D01*
X1047741Y-397995D01*
X1049408Y-397530D01*
X1050658Y-396910D01*
X1051699Y-395980D01*
X1052116Y-394740D01*
X1051699Y-393500D01*
X1050658Y-392570D01*
X1049408Y-391950D01*
X1047741Y-391485D01*
X1045866Y-391330D01*
X1043991Y-391485D01*
X1042324Y-391950D01*
X1041074Y-392570D01*
X1040033Y-393500D01*
X1039616Y-394740D01*
G01X1052116Y-380480D02*
X1039616D01*
X1048574Y-386215D01*
Y-378465D01*
G01X1050241Y-373350D02*
X1051283Y-372420D01*
X1051908Y-371335D01*
X1052116Y-369940D01*
X1051699Y-368545D01*
X1050866Y-367460D01*
X1049408Y-366685D01*
X1047741Y-366530D01*
X1046074Y-366840D01*
X1045033Y-367615D01*
X1044199Y-368700D01*
X1043991Y-369785D01*
X1044199Y-370870D01*
X1045033Y-372265D01*
X1039616Y-371800D01*
Y-367615D01*
G01X1052116Y-357540D02*
X1051908Y-356455D01*
X1051283Y-355215D01*
X1050241Y-354440D01*
X1048783Y-354130D01*
X1047325Y-354440D01*
X1046074Y-355370D01*
X1045449Y-356765D01*
Y-358315D01*
X1045033Y-359245D01*
X1043991Y-360020D01*
X1042533Y-360330D01*
X1041074Y-359865D01*
X1040033Y-358780D01*
X1039616Y-357540D01*
X1040033Y-356300D01*
X1041074Y-355215D01*
X1042533Y-354750D01*
X1043991Y-355060D01*
X1045033Y-355835D01*
X1045449Y-356765D01*
Y-358315D01*
X1046074Y-359710D01*
X1047325Y-360640D01*
X1048783Y-360950D01*
X1050241Y-360640D01*
X1051283Y-359865D01*
X1051908Y-358625D01*
X1052116Y-357540D01*
G01X1052533Y-345140D02*
X1052324Y-345450D01*
X1051908D01*
X1051699Y-345140D01*
X1051908Y-344830D01*
X1052324D01*
X1052533Y-345140D01*
G01X1046908Y-335685D02*
X1045449Y-334600D01*
X1044616Y-333670D01*
X1044199Y-332430D01*
X1044616Y-331345D01*
X1045449Y-330570D01*
X1046699Y-329950D01*
X1048158Y-329795D01*
X1049408Y-329950D01*
X1050658Y-330570D01*
X1051699Y-331500D01*
X1052116Y-332585D01*
X1051699Y-333825D01*
X1050450Y-334910D01*
X1048574Y-335530D01*
X1046491Y-335685D01*
X1043783Y-335375D01*
X1042324Y-334910D01*
X1040866Y-334135D01*
X1039824Y-333050D01*
X1039616Y-331965D01*
X1040033Y-330880D01*
X1041074Y-330105D01*
G01X1046908Y-323285D02*
X1045449Y-322200D01*
X1044616Y-321270D01*
X1044199Y-320030D01*
X1044616Y-318945D01*
X1045449Y-318170D01*
X1046699Y-317550D01*
X1048158Y-317395D01*
X1049408Y-317550D01*
X1050658Y-318170D01*
X1051699Y-319100D01*
X1052116Y-320185D01*
X1051699Y-321425D01*
X1050450Y-322510D01*
X1048574Y-323130D01*
X1046491Y-323285D01*
X1043783Y-322975D01*
X1042324Y-322510D01*
X1040866Y-321735D01*
X1039824Y-320650D01*
X1039616Y-319565D01*
X1040033Y-318480D01*
X1041074Y-317705D01*
G01X1041699Y-288685D02*
X1040450Y-287755D01*
X1039824Y-286670D01*
X1039616Y-285430D01*
X1040033Y-283880D01*
X1041074Y-282795D01*
X1042324Y-282485D01*
X1043575Y-282640D01*
X1044616Y-283260D01*
X1046699Y-286360D01*
X1048158Y-287755D01*
X1050241Y-288685D01*
X1052116Y-288995D01*
Y-282485D01*
G01X1046908Y-276285D02*
X1045449Y-275200D01*
X1044616Y-274270D01*
X1044199Y-273030D01*
X1044616Y-271945D01*
X1045449Y-271170D01*
X1046699Y-270550D01*
X1048158Y-270395D01*
X1049408Y-270550D01*
X1050658Y-271170D01*
X1051699Y-272100D01*
X1052116Y-273185D01*
X1051699Y-274425D01*
X1050450Y-275510D01*
X1048574Y-276130D01*
X1046491Y-276285D01*
X1043783Y-275975D01*
X1042324Y-275510D01*
X1040866Y-274735D01*
X1039824Y-273650D01*
X1039616Y-272565D01*
X1040033Y-271480D01*
X1041074Y-270705D01*
G01X1050241Y-264350D02*
X1051283Y-263420D01*
X1051908Y-262335D01*
X1052116Y-260940D01*
X1051699Y-259545D01*
X1050866Y-258460D01*
X1049408Y-257685D01*
X1047741Y-257530D01*
X1046074Y-257840D01*
X1045033Y-258615D01*
X1044199Y-259700D01*
X1043991Y-260785D01*
X1044199Y-261870D01*
X1045033Y-263265D01*
X1039616Y-262800D01*
Y-258615D01*
G01X1052533Y-248540D02*
X1052324Y-248850D01*
X1051908D01*
X1051699Y-248540D01*
X1051908Y-248230D01*
X1052324D01*
X1052533Y-248540D01*
G01X1046908Y-239085D02*
X1045449Y-238000D01*
X1044616Y-237070D01*
X1044199Y-235830D01*
X1044616Y-234745D01*
X1045449Y-233970D01*
X1046699Y-233350D01*
X1048158Y-233195D01*
X1049408Y-233350D01*
X1050658Y-233970D01*
X1051699Y-234900D01*
X1052116Y-235985D01*
X1051699Y-237225D01*
X1050450Y-238310D01*
X1048574Y-238930D01*
X1046491Y-239085D01*
X1043783Y-238775D01*
X1042324Y-238310D01*
X1040866Y-237535D01*
X1039824Y-236450D01*
X1039616Y-235365D01*
X1040033Y-234280D01*
X1041074Y-233505D01*
G01X1050241Y-227150D02*
X1051283Y-226220D01*
X1051908Y-225135D01*
X1052116Y-223740D01*
X1051699Y-222345D01*
X1050866Y-221260D01*
X1049408Y-220485D01*
X1047741Y-220330D01*
X1046074Y-220640D01*
X1045033Y-221415D01*
X1044199Y-222500D01*
X1043991Y-223585D01*
X1044199Y-224670D01*
X1045033Y-226065D01*
X1039616Y-225600D01*
Y-221415D01*
G01X1108550Y-408680D02*
X1096050D01*
X1098550Y-410540D01*
G01X1108550D02*
Y-406820D01*
G01X1096050Y-396280D02*
X1096467Y-397520D01*
X1097508Y-398450D01*
X1098758Y-399070D01*
X1100425Y-399535D01*
X1102300Y-399690D01*
X1104175Y-399535D01*
X1105842Y-399070D01*
X1107092Y-398450D01*
X1108133Y-397520D01*
X1108550Y-396280D01*
X1108133Y-395040D01*
X1107092Y-394110D01*
X1105842Y-393490D01*
X1104175Y-393025D01*
X1102300Y-392870D01*
X1100425Y-393025D01*
X1098758Y-393490D01*
X1097508Y-394110D01*
X1096467Y-395040D01*
X1096050Y-396280D01*
G01X1106675Y-387290D02*
X1107717Y-386360D01*
X1108342Y-385275D01*
X1108550Y-383880D01*
X1108133Y-382485D01*
X1107300Y-381400D01*
X1105842Y-380625D01*
X1104175Y-380470D01*
X1102508Y-380780D01*
X1101467Y-381555D01*
X1100633Y-382640D01*
X1100425Y-383725D01*
X1100633Y-384810D01*
X1101467Y-386205D01*
X1096050Y-385740D01*
Y-381555D01*
G01X1108550Y-371790D02*
X1105842Y-371480D01*
X1103550Y-371015D01*
X1101467Y-370395D01*
X1099175Y-369620D01*
X1096050Y-368380D01*
Y-374580D01*
G01X1103342Y-362025D02*
X1101883Y-360940D01*
X1101050Y-360010D01*
X1100633Y-358770D01*
X1101050Y-357685D01*
X1101883Y-356910D01*
X1103133Y-356290D01*
X1104592Y-356135D01*
X1105842Y-356290D01*
X1107092Y-356910D01*
X1108133Y-357840D01*
X1108550Y-358925D01*
X1108133Y-360165D01*
X1106884Y-361250D01*
X1105008Y-361870D01*
X1102925Y-362025D01*
X1100217Y-361715D01*
X1098758Y-361250D01*
X1097300Y-360475D01*
X1096258Y-359390D01*
X1096050Y-358305D01*
X1096467Y-357220D01*
X1097508Y-356445D01*
G01X1108967Y-346680D02*
X1108758Y-346990D01*
X1108342D01*
X1108133Y-346680D01*
X1108342Y-346370D01*
X1108758D01*
X1108967Y-346680D01*
G01X1106675Y-337690D02*
X1107717Y-336760D01*
X1108342Y-335675D01*
X1108550Y-334280D01*
X1108133Y-332885D01*
X1107300Y-331800D01*
X1105842Y-331025D01*
X1104175Y-330870D01*
X1102508Y-331180D01*
X1101467Y-331955D01*
X1100633Y-333040D01*
X1100425Y-334125D01*
X1100633Y-335210D01*
X1101467Y-336605D01*
X1096050Y-336140D01*
Y-331955D01*
G01X1107092Y-324515D02*
X1108133Y-323430D01*
X1108550Y-322190D01*
X1108133Y-320950D01*
X1106884Y-319865D01*
X1105008Y-319090D01*
X1103133Y-318780D01*
X1100842D01*
X1098967Y-319090D01*
X1097300Y-319865D01*
X1096467Y-320795D01*
X1096050Y-321880D01*
X1096467Y-323120D01*
X1097300Y-324050D01*
X1098550Y-324670D01*
X1100217Y-324980D01*
X1101675Y-324670D01*
X1103133Y-323895D01*
X1103967Y-322965D01*
X1104175Y-321880D01*
X1103759Y-320640D01*
X1102717Y-319710D01*
X1100842Y-318780D01*
G01X1098133Y-290225D02*
X1096884Y-289295D01*
X1096258Y-288210D01*
X1096050Y-286970D01*
X1096467Y-285420D01*
X1097508Y-284335D01*
X1098758Y-284025D01*
X1100009Y-284180D01*
X1101050Y-284800D01*
X1103133Y-287900D01*
X1104592Y-289295D01*
X1106675Y-290225D01*
X1108550Y-290535D01*
Y-284025D01*
G01X1103342Y-277825D02*
X1101883Y-276740D01*
X1101050Y-275810D01*
X1100633Y-274570D01*
X1101050Y-273485D01*
X1101883Y-272710D01*
X1103133Y-272090D01*
X1104592Y-271935D01*
X1105842Y-272090D01*
X1107092Y-272710D01*
X1108133Y-273640D01*
X1108550Y-274725D01*
X1108133Y-275965D01*
X1106884Y-277050D01*
X1105008Y-277670D01*
X1102925Y-277825D01*
X1100217Y-277515D01*
X1098758Y-277050D01*
X1097300Y-276275D01*
X1096258Y-275190D01*
X1096050Y-274105D01*
X1096467Y-273020D01*
X1097508Y-272245D01*
G01X1108550Y-262480D02*
X1108342Y-261395D01*
X1107717Y-260155D01*
X1106675Y-259380D01*
X1105217Y-259070D01*
X1103759Y-259380D01*
X1102508Y-260310D01*
X1101883Y-261705D01*
Y-263255D01*
X1101467Y-264185D01*
X1100425Y-264960D01*
X1098967Y-265270D01*
X1097508Y-264805D01*
X1096467Y-263720D01*
X1096050Y-262480D01*
X1096467Y-261240D01*
X1097508Y-260155D01*
X1098967Y-259690D01*
X1100425Y-260000D01*
X1101467Y-260775D01*
X1101883Y-261705D01*
Y-263255D01*
X1102508Y-264650D01*
X1103759Y-265580D01*
X1105217Y-265890D01*
X1106675Y-265580D01*
X1107717Y-264805D01*
X1108342Y-263565D01*
X1108550Y-262480D01*
G01X1108967Y-250080D02*
X1108758Y-250390D01*
X1108342D01*
X1108133Y-250080D01*
X1108342Y-249770D01*
X1108758D01*
X1108967Y-250080D01*
G01X1103342Y-240625D02*
X1101883Y-239540D01*
X1101050Y-238610D01*
X1100633Y-237370D01*
X1101050Y-236285D01*
X1101883Y-235510D01*
X1103133Y-234890D01*
X1104592Y-234735D01*
X1105842Y-234890D01*
X1107092Y-235510D01*
X1108133Y-236440D01*
X1108550Y-237525D01*
X1108133Y-238765D01*
X1106884Y-239850D01*
X1105008Y-240470D01*
X1102925Y-240625D01*
X1100217Y-240315D01*
X1098758Y-239850D01*
X1097300Y-239075D01*
X1096258Y-237990D01*
X1096050Y-236905D01*
X1096467Y-235820D01*
X1097508Y-235045D01*
G01X1106675Y-228690D02*
X1107717Y-227760D01*
X1108342Y-226675D01*
X1108550Y-225280D01*
X1108133Y-223885D01*
X1107300Y-222800D01*
X1105842Y-222025D01*
X1104175Y-221870D01*
X1102508Y-222180D01*
X1101467Y-222955D01*
X1100633Y-224040D01*
X1100425Y-225125D01*
X1100633Y-226210D01*
X1101467Y-227605D01*
X1096050Y-227140D01*
Y-222955D01*
G01X1144770Y-397090D02*
X1132270D01*
X1134770Y-398950D01*
G01X1144770D02*
Y-395230D01*
G01X1132270Y-384690D02*
X1132687Y-385930D01*
X1133728Y-386860D01*
X1134978Y-387480D01*
X1136645Y-387945D01*
X1138520Y-388100D01*
X1140395Y-387945D01*
X1142062Y-387480D01*
X1143312Y-386860D01*
X1144353Y-385930D01*
X1144770Y-384690D01*
X1144353Y-383450D01*
X1143312Y-382520D01*
X1142062Y-381900D01*
X1140395Y-381435D01*
X1138520Y-381280D01*
X1136645Y-381435D01*
X1134978Y-381900D01*
X1133728Y-382520D01*
X1132687Y-383450D01*
X1132270Y-384690D01*
G01X1143312Y-374925D02*
X1144353Y-373840D01*
X1144770Y-372600D01*
X1144353Y-371360D01*
X1143104Y-370275D01*
X1141228Y-369500D01*
X1139353Y-369190D01*
X1137062D01*
X1135187Y-369500D01*
X1133520Y-370275D01*
X1132687Y-371205D01*
X1132270Y-372290D01*
X1132687Y-373530D01*
X1133520Y-374460D01*
X1134770Y-375080D01*
X1136437Y-375390D01*
X1137895Y-375080D01*
X1139353Y-374305D01*
X1140187Y-373375D01*
X1140395Y-372290D01*
X1139979Y-371050D01*
X1138937Y-370120D01*
X1137062Y-369190D01*
G01X1144770Y-358030D02*
X1132270D01*
X1141228Y-363765D01*
Y-356015D01*
G01X1132270Y-347490D02*
X1132687Y-348730D01*
X1133728Y-349660D01*
X1134978Y-350280D01*
X1136645Y-350745D01*
X1138520Y-350900D01*
X1140395Y-350745D01*
X1142062Y-350280D01*
X1143312Y-349660D01*
X1144353Y-348730D01*
X1144770Y-347490D01*
X1144353Y-346250D01*
X1143312Y-345320D01*
X1142062Y-344700D01*
X1140395Y-344235D01*
X1138520Y-344080D01*
X1136645Y-344235D01*
X1134978Y-344700D01*
X1133728Y-345320D01*
X1132687Y-346250D01*
X1132270Y-347490D01*
G01X1145187Y-335090D02*
X1144978Y-335400D01*
X1144562D01*
X1144353Y-335090D01*
X1144562Y-334780D01*
X1144978D01*
X1145187Y-335090D01*
G01X1144770Y-323000D02*
X1142062Y-322690D01*
X1139770Y-322225D01*
X1137687Y-321605D01*
X1135395Y-320830D01*
X1132270Y-319590D01*
Y-325790D01*
G01X1139562Y-313235D02*
X1138103Y-312150D01*
X1137270Y-311220D01*
X1136853Y-309980D01*
X1137270Y-308895D01*
X1138103Y-308120D01*
X1139353Y-307500D01*
X1140812Y-307345D01*
X1142062Y-307500D01*
X1143312Y-308120D01*
X1144353Y-309050D01*
X1144770Y-310135D01*
X1144353Y-311375D01*
X1143104Y-312460D01*
X1141228Y-313080D01*
X1139145Y-313235D01*
X1136437Y-312925D01*
X1134978Y-312460D01*
X1133520Y-311685D01*
X1132478Y-310600D01*
X1132270Y-309515D01*
X1132687Y-308430D01*
X1133728Y-307655D01*
G01X1134353Y-278635D02*
X1133104Y-277705D01*
X1132478Y-276620D01*
X1132270Y-275380D01*
X1132687Y-273830D01*
X1133728Y-272745D01*
X1134978Y-272435D01*
X1136229Y-272590D01*
X1137270Y-273210D01*
X1139353Y-276310D01*
X1140812Y-277705D01*
X1142895Y-278635D01*
X1144770Y-278945D01*
Y-272435D01*
G01Y-263600D02*
X1142062Y-263290D01*
X1139770Y-262825D01*
X1137687Y-262205D01*
X1135395Y-261430D01*
X1132270Y-260190D01*
Y-266390D01*
G01X1144770Y-251200D02*
X1142062Y-250890D01*
X1139770Y-250425D01*
X1137687Y-249805D01*
X1135395Y-249030D01*
X1132270Y-247790D01*
Y-253990D01*
G01X1145187Y-238490D02*
X1144978Y-238800D01*
X1144562D01*
X1144353Y-238490D01*
X1144562Y-238180D01*
X1144978D01*
X1145187Y-238490D01*
G01X1143312Y-228725D02*
X1144353Y-227640D01*
X1144770Y-226400D01*
X1144353Y-225160D01*
X1143104Y-224075D01*
X1141228Y-223300D01*
X1139353Y-222990D01*
X1137062D01*
X1135187Y-223300D01*
X1133520Y-224075D01*
X1132687Y-225005D01*
X1132270Y-226090D01*
X1132687Y-227330D01*
X1133520Y-228260D01*
X1134770Y-228880D01*
X1136437Y-229190D01*
X1137895Y-228880D01*
X1139353Y-228105D01*
X1140187Y-227175D01*
X1140395Y-226090D01*
X1139979Y-224850D01*
X1138937Y-223920D01*
X1137062Y-222990D01*
G01X1184360Y227050D02*
Y235050D01*
X1188960Y227050D01*
Y235050D01*
G01X1192660Y227050D02*
Y235050D01*
X1195060D01*
X1195860Y234650D01*
X1196460Y233717D01*
X1196660Y232650D01*
X1196460Y231583D01*
X1195960Y230783D01*
X1195060Y230383D01*
X1192660D01*
G01X1202660Y235050D02*
Y227050D01*
G01X1200360Y235050D02*
X1204960D01*
G01X1208560Y227050D02*
Y235050D01*
G01X1212760D02*
Y227050D01*
G01Y231050D02*
X1208560D01*
G01X1204880Y-370810D02*
X1192380D01*
X1194880Y-372670D01*
G01X1204880D02*
Y-368950D01*
G01Y-358410D02*
X1192380D01*
X1194880Y-360270D01*
G01X1204880D02*
Y-356550D01*
G01X1203005Y-349420D02*
X1204047Y-348490D01*
X1204672Y-347405D01*
X1204880Y-346010D01*
X1204463Y-344615D01*
X1203630Y-343530D01*
X1202172Y-342755D01*
X1200505Y-342600D01*
X1198838Y-342910D01*
X1197797Y-343685D01*
X1196963Y-344770D01*
X1196755Y-345855D01*
X1196963Y-346940D01*
X1197797Y-348335D01*
X1192380Y-347870D01*
Y-343685D01*
G01X1202380Y-337020D02*
X1203839Y-336090D01*
X1204672Y-334850D01*
X1204880Y-333455D01*
X1204672Y-332215D01*
X1203630Y-330975D01*
X1202380Y-330200D01*
X1201130Y-330045D01*
X1199672Y-330355D01*
X1198630Y-331440D01*
X1198213Y-332525D01*
Y-333920D01*
G01Y-332525D02*
X1197588Y-331595D01*
X1196547Y-330820D01*
X1195297Y-330510D01*
X1194047Y-330820D01*
X1193005Y-331595D01*
X1192380Y-332990D01*
X1192588Y-334385D01*
X1193422Y-335780D01*
G01X1203005Y-324620D02*
X1204047Y-323690D01*
X1204672Y-322605D01*
X1204880Y-321210D01*
X1204463Y-319815D01*
X1203630Y-318730D01*
X1202172Y-317955D01*
X1200505Y-317800D01*
X1198838Y-318110D01*
X1197797Y-318885D01*
X1196963Y-319970D01*
X1196755Y-321055D01*
X1196963Y-322140D01*
X1197797Y-323535D01*
X1192380Y-323070D01*
Y-318885D01*
G01X1205297Y-308810D02*
X1205088Y-309120D01*
X1204672D01*
X1204463Y-308810D01*
X1204672Y-308500D01*
X1205088D01*
X1205297Y-308810D01*
G01X1203005Y-299820D02*
X1204047Y-298890D01*
X1204672Y-297805D01*
X1204880Y-296410D01*
X1204463Y-295015D01*
X1203630Y-293930D01*
X1202172Y-293155D01*
X1200505Y-293000D01*
X1198838Y-293310D01*
X1197797Y-294085D01*
X1196963Y-295170D01*
X1196755Y-296255D01*
X1196963Y-297340D01*
X1197797Y-298735D01*
X1192380Y-298270D01*
Y-294085D01*
G01X1203005Y-287420D02*
X1204047Y-286490D01*
X1204672Y-285405D01*
X1204880Y-284010D01*
X1204463Y-282615D01*
X1203630Y-281530D01*
X1202172Y-280755D01*
X1200505Y-280600D01*
X1198838Y-280910D01*
X1197797Y-281685D01*
X1196963Y-282770D01*
X1196755Y-283855D01*
X1196963Y-284940D01*
X1197797Y-286335D01*
X1192380Y-285870D01*
Y-281685D01*
G01X1194463Y-252355D02*
X1193214Y-251425D01*
X1192588Y-250340D01*
X1192380Y-249100D01*
X1192797Y-247550D01*
X1193838Y-246465D01*
X1195088Y-246155D01*
X1196339Y-246310D01*
X1197380Y-246930D01*
X1199463Y-250030D01*
X1200922Y-251425D01*
X1203005Y-252355D01*
X1204880Y-252665D01*
Y-246155D01*
G01X1203422Y-239645D02*
X1204463Y-238560D01*
X1204880Y-237320D01*
X1204463Y-236080D01*
X1203214Y-234995D01*
X1201338Y-234220D01*
X1199463Y-233910D01*
X1197172D01*
X1195297Y-234220D01*
X1193630Y-234995D01*
X1192797Y-235925D01*
X1192380Y-237010D01*
X1192797Y-238250D01*
X1193630Y-239180D01*
X1194880Y-239800D01*
X1196547Y-240110D01*
X1198005Y-239800D01*
X1199463Y-239025D01*
X1200297Y-238095D01*
X1200505Y-237010D01*
X1200089Y-235770D01*
X1199047Y-234840D01*
X1197172Y-233910D01*
G01X1202380Y-228020D02*
X1203839Y-227090D01*
X1204672Y-225850D01*
X1204880Y-224455D01*
X1204672Y-223215D01*
X1203630Y-221975D01*
X1202380Y-221200D01*
X1201130Y-221045D01*
X1199672Y-221355D01*
X1198630Y-222440D01*
X1198213Y-223525D01*
Y-224920D01*
G01Y-223525D02*
X1197588Y-222595D01*
X1196547Y-221820D01*
X1195297Y-221510D01*
X1194047Y-221820D01*
X1193005Y-222595D01*
X1192380Y-223990D01*
X1192588Y-225385D01*
X1193422Y-226780D01*
G01X1234170Y-409450D02*
X1221670D01*
X1224170Y-411310D01*
G01X1234170D02*
Y-407590D01*
G01Y-397050D02*
X1221670D01*
X1224170Y-398910D01*
G01X1234170D02*
Y-395190D01*
G01X1232295Y-388060D02*
X1233337Y-387130D01*
X1233962Y-386045D01*
X1234170Y-384650D01*
X1233753Y-383255D01*
X1232920Y-382170D01*
X1231462Y-381395D01*
X1229795Y-381240D01*
X1228128Y-381550D01*
X1227087Y-382325D01*
X1226253Y-383410D01*
X1226045Y-384495D01*
X1226253Y-385580D01*
X1227087Y-386975D01*
X1221670Y-386510D01*
Y-382325D01*
G01X1232295Y-375660D02*
X1233337Y-374730D01*
X1233962Y-373645D01*
X1234170Y-372250D01*
X1233753Y-370855D01*
X1232920Y-369770D01*
X1231462Y-368995D01*
X1229795Y-368840D01*
X1228128Y-369150D01*
X1227087Y-369925D01*
X1226253Y-371010D01*
X1226045Y-372095D01*
X1226253Y-373180D01*
X1227087Y-374575D01*
X1221670Y-374110D01*
Y-369925D01*
G01X1234170Y-360160D02*
X1231462Y-359850D01*
X1229170Y-359385D01*
X1227087Y-358765D01*
X1224795Y-357990D01*
X1221670Y-356750D01*
Y-362950D01*
G01X1234587Y-347450D02*
X1234378Y-347760D01*
X1233962D01*
X1233753Y-347450D01*
X1233962Y-347140D01*
X1234378D01*
X1234587Y-347450D01*
G01X1221670Y-335050D02*
X1222087Y-336290D01*
X1223128Y-337220D01*
X1224378Y-337840D01*
X1226045Y-338305D01*
X1227920Y-338460D01*
X1229795Y-338305D01*
X1231462Y-337840D01*
X1232712Y-337220D01*
X1233753Y-336290D01*
X1234170Y-335050D01*
X1233753Y-333810D01*
X1232712Y-332880D01*
X1231462Y-332260D01*
X1229795Y-331795D01*
X1227920Y-331640D01*
X1226045Y-331795D01*
X1224378Y-332260D01*
X1223128Y-332880D01*
X1222087Y-333810D01*
X1221670Y-335050D01*
G01X1232712Y-325285D02*
X1233753Y-324200D01*
X1234170Y-322960D01*
X1233753Y-321720D01*
X1232504Y-320635D01*
X1230628Y-319860D01*
X1228753Y-319550D01*
X1226462D01*
X1224587Y-319860D01*
X1222920Y-320635D01*
X1222087Y-321565D01*
X1221670Y-322650D01*
X1222087Y-323890D01*
X1222920Y-324820D01*
X1224170Y-325440D01*
X1225837Y-325750D01*
X1227295Y-325440D01*
X1228753Y-324665D01*
X1229587Y-323735D01*
X1229795Y-322650D01*
X1229379Y-321410D01*
X1228337Y-320480D01*
X1226462Y-319550D01*
G01X1223753Y-290995D02*
X1222504Y-290065D01*
X1221878Y-288980D01*
X1221670Y-287740D01*
X1222087Y-286190D01*
X1223128Y-285105D01*
X1224378Y-284795D01*
X1225629Y-284950D01*
X1226670Y-285570D01*
X1228753Y-288670D01*
X1230212Y-290065D01*
X1232295Y-290995D01*
X1234170Y-291305D01*
Y-284795D01*
G01X1232712Y-278285D02*
X1233753Y-277200D01*
X1234170Y-275960D01*
X1233753Y-274720D01*
X1232504Y-273635D01*
X1230628Y-272860D01*
X1228753Y-272550D01*
X1226462D01*
X1224587Y-272860D01*
X1222920Y-273635D01*
X1222087Y-274565D01*
X1221670Y-275650D01*
X1222087Y-276890D01*
X1222920Y-277820D01*
X1224170Y-278440D01*
X1225837Y-278750D01*
X1227295Y-278440D01*
X1228753Y-277665D01*
X1229587Y-276735D01*
X1229795Y-275650D01*
X1229379Y-274410D01*
X1228337Y-273480D01*
X1226462Y-272550D01*
G01X1231670Y-266660D02*
X1233129Y-265730D01*
X1233962Y-264490D01*
X1234170Y-263095D01*
X1233962Y-261855D01*
X1232920Y-260615D01*
X1231670Y-259840D01*
X1230420Y-259685D01*
X1228962Y-259995D01*
X1227920Y-261080D01*
X1227503Y-262165D01*
Y-263560D01*
G01Y-262165D02*
X1226878Y-261235D01*
X1225837Y-260460D01*
X1224587Y-260150D01*
X1223337Y-260460D01*
X1222295Y-261235D01*
X1221670Y-262630D01*
X1221878Y-264025D01*
X1222712Y-265420D01*
G01X1234587Y-250850D02*
X1234378Y-251160D01*
X1233962D01*
X1233753Y-250850D01*
X1233962Y-250540D01*
X1234378D01*
X1234587Y-250850D01*
G01X1232295Y-241860D02*
X1233337Y-240930D01*
X1233962Y-239845D01*
X1234170Y-238450D01*
X1233753Y-237055D01*
X1232920Y-235970D01*
X1231462Y-235195D01*
X1229795Y-235040D01*
X1228128Y-235350D01*
X1227087Y-236125D01*
X1226253Y-237210D01*
X1226045Y-238295D01*
X1226253Y-239380D01*
X1227087Y-240775D01*
X1221670Y-240310D01*
Y-236125D01*
G01X1232295Y-229460D02*
X1233337Y-228530D01*
X1233962Y-227445D01*
X1234170Y-226050D01*
X1233753Y-224655D01*
X1232920Y-223570D01*
X1231462Y-222795D01*
X1229795Y-222640D01*
X1228128Y-222950D01*
X1227087Y-223725D01*
X1226253Y-224810D01*
X1226045Y-225895D01*
X1226253Y-226980D01*
X1227087Y-228375D01*
X1221670Y-227910D01*
Y-223725D01*
G01X1241278Y1672795D02*
G03I-2500J0D01*
G01X1249152Y1676732D02*
G03I-2500J0D01*
G01X1241278Y1686968D02*
G03I-2500J0D01*
G01X1249152Y1690905D02*
G03I-2500J0D01*
G01X1241278Y1701141D02*
G03I-2500J0D01*
G01X1249152Y1705078D02*
G03I-2500J0D01*
G01X1241278Y1715314D02*
G03I-2500J0D01*
G01X1249152Y1719251D02*
G03I-2500J0D01*
G01X1241278Y1729488D02*
G03I-2500J0D01*
G01X1249152Y1733425D02*
G03I-2500J0D01*
G01X1257026Y1672795D02*
G03I-2500J0D01*
G01Y1686968D02*
G03I-2500J0D01*
G01Y1701141D02*
G03I-2500J0D01*
G01Y1715314D02*
G03I-2500J0D01*
G01Y1729488D02*
G03I-2500J0D01*
G01X1272774Y1672795D02*
G03I-2500J0D01*
G01X1264900Y1676732D02*
G03I-2500J0D01*
G01X1272774Y1686968D02*
G03I-2500J0D01*
G01X1264900Y1690905D02*
G03I-2500J0D01*
G01X1272774Y1701141D02*
G03I-2500J0D01*
G01X1264900Y1705078D02*
G03I-2500J0D01*
G01X1272774Y1715314D02*
G03I-2500J0D01*
G01X1264900Y1719251D02*
G03I-2500J0D01*
G01X1272774Y1729488D02*
G03I-2500J0D01*
G01X1264900Y1733425D02*
G03I-2500J0D01*
G01X1289660Y-411760D02*
X1277160D01*
X1279660Y-413620D01*
G01X1289660D02*
Y-409900D01*
G01X1279243Y-402305D02*
X1277994Y-401375D01*
X1277368Y-400290D01*
X1277160Y-399050D01*
X1277577Y-397500D01*
X1278618Y-396415D01*
X1279868Y-396105D01*
X1281119Y-396260D01*
X1282160Y-396880D01*
X1284243Y-399980D01*
X1285702Y-401375D01*
X1287785Y-402305D01*
X1289660Y-402615D01*
Y-396105D01*
G01X1287785Y-390370D02*
X1288827Y-389440D01*
X1289452Y-388355D01*
X1289660Y-386960D01*
X1289243Y-385565D01*
X1288410Y-384480D01*
X1286952Y-383705D01*
X1285285Y-383550D01*
X1283618Y-383860D01*
X1282577Y-384635D01*
X1281743Y-385720D01*
X1281535Y-386805D01*
X1281743Y-387890D01*
X1282577Y-389285D01*
X1277160Y-388820D01*
Y-384635D01*
G01X1289660Y-374560D02*
X1277160D01*
X1279660Y-376420D01*
G01X1289660D02*
Y-372700D01*
G01X1277160Y-362160D02*
X1277577Y-363400D01*
X1278618Y-364330D01*
X1279868Y-364950D01*
X1281535Y-365415D01*
X1283410Y-365570D01*
X1285285Y-365415D01*
X1286952Y-364950D01*
X1288202Y-364330D01*
X1289243Y-363400D01*
X1289660Y-362160D01*
X1289243Y-360920D01*
X1288202Y-359990D01*
X1286952Y-359370D01*
X1285285Y-358905D01*
X1283410Y-358750D01*
X1281535Y-358905D01*
X1279868Y-359370D01*
X1278618Y-359990D01*
X1277577Y-360920D01*
X1277160Y-362160D01*
G01X1290077Y-349760D02*
X1289868Y-350070D01*
X1289452D01*
X1289243Y-349760D01*
X1289452Y-349450D01*
X1289868D01*
X1290077Y-349760D01*
G01X1284452Y-340305D02*
X1282993Y-339220D01*
X1282160Y-338290D01*
X1281743Y-337050D01*
X1282160Y-335965D01*
X1282993Y-335190D01*
X1284243Y-334570D01*
X1285702Y-334415D01*
X1286952Y-334570D01*
X1288202Y-335190D01*
X1289243Y-336120D01*
X1289660Y-337205D01*
X1289243Y-338445D01*
X1287994Y-339530D01*
X1286118Y-340150D01*
X1284035Y-340305D01*
X1281327Y-339995D01*
X1279868Y-339530D01*
X1278410Y-338755D01*
X1277368Y-337670D01*
X1277160Y-336585D01*
X1277577Y-335500D01*
X1278618Y-334725D01*
G01X1287160Y-328370D02*
X1288619Y-327440D01*
X1289452Y-326200D01*
X1289660Y-324805D01*
X1289452Y-323565D01*
X1288410Y-322325D01*
X1287160Y-321550D01*
X1285910Y-321395D01*
X1284452Y-321705D01*
X1283410Y-322790D01*
X1282993Y-323875D01*
Y-325270D01*
G01Y-323875D02*
X1282368Y-322945D01*
X1281327Y-322170D01*
X1280077Y-321860D01*
X1278827Y-322170D01*
X1277785Y-322945D01*
X1277160Y-324340D01*
X1277368Y-325735D01*
X1278202Y-327130D01*
G01X1287160Y-293770D02*
X1288619Y-292840D01*
X1289452Y-291600D01*
X1289660Y-290205D01*
X1289452Y-288965D01*
X1288410Y-287725D01*
X1287160Y-286950D01*
X1285910Y-286795D01*
X1284452Y-287105D01*
X1283410Y-288190D01*
X1282993Y-289275D01*
Y-290670D01*
G01Y-289275D02*
X1282368Y-288345D01*
X1281327Y-287570D01*
X1280077Y-287260D01*
X1278827Y-287570D01*
X1277785Y-288345D01*
X1277160Y-289740D01*
X1277368Y-291135D01*
X1278202Y-292530D01*
G01X1289660Y-277960D02*
X1277160D01*
X1279660Y-279820D01*
G01X1289660D02*
Y-276100D01*
G01Y-265870D02*
X1286952Y-265560D01*
X1284660Y-265095D01*
X1282577Y-264475D01*
X1280285Y-263700D01*
X1277160Y-262460D01*
Y-268660D01*
G01X1290077Y-253160D02*
X1289868Y-253470D01*
X1289452D01*
X1289243Y-253160D01*
X1289452Y-252850D01*
X1289868D01*
X1290077Y-253160D01*
G01X1289660Y-241070D02*
X1286952Y-240760D01*
X1284660Y-240295D01*
X1282577Y-239675D01*
X1280285Y-238900D01*
X1277160Y-237660D01*
Y-243860D01*
G01X1289660Y-228670D02*
X1286952Y-228360D01*
X1284660Y-227895D01*
X1282577Y-227275D01*
X1280285Y-226500D01*
X1277160Y-225260D01*
Y-231460D01*
G01X1288522Y1672795D02*
G03I-2500J0D01*
G01X1280648Y1676732D02*
G03I-2500J0D01*
G01X1288522Y1686968D02*
G03I-2500J0D01*
G01X1280648Y1690905D02*
G03I-2500J0D01*
G01X1288522Y1701141D02*
G03I-2500J0D01*
G01X1280648Y1705078D02*
G03I-2500J0D01*
G01X1288522Y1715314D02*
G03I-2500J0D01*
G01X1280648Y1719251D02*
G03I-2500J0D01*
G01X1288522Y1729488D02*
G03I-2500J0D01*
G01X1280648Y1733425D02*
G03I-2500J0D01*
G01X1315090Y-398630D02*
X1302590D01*
X1305090Y-400490D01*
G01X1315090D02*
Y-396770D01*
G01X1304673Y-389175D02*
X1303424Y-388245D01*
X1302798Y-387160D01*
X1302590Y-385920D01*
X1303007Y-384370D01*
X1304048Y-383285D01*
X1305298Y-382975D01*
X1306549Y-383130D01*
X1307590Y-383750D01*
X1309673Y-386850D01*
X1311132Y-388245D01*
X1313215Y-389175D01*
X1315090Y-389485D01*
Y-382975D01*
G01Y-374140D02*
X1312382Y-373830D01*
X1310090Y-373365D01*
X1308007Y-372745D01*
X1305715Y-371970D01*
X1302590Y-370730D01*
Y-376930D01*
G01X1315090Y-361430D02*
X1302590D01*
X1305090Y-363290D01*
G01X1315090D02*
Y-359570D01*
G01X1304673Y-351975D02*
X1303424Y-351045D01*
X1302798Y-349960D01*
X1302590Y-348720D01*
X1303007Y-347170D01*
X1304048Y-346085D01*
X1305298Y-345775D01*
X1306549Y-345930D01*
X1307590Y-346550D01*
X1309673Y-349650D01*
X1311132Y-351045D01*
X1313215Y-351975D01*
X1315090Y-352285D01*
Y-345775D01*
G01X1315507Y-336630D02*
X1315298Y-336940D01*
X1314882D01*
X1314673Y-336630D01*
X1314882Y-336320D01*
X1315298D01*
X1315507Y-336630D01*
G01X1309882Y-327175D02*
X1308423Y-326090D01*
X1307590Y-325160D01*
X1307173Y-323920D01*
X1307590Y-322835D01*
X1308423Y-322060D01*
X1309673Y-321440D01*
X1311132Y-321285D01*
X1312382Y-321440D01*
X1313632Y-322060D01*
X1314673Y-322990D01*
X1315090Y-324075D01*
X1314673Y-325315D01*
X1313424Y-326400D01*
X1311548Y-327020D01*
X1309465Y-327175D01*
X1306757Y-326865D01*
X1305298Y-326400D01*
X1303840Y-325625D01*
X1302798Y-324540D01*
X1302590Y-323455D01*
X1303007Y-322370D01*
X1304048Y-321595D01*
G01X1302590Y-311830D02*
X1303007Y-313070D01*
X1304048Y-314000D01*
X1305298Y-314620D01*
X1306965Y-315085D01*
X1308840Y-315240D01*
X1310715Y-315085D01*
X1312382Y-314620D01*
X1313632Y-314000D01*
X1314673Y-313070D01*
X1315090Y-311830D01*
X1314673Y-310590D01*
X1313632Y-309660D01*
X1312382Y-309040D01*
X1310715Y-308575D01*
X1308840Y-308420D01*
X1306965Y-308575D01*
X1305298Y-309040D01*
X1304048Y-309660D01*
X1303007Y-310590D01*
X1302590Y-311830D01*
G01X1312590Y-280640D02*
X1314049Y-279710D01*
X1314882Y-278470D01*
X1315090Y-277075D01*
X1314882Y-275835D01*
X1313840Y-274595D01*
X1312590Y-273820D01*
X1311340Y-273665D01*
X1309882Y-273975D01*
X1308840Y-275060D01*
X1308423Y-276145D01*
Y-277540D01*
G01Y-276145D02*
X1307798Y-275215D01*
X1306757Y-274440D01*
X1305507Y-274130D01*
X1304257Y-274440D01*
X1303215Y-275215D01*
X1302590Y-276610D01*
X1302798Y-278005D01*
X1303632Y-279400D01*
G01X1304673Y-267775D02*
X1303424Y-266845D01*
X1302798Y-265760D01*
X1302590Y-264520D01*
X1303007Y-262970D01*
X1304048Y-261885D01*
X1305298Y-261575D01*
X1306549Y-261730D01*
X1307590Y-262350D01*
X1309673Y-265450D01*
X1311132Y-266845D01*
X1313215Y-267775D01*
X1315090Y-268085D01*
Y-261575D01*
G01X1304673Y-255375D02*
X1303424Y-254445D01*
X1302798Y-253360D01*
X1302590Y-252120D01*
X1303007Y-250570D01*
X1304048Y-249485D01*
X1305298Y-249175D01*
X1306549Y-249330D01*
X1307590Y-249950D01*
X1309673Y-253050D01*
X1311132Y-254445D01*
X1313215Y-255375D01*
X1315090Y-255685D01*
Y-249175D01*
G01X1315507Y-240030D02*
X1315298Y-240340D01*
X1314882D01*
X1314673Y-240030D01*
X1314882Y-239720D01*
X1315298D01*
X1315507Y-240030D01*
G01X1313632Y-230265D02*
X1314673Y-229180D01*
X1315090Y-227940D01*
X1314673Y-226700D01*
X1313424Y-225615D01*
X1311548Y-224840D01*
X1309673Y-224530D01*
X1307382D01*
X1305507Y-224840D01*
X1303840Y-225615D01*
X1303007Y-226545D01*
X1302590Y-227630D01*
X1303007Y-228870D01*
X1303840Y-229800D01*
X1305090Y-230420D01*
X1306757Y-230730D01*
X1308215Y-230420D01*
X1309673Y-229645D01*
X1310507Y-228715D01*
X1310715Y-227630D01*
X1310299Y-226390D01*
X1309257Y-225460D01*
X1307382Y-224530D01*
G01X1308208Y1672795D02*
G03I-2500J0D01*
G01Y1686968D02*
G03I-2500J0D01*
G01X1296396Y1676732D02*
G03I-2500J0D01*
G01X1308208Y1701141D02*
G03I-2500J0D01*
G01X1296396Y1690905D02*
G03I-2500J0D01*
G01X1308208Y1715314D02*
G03I-2500J0D01*
G01X1296396Y1705078D02*
G03I-2500J0D01*
G01X1308208Y1729488D02*
G03I-2500J0D01*
G01X1296396Y1719251D02*
G03I-2500J0D01*
G01Y1733425D02*
G03I-2500J0D01*
G01X1323956Y1672795D02*
G03I-2500J0D01*
G01X1316082Y1676732D02*
G03I-2500J0D01*
G01X1323956Y1701141D02*
G03I-2500J0D01*
G01Y1686968D02*
G03I-2500J0D01*
G01X1316082Y1690905D02*
G03I-2500J0D01*
G01X1323956Y1715314D02*
G03I-2500J0D01*
G01X1316082Y1705078D02*
G03I-2500J0D01*
G01X1323956Y1729488D02*
G03I-2500J0D01*
G01X1316082Y1719251D02*
G03I-2500J0D01*
G01Y1733425D02*
G03I-2500J0D01*
G01X1344380Y-411760D02*
X1331880D01*
X1334380Y-413620D01*
G01X1344380D02*
Y-409900D01*
G01X1333963Y-402305D02*
X1332714Y-401375D01*
X1332088Y-400290D01*
X1331880Y-399050D01*
X1332297Y-397500D01*
X1333338Y-396415D01*
X1334588Y-396105D01*
X1335839Y-396260D01*
X1336880Y-396880D01*
X1338963Y-399980D01*
X1340422Y-401375D01*
X1342505Y-402305D01*
X1344380Y-402615D01*
Y-396105D01*
G01X1342922Y-389595D02*
X1343963Y-388510D01*
X1344380Y-387270D01*
X1343963Y-386030D01*
X1342714Y-384945D01*
X1340838Y-384170D01*
X1338963Y-383860D01*
X1336672D01*
X1334797Y-384170D01*
X1333130Y-384945D01*
X1332297Y-385875D01*
X1331880Y-386960D01*
X1332297Y-388200D01*
X1333130Y-389130D01*
X1334380Y-389750D01*
X1336047Y-390060D01*
X1337505Y-389750D01*
X1338963Y-388975D01*
X1339797Y-388045D01*
X1340005Y-386960D01*
X1339589Y-385720D01*
X1338547Y-384790D01*
X1336672Y-383860D01*
G01X1339172Y-377505D02*
X1337713Y-376420D01*
X1336880Y-375490D01*
X1336463Y-374250D01*
X1336880Y-373165D01*
X1337713Y-372390D01*
X1338963Y-371770D01*
X1340422Y-371615D01*
X1341672Y-371770D01*
X1342922Y-372390D01*
X1343963Y-373320D01*
X1344380Y-374405D01*
X1343963Y-375645D01*
X1342714Y-376730D01*
X1340838Y-377350D01*
X1338755Y-377505D01*
X1336047Y-377195D01*
X1334588Y-376730D01*
X1333130Y-375955D01*
X1332088Y-374870D01*
X1331880Y-373785D01*
X1332297Y-372700D01*
X1333338Y-371925D01*
G01X1341880Y-365570D02*
X1343339Y-364640D01*
X1344172Y-363400D01*
X1344380Y-362005D01*
X1344172Y-360765D01*
X1343130Y-359525D01*
X1341880Y-358750D01*
X1340630Y-358595D01*
X1339172Y-358905D01*
X1338130Y-359990D01*
X1337713Y-361075D01*
Y-362470D01*
G01Y-361075D02*
X1337088Y-360145D01*
X1336047Y-359370D01*
X1334797Y-359060D01*
X1333547Y-359370D01*
X1332505Y-360145D01*
X1331880Y-361540D01*
X1332088Y-362935D01*
X1332922Y-364330D01*
G01X1344797Y-349760D02*
X1344588Y-350070D01*
X1344172D01*
X1343963Y-349760D01*
X1344172Y-349450D01*
X1344588D01*
X1344797Y-349760D01*
G01X1341880Y-340770D02*
X1343339Y-339840D01*
X1344172Y-338600D01*
X1344380Y-337205D01*
X1344172Y-335965D01*
X1343130Y-334725D01*
X1341880Y-333950D01*
X1340630Y-333795D01*
X1339172Y-334105D01*
X1338130Y-335190D01*
X1337713Y-336275D01*
Y-337670D01*
G01Y-336275D02*
X1337088Y-335345D01*
X1336047Y-334570D01*
X1334797Y-334260D01*
X1333547Y-334570D01*
X1332505Y-335345D01*
X1331880Y-336740D01*
X1332088Y-338135D01*
X1332922Y-339530D01*
G01X1342922Y-327595D02*
X1343963Y-326510D01*
X1344380Y-325270D01*
X1343963Y-324030D01*
X1342714Y-322945D01*
X1340838Y-322170D01*
X1338963Y-321860D01*
X1336672D01*
X1334797Y-322170D01*
X1333130Y-322945D01*
X1332297Y-323875D01*
X1331880Y-324960D01*
X1332297Y-326200D01*
X1333130Y-327130D01*
X1334380Y-327750D01*
X1336047Y-328060D01*
X1337505Y-327750D01*
X1338963Y-326975D01*
X1339797Y-326045D01*
X1340005Y-324960D01*
X1339589Y-323720D01*
X1338547Y-322790D01*
X1336672Y-321860D01*
G01X1341880Y-293770D02*
X1343339Y-292840D01*
X1344172Y-291600D01*
X1344380Y-290205D01*
X1344172Y-288965D01*
X1343130Y-287725D01*
X1341880Y-286950D01*
X1340630Y-286795D01*
X1339172Y-287105D01*
X1338130Y-288190D01*
X1337713Y-289275D01*
Y-290670D01*
G01Y-289275D02*
X1337088Y-288345D01*
X1336047Y-287570D01*
X1334797Y-287260D01*
X1333547Y-287570D01*
X1332505Y-288345D01*
X1331880Y-289740D01*
X1332088Y-291135D01*
X1332922Y-292530D01*
G01X1333963Y-280905D02*
X1332714Y-279975D01*
X1332088Y-278890D01*
X1331880Y-277650D01*
X1332297Y-276100D01*
X1333338Y-275015D01*
X1334588Y-274705D01*
X1335839Y-274860D01*
X1336880Y-275480D01*
X1338963Y-278580D01*
X1340422Y-279975D01*
X1342505Y-280905D01*
X1344380Y-281215D01*
Y-274705D01*
G01X1342922Y-268195D02*
X1343963Y-267110D01*
X1344380Y-265870D01*
X1343963Y-264630D01*
X1342714Y-263545D01*
X1340838Y-262770D01*
X1338963Y-262460D01*
X1336672D01*
X1334797Y-262770D01*
X1333130Y-263545D01*
X1332297Y-264475D01*
X1331880Y-265560D01*
X1332297Y-266800D01*
X1333130Y-267730D01*
X1334380Y-268350D01*
X1336047Y-268660D01*
X1337505Y-268350D01*
X1338963Y-267575D01*
X1339797Y-266645D01*
X1340005Y-265560D01*
X1339589Y-264320D01*
X1338547Y-263390D01*
X1336672Y-262460D01*
G01X1344797Y-253160D02*
X1344588Y-253470D01*
X1344172D01*
X1343963Y-253160D01*
X1344172Y-252850D01*
X1344588D01*
X1344797Y-253160D01*
G01X1333963Y-243705D02*
X1332714Y-242775D01*
X1332088Y-241690D01*
X1331880Y-240450D01*
X1332297Y-238900D01*
X1333338Y-237815D01*
X1334588Y-237505D01*
X1335839Y-237660D01*
X1336880Y-238280D01*
X1338963Y-241380D01*
X1340422Y-242775D01*
X1342505Y-243705D01*
X1344380Y-244015D01*
Y-237505D01*
G01Y-228670D02*
X1341672Y-228360D01*
X1339380Y-227895D01*
X1337297Y-227275D01*
X1335005Y-226500D01*
X1331880Y-225260D01*
Y-231460D01*
G01X1331830Y1676732D02*
G03I-2500J0D01*
G01Y1690905D02*
G03I-2500J0D01*
G01Y1705078D02*
G03I-2500J0D01*
G01Y1719251D02*
G03I-2500J0D01*
G01Y1733425D02*
G03I-2500J0D01*
G01X1339704Y1672795D02*
G03I-2500J0D01*
G01X1347578Y1676732D02*
G03I-2500J0D01*
G01X1339704Y1686968D02*
G03I-2500J0D01*
G01X1347578Y1690905D02*
G03I-2500J0D01*
G01X1339704Y1701141D02*
G03I-2500J0D01*
G01X1347578Y1705078D02*
G03I-2500J0D01*
G01X1339704Y1715314D02*
G03I-2500J0D01*
G01X1347578Y1719251D02*
G03I-2500J0D01*
G01X1339704Y1729488D02*
G03I-2500J0D01*
G01X1347578Y1733425D02*
G03I-2500J0D01*
G01X1355452Y1672795D02*
G03I-2500J0D01*
G01X1363326Y1676732D02*
G03I-2500J0D01*
G01X1355452Y1686968D02*
G03I-2500J0D01*
G01X1363326Y1690905D02*
G03I-2500J0D01*
G01X1355452Y1701141D02*
G03I-2500J0D01*
G01X1363326Y1705078D02*
G03I-2500J0D01*
G01X1355452Y1715314D02*
G03I-2500J0D01*
G01X1363326Y1719251D02*
G03I-2500J0D01*
G01X1355452Y1729488D02*
G03I-2500J0D01*
G01X1363326Y1733425D02*
G03I-2500J0D01*
G01X1376533Y-410220D02*
X1364033D01*
X1366533Y-412080D01*
G01X1376533D02*
Y-408360D01*
G01X1374033Y-401230D02*
X1375492Y-400300D01*
X1376325Y-399060D01*
X1376533Y-397665D01*
X1376325Y-396425D01*
X1375283Y-395185D01*
X1374033Y-394410D01*
X1372783Y-394255D01*
X1371325Y-394565D01*
X1370283Y-395650D01*
X1369866Y-396735D01*
Y-398130D01*
G01Y-396735D02*
X1369241Y-395805D01*
X1368200Y-395030D01*
X1366950Y-394720D01*
X1365700Y-395030D01*
X1364658Y-395805D01*
X1364033Y-397200D01*
X1364241Y-398595D01*
X1365075Y-399990D01*
G01X1376533Y-385730D02*
X1373825Y-385420D01*
X1371533Y-384955D01*
X1369450Y-384335D01*
X1367158Y-383560D01*
X1364033Y-382320D01*
Y-388520D01*
G01Y-373020D02*
X1364450Y-374260D01*
X1365491Y-375190D01*
X1366741Y-375810D01*
X1368408Y-376275D01*
X1370283Y-376430D01*
X1372158Y-376275D01*
X1373825Y-375810D01*
X1375075Y-375190D01*
X1376116Y-374260D01*
X1376533Y-373020D01*
X1376116Y-371780D01*
X1375075Y-370850D01*
X1373825Y-370230D01*
X1372158Y-369765D01*
X1370283Y-369610D01*
X1368408Y-369765D01*
X1366741Y-370230D01*
X1365491Y-370850D01*
X1364450Y-371780D01*
X1364033Y-373020D01*
G01X1366116Y-363565D02*
X1364867Y-362635D01*
X1364241Y-361550D01*
X1364033Y-360310D01*
X1364450Y-358760D01*
X1365491Y-357675D01*
X1366741Y-357365D01*
X1367992Y-357520D01*
X1369033Y-358140D01*
X1371116Y-361240D01*
X1372575Y-362635D01*
X1374658Y-363565D01*
X1376533Y-363875D01*
Y-357365D01*
G01X1376950Y-348220D02*
X1376741Y-348530D01*
X1376325D01*
X1376116Y-348220D01*
X1376325Y-347910D01*
X1376741D01*
X1376950Y-348220D01*
G01X1376533Y-335820D02*
X1376325Y-334735D01*
X1375700Y-333495D01*
X1374658Y-332720D01*
X1373200Y-332410D01*
X1371742Y-332720D01*
X1370491Y-333650D01*
X1369866Y-335045D01*
Y-336595D01*
X1369450Y-337525D01*
X1368408Y-338300D01*
X1366950Y-338610D01*
X1365491Y-338145D01*
X1364450Y-337060D01*
X1364033Y-335820D01*
X1364450Y-334580D01*
X1365491Y-333495D01*
X1366950Y-333030D01*
X1368408Y-333340D01*
X1369450Y-334115D01*
X1369866Y-335045D01*
Y-336595D01*
X1370491Y-337990D01*
X1371742Y-338920D01*
X1373200Y-339230D01*
X1374658Y-338920D01*
X1375700Y-338145D01*
X1376325Y-336905D01*
X1376533Y-335820D01*
G01X1374033Y-326830D02*
X1375492Y-325900D01*
X1376325Y-324660D01*
X1376533Y-323265D01*
X1376325Y-322025D01*
X1375283Y-320785D01*
X1374033Y-320010D01*
X1372783Y-319855D01*
X1371325Y-320165D01*
X1370283Y-321250D01*
X1369866Y-322335D01*
Y-323730D01*
G01Y-322335D02*
X1369241Y-321405D01*
X1368200Y-320630D01*
X1366950Y-320320D01*
X1365700Y-320630D01*
X1364658Y-321405D01*
X1364033Y-322800D01*
X1364241Y-324195D01*
X1365075Y-325590D01*
G01X1374033Y-292230D02*
X1375492Y-291300D01*
X1376325Y-290060D01*
X1376533Y-288665D01*
X1376325Y-287425D01*
X1375283Y-286185D01*
X1374033Y-285410D01*
X1372783Y-285255D01*
X1371325Y-285565D01*
X1370283Y-286650D01*
X1369866Y-287735D01*
Y-289130D01*
G01Y-287735D02*
X1369241Y-286805D01*
X1368200Y-286030D01*
X1366950Y-285720D01*
X1365700Y-286030D01*
X1364658Y-286805D01*
X1364033Y-288200D01*
X1364241Y-289595D01*
X1365075Y-290990D01*
G01X1376533Y-274560D02*
X1364033D01*
X1372991Y-280295D01*
Y-272545D01*
G01X1376533Y-264020D02*
X1376325Y-262935D01*
X1375700Y-261695D01*
X1374658Y-260920D01*
X1373200Y-260610D01*
X1371742Y-260920D01*
X1370491Y-261850D01*
X1369866Y-263245D01*
Y-264795D01*
X1369450Y-265725D01*
X1368408Y-266500D01*
X1366950Y-266810D01*
X1365491Y-266345D01*
X1364450Y-265260D01*
X1364033Y-264020D01*
X1364450Y-262780D01*
X1365491Y-261695D01*
X1366950Y-261230D01*
X1368408Y-261540D01*
X1369450Y-262315D01*
X1369866Y-263245D01*
Y-264795D01*
X1370491Y-266190D01*
X1371742Y-267120D01*
X1373200Y-267430D01*
X1374658Y-267120D01*
X1375700Y-266345D01*
X1376325Y-265105D01*
X1376533Y-264020D01*
G01X1376950Y-251620D02*
X1376741Y-251930D01*
X1376325D01*
X1376116Y-251620D01*
X1376325Y-251310D01*
X1376741D01*
X1376950Y-251620D01*
G01X1364033Y-239220D02*
X1364450Y-240460D01*
X1365491Y-241390D01*
X1366741Y-242010D01*
X1368408Y-242475D01*
X1370283Y-242630D01*
X1372158Y-242475D01*
X1373825Y-242010D01*
X1375075Y-241390D01*
X1376116Y-240460D01*
X1376533Y-239220D01*
X1376116Y-237980D01*
X1375075Y-237050D01*
X1373825Y-236430D01*
X1372158Y-235965D01*
X1370283Y-235810D01*
X1368408Y-235965D01*
X1366741Y-236430D01*
X1365491Y-237050D01*
X1364450Y-237980D01*
X1364033Y-239220D01*
G01X1374658Y-230230D02*
X1375700Y-229300D01*
X1376325Y-228215D01*
X1376533Y-226820D01*
X1376116Y-225425D01*
X1375283Y-224340D01*
X1373825Y-223565D01*
X1372158Y-223410D01*
X1370491Y-223720D01*
X1369450Y-224495D01*
X1368616Y-225580D01*
X1368408Y-226665D01*
X1368616Y-227750D01*
X1369450Y-229145D01*
X1364033Y-228680D01*
Y-224495D01*
G01X1415379Y1928465D02*
X1407879D01*
X1414129Y1930892D01*
X1407879Y1933319D01*
X1415379D01*
G01Y1936059D02*
X1407879Y1938392D01*
X1415379Y1940725D01*
G01X1412754Y1939885D02*
Y1936899D01*
G01X1415379Y1944025D02*
X1407879D01*
Y1946359D01*
X1408254Y1947105D01*
X1408754Y1947572D01*
X1409754Y1947759D01*
X1410754Y1947572D01*
X1411379Y1947012D01*
X1411754Y1946359D01*
Y1944025D01*
G01Y1946359D02*
X1415379Y1947759D01*
G01Y1951339D02*
X1407879D01*
G01Y1954885D02*
X1412504Y1951339D01*
G01X1415379Y1955445D02*
X1410379Y1952925D01*
G01X1415629Y1960892D02*
X1415504Y1960705D01*
X1415254D01*
X1415129Y1960892D01*
X1415254Y1961079D01*
X1415504D01*
X1415629Y1960892D01*
G01X1412254D02*
X1412129Y1960705D01*
X1411879D01*
X1411754Y1960892D01*
X1411879Y1961079D01*
X1412129D01*
X1412254Y1960892D01*
G01X1407879Y1968392D02*
X1415379D01*
G01X1407879Y1966245D02*
Y1970539D01*
G01Y1974772D02*
Y1977012D01*
G01Y1975892D02*
X1415379D01*
G01Y1974772D02*
Y1977012D01*
G01Y1981245D02*
X1407879D01*
X1415379Y1985539D01*
X1407879D01*
G01Y1996525D02*
X1415379D01*
Y2000259D01*
G01Y2007759D02*
Y2004025D01*
X1407879D01*
Y2007759D01*
G01X1411504Y2006265D02*
Y2004025D01*
G01X1415379Y2011059D02*
X1407879Y2013392D01*
X1415379Y2015725D01*
G01X1412754Y2014885D02*
Y2011899D01*
G01X1415379Y2018839D02*
X1407879D01*
Y2020705D01*
X1408254Y2021452D01*
X1408754Y2022012D01*
X1409504Y2022479D01*
X1410379Y2022852D01*
X1411629Y2022945D01*
X1412879Y2022852D01*
X1413754Y2022479D01*
X1414504Y2022012D01*
X1415004Y2021452D01*
X1415379Y2020705D01*
Y2018839D01*
G01X1415629Y2028392D02*
X1415504Y2028205D01*
X1415254D01*
X1415129Y2028392D01*
X1415254Y2028579D01*
X1415504D01*
X1415629Y2028392D01*
G01X1412254D02*
X1412129Y2028205D01*
X1411879D01*
X1411754Y2028392D01*
X1411879Y2028579D01*
X1412129D01*
X1412254Y2028392D01*
G01X1415379Y2034025D02*
X1407879D01*
Y2036359D01*
X1408254Y2037105D01*
X1408754Y2037572D01*
X1409754Y2037759D01*
X1410754Y2037572D01*
X1411379Y2037012D01*
X1411754Y2036359D01*
Y2034025D01*
G01Y2036359D02*
X1415379Y2037759D01*
G01Y2045259D02*
Y2041525D01*
X1407879D01*
Y2045259D01*
G01X1411504Y2043765D02*
Y2041525D01*
G01X1408504Y2052945D02*
X1408129Y2052385D01*
X1407879Y2051732D01*
Y2050985D01*
X1408254Y2050145D01*
X1408879Y2049492D01*
X1409629Y2049025D01*
X1410879Y2048652D01*
X1412004Y2048559D01*
X1413129Y2048745D01*
X1413879Y2049025D01*
X1414629Y2049585D01*
X1415129Y2050239D01*
X1415379Y2050892D01*
Y2051545D01*
X1415129Y2052199D01*
X1414754Y2052759D01*
X1414254Y2053225D01*
G01X1415379Y2058392D02*
X1415254Y2057645D01*
X1414754Y2056992D01*
X1414004Y2056432D01*
X1413129Y2056059D01*
X1412129Y2055872D01*
X1411129D01*
X1410129Y2056059D01*
X1409254Y2056432D01*
X1408504Y2056992D01*
X1408004Y2057645D01*
X1407879Y2058392D01*
X1408004Y2059139D01*
X1408504Y2059792D01*
X1409254Y2060352D01*
X1410129Y2060725D01*
X1411129Y2060912D01*
X1412129D01*
X1413129Y2060725D01*
X1414004Y2060352D01*
X1414754Y2059792D01*
X1415254Y2059139D01*
X1415379Y2058392D01*
G01Y2063465D02*
X1407879D01*
X1414129Y2065892D01*
X1407879Y2068319D01*
X1415379D01*
G01Y2070965D02*
X1407879D01*
X1414129Y2073392D01*
X1407879Y2075819D01*
X1415379D01*
G01Y2082759D02*
Y2079025D01*
X1407879D01*
Y2082759D01*
G01X1411504Y2081265D02*
Y2079025D01*
G01X1415379Y2086245D02*
X1407879D01*
X1415379Y2090539D01*
X1407879D01*
G01X1415379Y2093839D02*
X1407879D01*
Y2095705D01*
X1408254Y2096452D01*
X1408754Y2097012D01*
X1409504Y2097479D01*
X1410379Y2097852D01*
X1411629Y2097945D01*
X1412879Y2097852D01*
X1413754Y2097479D01*
X1414504Y2097012D01*
X1415004Y2096452D01*
X1415379Y2095705D01*
Y2093839D01*
G01Y2105259D02*
Y2101525D01*
X1407879D01*
Y2105259D01*
G01X1411504Y2103765D02*
Y2101525D01*
G01X1415379Y2108839D02*
X1407879D01*
Y2110705D01*
X1408254Y2111452D01*
X1408754Y2112012D01*
X1409504Y2112479D01*
X1410379Y2112852D01*
X1411629Y2112945D01*
X1412879Y2112852D01*
X1413754Y2112479D01*
X1414504Y2112012D01*
X1415004Y2111452D01*
X1415379Y2110705D01*
Y2108839D01*
G01Y2123839D02*
X1407879D01*
Y2125705D01*
X1408254Y2126452D01*
X1408754Y2127012D01*
X1409504Y2127479D01*
X1410379Y2127852D01*
X1411629Y2127945D01*
X1412879Y2127852D01*
X1413754Y2127479D01*
X1414504Y2127012D01*
X1415004Y2126452D01*
X1415379Y2125705D01*
Y2123839D01*
G01Y2131525D02*
X1407879D01*
Y2133859D01*
X1408254Y2134605D01*
X1408754Y2135072D01*
X1409754Y2135259D01*
X1410754Y2135072D01*
X1411379Y2134512D01*
X1411754Y2133859D01*
Y2131525D01*
G01Y2133859D02*
X1415379Y2135259D01*
G01X1407879Y2139772D02*
Y2142012D01*
G01Y2140892D02*
X1415379D01*
G01Y2139772D02*
Y2142012D01*
G01X1407879Y2146525D02*
X1415379D01*
Y2150259D01*
G01X1407879Y2154025D02*
X1415379D01*
Y2157759D01*
G01X1414379Y2168932D02*
X1415004Y2169679D01*
X1415379Y2170519D01*
Y2171265D01*
X1415004Y2172012D01*
X1414379Y2172572D01*
X1413504Y2172852D01*
X1412629Y2172665D01*
X1411879Y2172199D01*
X1411379Y2171359D01*
X1411129Y2170239D01*
X1410629Y2169585D01*
X1409754Y2169305D01*
X1408879Y2169492D01*
X1408254Y2169959D01*
X1407879Y2170612D01*
Y2171265D01*
X1408129Y2171919D01*
X1408754Y2172479D01*
G01X1407879Y2177272D02*
Y2179512D01*
G01Y2178392D02*
X1415379D01*
G01Y2177272D02*
Y2179512D01*
G01X1407879Y2184119D02*
Y2187665D01*
X1415379Y2184119D01*
Y2187665D01*
G01Y2195259D02*
Y2191525D01*
X1407879D01*
Y2195259D01*
G01X1411504Y2193765D02*
Y2191525D01*
G01X1415379Y2206619D02*
X1407879D01*
Y2210165D01*
G01X1411504Y2208859D02*
Y2206619D01*
G01X1415379Y2215892D02*
X1415254Y2215145D01*
X1414754Y2214492D01*
X1414004Y2213932D01*
X1413129Y2213559D01*
X1412129Y2213372D01*
X1411129D01*
X1410129Y2213559D01*
X1409254Y2213932D01*
X1408504Y2214492D01*
X1408004Y2215145D01*
X1407879Y2215892D01*
X1408004Y2216639D01*
X1408504Y2217292D01*
X1409254Y2217852D01*
X1410129Y2218225D01*
X1411129Y2218412D01*
X1412129D01*
X1413129Y2218225D01*
X1414004Y2217852D01*
X1414754Y2217292D01*
X1415254Y2216639D01*
X1415379Y2215892D01*
G01Y2221525D02*
X1407879D01*
Y2223859D01*
X1408254Y2224605D01*
X1408754Y2225072D01*
X1409754Y2225259D01*
X1410754Y2225072D01*
X1411379Y2224512D01*
X1411754Y2223859D01*
Y2221525D01*
G01Y2223859D02*
X1415379Y2225259D01*
G01X1407879Y2238392D02*
X1408129Y2237645D01*
X1408754Y2237085D01*
X1409504Y2236712D01*
X1410504Y2236432D01*
X1411629Y2236339D01*
X1412754Y2236432D01*
X1413754Y2236712D01*
X1414504Y2237085D01*
X1415129Y2237645D01*
X1415379Y2238392D01*
X1415129Y2239139D01*
X1414504Y2239699D01*
X1413754Y2240072D01*
X1412754Y2240352D01*
X1411629Y2240445D01*
X1410504Y2240352D01*
X1409504Y2240072D01*
X1408754Y2239699D01*
X1408129Y2239139D01*
X1407879Y2238392D01*
G01X1415629Y2245892D02*
X1415504Y2245705D01*
X1415254D01*
X1415129Y2245892D01*
X1415254Y2246079D01*
X1415504D01*
X1415629Y2245892D01*
G01X1414254Y2251339D02*
X1414879Y2251899D01*
X1415254Y2252552D01*
X1415379Y2253392D01*
X1415129Y2254232D01*
X1414629Y2254885D01*
X1413754Y2255352D01*
X1412754Y2255445D01*
X1411754Y2255259D01*
X1411129Y2254792D01*
X1410629Y2254139D01*
X1410504Y2253485D01*
X1410629Y2252832D01*
X1411129Y2251992D01*
X1407879Y2252272D01*
Y2254792D01*
G01X1415379Y2258465D02*
X1407879D01*
X1414129Y2260892D01*
X1407879Y2263319D01*
X1415379D01*
G01Y2265965D02*
X1407879D01*
X1414129Y2268392D01*
X1407879Y2270819D01*
X1415379D01*
G01Y2281619D02*
X1407879D01*
Y2285165D01*
G01X1411504Y2283859D02*
Y2281619D01*
G01X1407879Y2289772D02*
Y2292012D01*
G01Y2290892D02*
X1415379D01*
G01Y2289772D02*
Y2292012D01*
G01Y2296245D02*
X1407879D01*
X1415379Y2300539D01*
X1407879D01*
G01Y2304772D02*
Y2307012D01*
G01Y2305892D02*
X1415379D01*
G01Y2304772D02*
Y2307012D01*
G01X1414379Y2311432D02*
X1415004Y2312179D01*
X1415379Y2313019D01*
Y2313765D01*
X1415004Y2314512D01*
X1414379Y2315072D01*
X1413504Y2315352D01*
X1412629Y2315165D01*
X1411879Y2314699D01*
X1411379Y2313859D01*
X1411129Y2312739D01*
X1410629Y2312085D01*
X1409754Y2311805D01*
X1408879Y2311992D01*
X1408254Y2312459D01*
X1407879Y2313112D01*
Y2313765D01*
X1408129Y2314419D01*
X1408754Y2314979D01*
G01X1415379Y2318932D02*
X1407879D01*
G01Y2322852D02*
X1415379D01*
G01X1411629D02*
Y2318932D01*
G01X1415379Y2330259D02*
Y2326525D01*
X1407879D01*
Y2330259D01*
G01X1411504Y2328765D02*
Y2326525D01*
G01X1415379Y2333839D02*
X1407879D01*
Y2335705D01*
X1408254Y2336452D01*
X1408754Y2337012D01*
X1409504Y2337479D01*
X1410379Y2337852D01*
X1411629Y2337945D01*
X1412879Y2337852D01*
X1413754Y2337479D01*
X1414504Y2337012D01*
X1415004Y2336452D01*
X1415379Y2335705D01*
Y2333839D01*
G01Y2349025D02*
X1407879D01*
Y2351265D01*
X1408254Y2352012D01*
X1409129Y2352572D01*
X1410129Y2352759D01*
X1411129Y2352572D01*
X1411879Y2352105D01*
X1412254Y2351265D01*
Y2349025D01*
G01X1407879Y2358392D02*
X1415379D01*
G01X1407879Y2356245D02*
Y2360539D01*
G01X1415379Y2363932D02*
X1407879D01*
G01Y2367852D02*
X1415379D01*
G01X1411629D02*
Y2363932D01*
G01X1407879Y2379772D02*
Y2382012D01*
G01Y2380892D02*
X1415379D01*
G01Y2379772D02*
Y2382012D01*
G01X1414379Y2386432D02*
X1415004Y2387179D01*
X1415379Y2388019D01*
Y2388765D01*
X1415004Y2389512D01*
X1414379Y2390072D01*
X1413504Y2390352D01*
X1412629Y2390165D01*
X1411879Y2389699D01*
X1411379Y2388859D01*
X1411129Y2387739D01*
X1410629Y2387085D01*
X1409754Y2386805D01*
X1408879Y2386992D01*
X1408254Y2387459D01*
X1407879Y2388112D01*
Y2388765D01*
X1408129Y2389419D01*
X1408754Y2389979D01*
G01X1407879Y2403392D02*
X1408129Y2402645D01*
X1408754Y2402085D01*
X1409504Y2401712D01*
X1410504Y2401432D01*
X1411629Y2401339D01*
X1412754Y2401432D01*
X1413754Y2401712D01*
X1414504Y2402085D01*
X1415129Y2402645D01*
X1415379Y2403392D01*
X1415129Y2404139D01*
X1414504Y2404699D01*
X1413754Y2405072D01*
X1412754Y2405352D01*
X1411629Y2405445D01*
X1410504Y2405352D01*
X1409504Y2405072D01*
X1408754Y2404699D01*
X1408129Y2404139D01*
X1407879Y2403392D01*
G01X1415629Y2410892D02*
X1415504Y2410705D01*
X1415254D01*
X1415129Y2410892D01*
X1415254Y2411079D01*
X1415504D01*
X1415629Y2410892D01*
G01X1412254Y2416619D02*
X1411379Y2417272D01*
X1410879Y2417832D01*
X1410629Y2418579D01*
X1410879Y2419232D01*
X1411379Y2419699D01*
X1412129Y2420072D01*
X1413004Y2420165D01*
X1413754Y2420072D01*
X1414504Y2419699D01*
X1415129Y2419139D01*
X1415379Y2418485D01*
X1415129Y2417739D01*
X1414379Y2417085D01*
X1413254Y2416712D01*
X1412004Y2416619D01*
X1410379Y2416805D01*
X1409504Y2417085D01*
X1408629Y2417552D01*
X1408004Y2418205D01*
X1407879Y2418859D01*
X1408129Y2419512D01*
X1408754Y2419979D01*
G01X1415379Y2423465D02*
X1407879D01*
X1414129Y2425892D01*
X1407879Y2428319D01*
X1415379D01*
G01Y2430965D02*
X1407879D01*
X1414129Y2433392D01*
X1407879Y2435819D01*
X1415379D01*
G01Y2445965D02*
X1407879D01*
X1414129Y2448392D01*
X1407879Y2450819D01*
X1415379D01*
G01Y2457759D02*
Y2454025D01*
X1407879D01*
Y2457759D01*
G01X1411504Y2456265D02*
Y2454025D01*
G01X1407879Y2463392D02*
X1415379D01*
G01X1407879Y2461245D02*
Y2465539D01*
G01X1415379Y2469025D02*
X1407879D01*
Y2471359D01*
X1408254Y2472105D01*
X1408754Y2472572D01*
X1409754Y2472759D01*
X1410754Y2472572D01*
X1411379Y2472012D01*
X1411754Y2471359D01*
Y2469025D01*
G01Y2471359D02*
X1415379Y2472759D01*
G01X1407879Y2477272D02*
Y2479512D01*
G01Y2478392D02*
X1415379D01*
G01Y2477272D02*
Y2479512D01*
G01X1408504Y2487945D02*
X1408129Y2487385D01*
X1407879Y2486732D01*
Y2485985D01*
X1408254Y2485145D01*
X1408879Y2484492D01*
X1409629Y2484025D01*
X1410879Y2483652D01*
X1412004Y2483559D01*
X1413129Y2483745D01*
X1413879Y2484025D01*
X1414629Y2484585D01*
X1415129Y2485239D01*
X1415379Y2485892D01*
Y2486545D01*
X1415129Y2487199D01*
X1414754Y2487759D01*
X1414254Y2488225D01*
G01X1415379Y2498839D02*
X1407879D01*
Y2500705D01*
X1408254Y2501452D01*
X1408754Y2502012D01*
X1409504Y2502479D01*
X1410379Y2502852D01*
X1411629Y2502945D01*
X1412879Y2502852D01*
X1413754Y2502479D01*
X1414504Y2502012D01*
X1415004Y2501452D01*
X1415379Y2500705D01*
Y2498839D01*
G01Y2506525D02*
X1407879D01*
Y2508859D01*
X1408254Y2509605D01*
X1408754Y2510072D01*
X1409754Y2510259D01*
X1410754Y2510072D01*
X1411379Y2509512D01*
X1411754Y2508859D01*
Y2506525D01*
G01Y2508859D02*
X1415379Y2510259D01*
G01X1407879Y2514772D02*
Y2517012D01*
G01Y2515892D02*
X1415379D01*
G01Y2514772D02*
Y2517012D01*
G01X1407879Y2521525D02*
X1415379D01*
Y2525259D01*
G01X1407879Y2529025D02*
X1415379D01*
Y2532759D01*
G01X1417879Y2537925D02*
X1416629Y2536992D01*
X1415379Y2536525D01*
X1410379D01*
X1409129Y2536992D01*
X1407879Y2537925D01*
G01Y2545892D02*
X1408129Y2545145D01*
X1408754Y2544585D01*
X1409504Y2544212D01*
X1410504Y2543932D01*
X1411629Y2543839D01*
X1412754Y2543932D01*
X1413754Y2544212D01*
X1414504Y2544585D01*
X1415129Y2545145D01*
X1415379Y2545892D01*
X1415129Y2546639D01*
X1414504Y2547199D01*
X1413754Y2547572D01*
X1412754Y2547852D01*
X1411629Y2547945D01*
X1410504Y2547852D01*
X1409504Y2547572D01*
X1408754Y2547199D01*
X1408129Y2546639D01*
X1407879Y2545892D01*
G01X1415629Y2553392D02*
X1415504Y2553205D01*
X1415254D01*
X1415129Y2553392D01*
X1415254Y2553579D01*
X1415504D01*
X1415629Y2553392D01*
G01X1407879Y2560892D02*
X1408129Y2560145D01*
X1408754Y2559585D01*
X1409504Y2559212D01*
X1410504Y2558932D01*
X1411629Y2558839D01*
X1412754Y2558932D01*
X1413754Y2559212D01*
X1414504Y2559585D01*
X1415129Y2560145D01*
X1415379Y2560892D01*
X1415129Y2561639D01*
X1414504Y2562199D01*
X1413754Y2562572D01*
X1412754Y2562852D01*
X1411629Y2562945D01*
X1410504Y2562852D01*
X1409504Y2562572D01*
X1408754Y2562199D01*
X1408129Y2561639D01*
X1407879Y2560892D01*
G01X1409129Y2566619D02*
X1408379Y2567179D01*
X1408004Y2567832D01*
X1407879Y2568579D01*
X1408129Y2569512D01*
X1408754Y2570165D01*
X1409504Y2570352D01*
X1410254Y2570259D01*
X1410879Y2569885D01*
X1412129Y2568019D01*
X1413004Y2567179D01*
X1414254Y2566619D01*
X1415379Y2566432D01*
Y2570352D01*
G01X1413879Y2573839D02*
X1414754Y2574399D01*
X1415254Y2575145D01*
X1415379Y2575985D01*
X1415254Y2576732D01*
X1414629Y2577479D01*
X1413879Y2577945D01*
X1413129Y2578039D01*
X1412254Y2577852D01*
X1411629Y2577199D01*
X1411379Y2576545D01*
Y2575705D01*
G01Y2576545D02*
X1411004Y2577105D01*
X1410379Y2577572D01*
X1409629Y2577759D01*
X1408879Y2577572D01*
X1408254Y2577105D01*
X1407879Y2576265D01*
X1408004Y2575425D01*
X1408504Y2574585D01*
G01X1412254Y2581619D02*
X1411379Y2582272D01*
X1410879Y2582832D01*
X1410629Y2583579D01*
X1410879Y2584232D01*
X1411379Y2584699D01*
X1412129Y2585072D01*
X1413004Y2585165D01*
X1413754Y2585072D01*
X1414504Y2584699D01*
X1415129Y2584139D01*
X1415379Y2583485D01*
X1415129Y2582739D01*
X1414379Y2582085D01*
X1413254Y2581712D01*
X1412004Y2581619D01*
X1410379Y2581805D01*
X1409504Y2582085D01*
X1408629Y2582552D01*
X1408004Y2583205D01*
X1407879Y2583859D01*
X1408129Y2584512D01*
X1408754Y2584979D01*
G01X1409504Y2590052D02*
X1407879Y2590519D01*
G01Y2591732D02*
X1409504Y2591265D01*
G01X1417879Y2598859D02*
X1416629Y2599792D01*
X1415379Y2600259D01*
X1410379D01*
X1409129Y2599792D01*
X1407879Y2598859D01*
G01X1415629Y2605892D02*
X1415504Y2605705D01*
X1415254D01*
X1415129Y2605892D01*
X1415254Y2606079D01*
X1415504D01*
X1415629Y2605892D01*
G01X1422784Y1970673D02*
X1422409Y1970113D01*
X1422159Y1969460D01*
Y1968713D01*
X1422534Y1967873D01*
X1423159Y1967220D01*
X1423909Y1966753D01*
X1425159Y1966380D01*
X1426284Y1966287D01*
X1427409Y1966473D01*
X1428159Y1966753D01*
X1428909Y1967313D01*
X1429409Y1967967D01*
X1429659Y1968620D01*
Y1969273D01*
X1429409Y1969927D01*
X1429034Y1970487D01*
X1428534Y1970953D01*
G01X1429659Y1976120D02*
X1429534Y1975373D01*
X1429034Y1974720D01*
X1428284Y1974160D01*
X1427409Y1973787D01*
X1426409Y1973600D01*
X1425409D01*
X1424409Y1973787D01*
X1423534Y1974160D01*
X1422784Y1974720D01*
X1422284Y1975373D01*
X1422159Y1976120D01*
X1422284Y1976867D01*
X1422784Y1977520D01*
X1423534Y1978080D01*
X1424409Y1978453D01*
X1425409Y1978640D01*
X1426409D01*
X1427409Y1978453D01*
X1428284Y1978080D01*
X1429034Y1977520D01*
X1429534Y1976867D01*
X1429659Y1976120D01*
G01Y1981753D02*
X1422159D01*
Y1983993D01*
X1422534Y1984740D01*
X1423409Y1985300D01*
X1424409Y1985487D01*
X1425409Y1985300D01*
X1426159Y1984833D01*
X1426534Y1983993D01*
Y1981753D01*
G01X1429659Y1989253D02*
X1422159D01*
Y1991493D01*
X1422534Y1992240D01*
X1423409Y1992800D01*
X1424409Y1992987D01*
X1425409Y1992800D01*
X1426159Y1992333D01*
X1426534Y1991493D01*
Y1989253D01*
G01X1429659Y2000487D02*
Y1996753D01*
X1422159D01*
Y2000487D01*
G01X1425784Y1998993D02*
Y1996753D01*
G01X1429659Y2004253D02*
X1422159D01*
Y2006587D01*
X1422534Y2007333D01*
X1423034Y2007800D01*
X1424034Y2007987D01*
X1425034Y2007800D01*
X1425659Y2007240D01*
X1426034Y2006587D01*
Y2004253D01*
G01Y2006587D02*
X1429659Y2007987D01*
G01Y2021120D02*
X1429534Y2020373D01*
X1429034Y2019720D01*
X1428284Y2019160D01*
X1427409Y2018787D01*
X1426409Y2018600D01*
X1425409D01*
X1424409Y2018787D01*
X1423534Y2019160D01*
X1422784Y2019720D01*
X1422284Y2020373D01*
X1422159Y2021120D01*
X1422284Y2021867D01*
X1422784Y2022520D01*
X1423534Y2023080D01*
X1424409Y2023453D01*
X1425409Y2023640D01*
X1426409D01*
X1427409Y2023453D01*
X1428284Y2023080D01*
X1429034Y2022520D01*
X1429534Y2021867D01*
X1429659Y2021120D01*
G01X1428659Y2026660D02*
X1429284Y2027407D01*
X1429659Y2028247D01*
Y2028993D01*
X1429284Y2029740D01*
X1428659Y2030300D01*
X1427784Y2030580D01*
X1426909Y2030393D01*
X1426159Y2029927D01*
X1425659Y2029087D01*
X1425409Y2027967D01*
X1424909Y2027313D01*
X1424034Y2027033D01*
X1423159Y2027220D01*
X1422534Y2027687D01*
X1422159Y2028340D01*
Y2028993D01*
X1422409Y2029647D01*
X1423034Y2030207D01*
G01X1429659Y2034253D02*
X1422159D01*
Y2036493D01*
X1422534Y2037240D01*
X1423409Y2037800D01*
X1424409Y2037987D01*
X1425409Y2037800D01*
X1426159Y2037333D01*
X1426534Y2036493D01*
Y2034253D01*
G01X1429909Y2041940D02*
X1422159Y2045300D01*
G01Y2051120D02*
X1429659D01*
G01X1422159Y2048973D02*
Y2053267D01*
G01Y2057500D02*
Y2059740D01*
G01Y2058620D02*
X1429659D01*
G01Y2057500D02*
Y2059740D01*
G01Y2063973D02*
X1422159D01*
X1429659Y2068267D01*
X1422159D01*
G01X1432159Y2073153D02*
X1430909Y2072220D01*
X1429659Y2071753D01*
X1424659D01*
X1423409Y2072220D01*
X1422159Y2073153D01*
G01Y2080000D02*
Y2082240D01*
G01Y2081120D02*
X1429659D01*
G01Y2080000D02*
Y2082240D01*
G01Y2086193D02*
X1422159D01*
X1428409Y2088620D01*
X1422159Y2091047D01*
X1429659D01*
G01Y2093693D02*
X1422159D01*
X1428409Y2096120D01*
X1422159Y2098547D01*
X1429659D01*
G01Y2105487D02*
Y2101753D01*
X1422159D01*
Y2105487D01*
G01X1425784Y2103993D02*
Y2101753D01*
G01X1429659Y2109253D02*
X1422159D01*
Y2111587D01*
X1422534Y2112333D01*
X1423034Y2112800D01*
X1424034Y2112987D01*
X1425034Y2112800D01*
X1425659Y2112240D01*
X1426034Y2111587D01*
Y2109253D01*
G01Y2111587D02*
X1429659Y2112987D01*
G01X1428659Y2116660D02*
X1429284Y2117407D01*
X1429659Y2118247D01*
Y2118993D01*
X1429284Y2119740D01*
X1428659Y2120300D01*
X1427784Y2120580D01*
X1426909Y2120393D01*
X1426159Y2119927D01*
X1425659Y2119087D01*
X1425409Y2117967D01*
X1424909Y2117313D01*
X1424034Y2117033D01*
X1423159Y2117220D01*
X1422534Y2117687D01*
X1422159Y2118340D01*
Y2118993D01*
X1422409Y2119647D01*
X1423034Y2120207D01*
G01X1422159Y2125000D02*
Y2127240D01*
G01Y2126120D02*
X1429659D01*
G01Y2125000D02*
Y2127240D01*
G01Y2133620D02*
X1429534Y2132873D01*
X1429034Y2132220D01*
X1428284Y2131660D01*
X1427409Y2131287D01*
X1426409Y2131100D01*
X1425409D01*
X1424409Y2131287D01*
X1423534Y2131660D01*
X1422784Y2132220D01*
X1422284Y2132873D01*
X1422159Y2133620D01*
X1422284Y2134367D01*
X1422784Y2135020D01*
X1423534Y2135580D01*
X1424409Y2135953D01*
X1425409Y2136140D01*
X1426409D01*
X1427409Y2135953D01*
X1428284Y2135580D01*
X1429034Y2135020D01*
X1429534Y2134367D01*
X1429659Y2133620D01*
G01Y2138973D02*
X1422159D01*
X1429659Y2143267D01*
X1422159D01*
G01X1432159Y2149087D02*
X1430909Y2150020D01*
X1429659Y2150487D01*
X1424659D01*
X1423409Y2150020D01*
X1422159Y2149087D01*
G01X1429909Y2156120D02*
X1429784Y2155933D01*
X1429534D01*
X1429409Y2156120D01*
X1429534Y2156307D01*
X1429784D01*
X1429909Y2156120D01*
G01X1426534D02*
X1426409Y2155933D01*
X1426159D01*
X1426034Y2156120D01*
X1426159Y2156307D01*
X1426409D01*
X1426534Y2156120D01*
G01X1429659Y2161753D02*
X1422159D01*
Y2164087D01*
X1422534Y2164833D01*
X1423034Y2165300D01*
X1424034Y2165487D01*
X1425034Y2165300D01*
X1425659Y2164740D01*
X1426034Y2164087D01*
Y2161753D01*
G01Y2164087D02*
X1429659Y2165487D01*
G01Y2172987D02*
Y2169253D01*
X1422159D01*
Y2172987D01*
G01X1425784Y2171493D02*
Y2169253D01*
G01X1422784Y2180673D02*
X1422409Y2180113D01*
X1422159Y2179460D01*
Y2178713D01*
X1422534Y2177873D01*
X1423159Y2177220D01*
X1423909Y2176753D01*
X1425159Y2176380D01*
X1426284Y2176287D01*
X1427409Y2176473D01*
X1428159Y2176753D01*
X1428909Y2177313D01*
X1429409Y2177967D01*
X1429659Y2178620D01*
Y2179273D01*
X1429409Y2179927D01*
X1429034Y2180487D01*
X1428534Y2180953D01*
G01X1429659Y2186120D02*
X1429534Y2185373D01*
X1429034Y2184720D01*
X1428284Y2184160D01*
X1427409Y2183787D01*
X1426409Y2183600D01*
X1425409D01*
X1424409Y2183787D01*
X1423534Y2184160D01*
X1422784Y2184720D01*
X1422284Y2185373D01*
X1422159Y2186120D01*
X1422284Y2186867D01*
X1422784Y2187520D01*
X1423534Y2188080D01*
X1424409Y2188453D01*
X1425409Y2188640D01*
X1426409D01*
X1427409Y2188453D01*
X1428284Y2188080D01*
X1429034Y2187520D01*
X1429534Y2186867D01*
X1429659Y2186120D01*
G01Y2191193D02*
X1422159D01*
X1428409Y2193620D01*
X1422159Y2196047D01*
X1429659D01*
G01Y2198693D02*
X1422159D01*
X1428409Y2201120D01*
X1422159Y2203547D01*
X1429659D01*
G01Y2210487D02*
Y2206753D01*
X1422159D01*
Y2210487D01*
G01X1425784Y2208993D02*
Y2206753D01*
G01X1429659Y2213973D02*
X1422159D01*
X1429659Y2218267D01*
X1422159D01*
G01X1429659Y2221567D02*
X1422159D01*
Y2223433D01*
X1422534Y2224180D01*
X1423034Y2224740D01*
X1423784Y2225207D01*
X1424659Y2225580D01*
X1425909Y2225673D01*
X1427159Y2225580D01*
X1428034Y2225207D01*
X1428784Y2224740D01*
X1429284Y2224180D01*
X1429659Y2223433D01*
Y2221567D01*
G01Y2232987D02*
Y2229253D01*
X1422159D01*
Y2232987D01*
G01X1425784Y2231493D02*
Y2229253D01*
G01X1429659Y2236567D02*
X1422159D01*
Y2238433D01*
X1422534Y2239180D01*
X1423034Y2239740D01*
X1423784Y2240207D01*
X1424659Y2240580D01*
X1425909Y2240673D01*
X1427159Y2240580D01*
X1428034Y2240207D01*
X1428784Y2239740D01*
X1429284Y2239180D01*
X1429659Y2238433D01*
Y2236567D01*
G01Y2251567D02*
X1422159D01*
Y2253433D01*
X1422534Y2254180D01*
X1423034Y2254740D01*
X1423784Y2255207D01*
X1424659Y2255580D01*
X1425909Y2255673D01*
X1427159Y2255580D01*
X1428034Y2255207D01*
X1428784Y2254740D01*
X1429284Y2254180D01*
X1429659Y2253433D01*
Y2251567D01*
G01Y2259253D02*
X1422159D01*
Y2261587D01*
X1422534Y2262333D01*
X1423034Y2262800D01*
X1424034Y2262987D01*
X1425034Y2262800D01*
X1425659Y2262240D01*
X1426034Y2261587D01*
Y2259253D01*
G01Y2261587D02*
X1429659Y2262987D01*
G01X1422159Y2267500D02*
Y2269740D01*
G01Y2268620D02*
X1429659D01*
G01Y2267500D02*
Y2269740D01*
G01X1422159Y2274253D02*
X1429659D01*
Y2277987D01*
G01X1422159Y2281753D02*
X1429659D01*
Y2285487D01*
G01X1428659Y2296660D02*
X1429284Y2297407D01*
X1429659Y2298247D01*
Y2298993D01*
X1429284Y2299740D01*
X1428659Y2300300D01*
X1427784Y2300580D01*
X1426909Y2300393D01*
X1426159Y2299927D01*
X1425659Y2299087D01*
X1425409Y2297967D01*
X1424909Y2297313D01*
X1424034Y2297033D01*
X1423159Y2297220D01*
X1422534Y2297687D01*
X1422159Y2298340D01*
Y2298993D01*
X1422409Y2299647D01*
X1423034Y2300207D01*
G01X1422159Y2305000D02*
Y2307240D01*
G01Y2306120D02*
X1429659D01*
G01Y2305000D02*
Y2307240D01*
G01X1422159Y2311847D02*
Y2315393D01*
X1429659Y2311847D01*
Y2315393D01*
G01Y2322987D02*
Y2319253D01*
X1422159D01*
Y2322987D01*
G01X1425784Y2321493D02*
Y2319253D01*
G01X1429659Y2334347D02*
X1422159D01*
Y2337893D01*
G01X1425784Y2336587D02*
Y2334347D01*
G01X1429659Y2343620D02*
X1429534Y2342873D01*
X1429034Y2342220D01*
X1428284Y2341660D01*
X1427409Y2341287D01*
X1426409Y2341100D01*
X1425409D01*
X1424409Y2341287D01*
X1423534Y2341660D01*
X1422784Y2342220D01*
X1422284Y2342873D01*
X1422159Y2343620D01*
X1422284Y2344367D01*
X1422784Y2345020D01*
X1423534Y2345580D01*
X1424409Y2345953D01*
X1425409Y2346140D01*
X1426409D01*
X1427409Y2345953D01*
X1428284Y2345580D01*
X1429034Y2345020D01*
X1429534Y2344367D01*
X1429659Y2343620D01*
G01Y2349253D02*
X1422159D01*
Y2351587D01*
X1422534Y2352333D01*
X1423034Y2352800D01*
X1424034Y2352987D01*
X1425034Y2352800D01*
X1425659Y2352240D01*
X1426034Y2351587D01*
Y2349253D01*
G01Y2351587D02*
X1429659Y2352987D01*
G01X1422159Y2366120D02*
X1422409Y2365373D01*
X1423034Y2364813D01*
X1423784Y2364440D01*
X1424784Y2364160D01*
X1425909Y2364067D01*
X1427034Y2364160D01*
X1428034Y2364440D01*
X1428784Y2364813D01*
X1429409Y2365373D01*
X1429659Y2366120D01*
X1429409Y2366867D01*
X1428784Y2367427D01*
X1428034Y2367800D01*
X1427034Y2368080D01*
X1425909Y2368173D01*
X1424784Y2368080D01*
X1423784Y2367800D01*
X1423034Y2367427D01*
X1422409Y2366867D01*
X1422159Y2366120D01*
G01X1429909Y2373620D02*
X1429784Y2373433D01*
X1429534D01*
X1429409Y2373620D01*
X1429534Y2373807D01*
X1429784D01*
X1429909Y2373620D01*
G01X1428534Y2379067D02*
X1429159Y2379627D01*
X1429534Y2380280D01*
X1429659Y2381120D01*
X1429409Y2381960D01*
X1428909Y2382613D01*
X1428034Y2383080D01*
X1427034Y2383173D01*
X1426034Y2382987D01*
X1425409Y2382520D01*
X1424909Y2381867D01*
X1424784Y2381213D01*
X1424909Y2380560D01*
X1425409Y2379720D01*
X1422159Y2380000D01*
Y2382520D01*
G01X1429659Y2386193D02*
X1422159D01*
X1428409Y2388620D01*
X1422159Y2391047D01*
X1429659D01*
G01Y2393693D02*
X1422159D01*
X1428409Y2396120D01*
X1422159Y2398547D01*
X1429659D01*
G01Y2409347D02*
X1422159D01*
Y2412893D01*
G01X1425784Y2411587D02*
Y2409347D01*
G01X1422159Y2417500D02*
Y2419740D01*
G01Y2418620D02*
X1429659D01*
G01Y2417500D02*
Y2419740D01*
G01Y2423973D02*
X1422159D01*
X1429659Y2428267D01*
X1422159D01*
G01Y2432500D02*
Y2434740D01*
G01Y2433620D02*
X1429659D01*
G01Y2432500D02*
Y2434740D01*
G01X1428659Y2439160D02*
X1429284Y2439907D01*
X1429659Y2440747D01*
Y2441493D01*
X1429284Y2442240D01*
X1428659Y2442800D01*
X1427784Y2443080D01*
X1426909Y2442893D01*
X1426159Y2442427D01*
X1425659Y2441587D01*
X1425409Y2440467D01*
X1424909Y2439813D01*
X1424034Y2439533D01*
X1423159Y2439720D01*
X1422534Y2440187D01*
X1422159Y2440840D01*
Y2441493D01*
X1422409Y2442147D01*
X1423034Y2442707D01*
G01X1429659Y2446660D02*
X1422159D01*
G01Y2450580D02*
X1429659D01*
G01X1425909D02*
Y2446660D01*
G01X1429659Y2457987D02*
Y2454253D01*
X1422159D01*
Y2457987D01*
G01X1425784Y2456493D02*
Y2454253D01*
G01X1429659Y2461567D02*
X1422159D01*
Y2463433D01*
X1422534Y2464180D01*
X1423034Y2464740D01*
X1423784Y2465207D01*
X1424659Y2465580D01*
X1425909Y2465673D01*
X1427159Y2465580D01*
X1428034Y2465207D01*
X1428784Y2464740D01*
X1429284Y2464180D01*
X1429659Y2463433D01*
Y2461567D01*
G01Y2476753D02*
X1422159D01*
Y2478993D01*
X1422534Y2479740D01*
X1423409Y2480300D01*
X1424409Y2480487D01*
X1425409Y2480300D01*
X1426159Y2479833D01*
X1426534Y2478993D01*
Y2476753D01*
G01X1422159Y2486120D02*
X1429659D01*
G01X1422159Y2483973D02*
Y2488267D01*
G01X1429659Y2491660D02*
X1422159D01*
G01Y2495580D02*
X1429659D01*
G01X1425909D02*
Y2491660D01*
G01X1422159Y2507500D02*
Y2509740D01*
G01Y2508620D02*
X1429659D01*
G01Y2507500D02*
Y2509740D01*
G01X1428659Y2514160D02*
X1429284Y2514907D01*
X1429659Y2515747D01*
Y2516493D01*
X1429284Y2517240D01*
X1428659Y2517800D01*
X1427784Y2518080D01*
X1426909Y2517893D01*
X1426159Y2517427D01*
X1425659Y2516587D01*
X1425409Y2515467D01*
X1424909Y2514813D01*
X1424034Y2514533D01*
X1423159Y2514720D01*
X1422534Y2515187D01*
X1422159Y2515840D01*
Y2516493D01*
X1422409Y2517147D01*
X1423034Y2517707D01*
G01X1422159Y2531120D02*
X1422409Y2530373D01*
X1423034Y2529813D01*
X1423784Y2529440D01*
X1424784Y2529160D01*
X1425909Y2529067D01*
X1427034Y2529160D01*
X1428034Y2529440D01*
X1428784Y2529813D01*
X1429409Y2530373D01*
X1429659Y2531120D01*
X1429409Y2531867D01*
X1428784Y2532427D01*
X1428034Y2532800D01*
X1427034Y2533080D01*
X1425909Y2533173D01*
X1424784Y2533080D01*
X1423784Y2532800D01*
X1423034Y2532427D01*
X1422409Y2531867D01*
X1422159Y2531120D01*
G01X1429909Y2538620D02*
X1429784Y2538433D01*
X1429534D01*
X1429409Y2538620D01*
X1429534Y2538807D01*
X1429784D01*
X1429909Y2538620D01*
G01X1426534Y2544347D02*
X1425659Y2545000D01*
X1425159Y2545560D01*
X1424909Y2546307D01*
X1425159Y2546960D01*
X1425659Y2547427D01*
X1426409Y2547800D01*
X1427284Y2547893D01*
X1428034Y2547800D01*
X1428784Y2547427D01*
X1429409Y2546867D01*
X1429659Y2546213D01*
X1429409Y2545467D01*
X1428659Y2544813D01*
X1427534Y2544440D01*
X1426284Y2544347D01*
X1424659Y2544533D01*
X1423784Y2544813D01*
X1422909Y2545280D01*
X1422284Y2545933D01*
X1422159Y2546587D01*
X1422409Y2547240D01*
X1423034Y2547707D01*
G01X1429659Y2551193D02*
X1422159D01*
X1428409Y2553620D01*
X1422159Y2556047D01*
X1429659D01*
G01Y2558693D02*
X1422159D01*
X1428409Y2561120D01*
X1422159Y2563547D01*
X1429659D01*
G01Y2573693D02*
X1422159D01*
X1428409Y2576120D01*
X1422159Y2578547D01*
X1429659D01*
G01Y2585487D02*
Y2581753D01*
X1422159D01*
Y2585487D01*
G01X1425784Y2583993D02*
Y2581753D01*
G01X1422159Y2591120D02*
X1429659D01*
G01X1422159Y2588973D02*
Y2593267D01*
G01X1429659Y2596753D02*
X1422159D01*
Y2599087D01*
X1422534Y2599833D01*
X1423034Y2600300D01*
X1424034Y2600487D01*
X1425034Y2600300D01*
X1425659Y2599740D01*
X1426034Y2599087D01*
Y2596753D01*
G01Y2599087D02*
X1429659Y2600487D01*
G01X1422159Y2605000D02*
Y2607240D01*
G01Y2606120D02*
X1429659D01*
G01Y2605000D02*
Y2607240D01*
G01X1422784Y2615673D02*
X1422409Y2615113D01*
X1422159Y2614460D01*
Y2613713D01*
X1422534Y2612873D01*
X1423159Y2612220D01*
X1423909Y2611753D01*
X1425159Y2611380D01*
X1426284Y2611287D01*
X1427409Y2611473D01*
X1428159Y2611753D01*
X1428909Y2612313D01*
X1429409Y2612967D01*
X1429659Y2613620D01*
Y2614273D01*
X1429409Y2614927D01*
X1429034Y2615487D01*
X1428534Y2615953D01*
G01X1429659Y2626567D02*
X1422159D01*
Y2628433D01*
X1422534Y2629180D01*
X1423034Y2629740D01*
X1423784Y2630207D01*
X1424659Y2630580D01*
X1425909Y2630673D01*
X1427159Y2630580D01*
X1428034Y2630207D01*
X1428784Y2629740D01*
X1429284Y2629180D01*
X1429659Y2628433D01*
Y2626567D01*
G01Y2634253D02*
X1422159D01*
Y2636587D01*
X1422534Y2637333D01*
X1423034Y2637800D01*
X1424034Y2637987D01*
X1425034Y2637800D01*
X1425659Y2637240D01*
X1426034Y2636587D01*
Y2634253D01*
G01Y2636587D02*
X1429659Y2637987D01*
G01X1422159Y2642500D02*
Y2644740D01*
G01Y2643620D02*
X1429659D01*
G01Y2642500D02*
Y2644740D01*
G01X1422159Y2649253D02*
X1429659D01*
Y2652987D01*
G01X1422159Y2656753D02*
X1429659D01*
Y2660487D01*
G01X1432159Y2665653D02*
X1430909Y2664720D01*
X1429659Y2664253D01*
X1424659D01*
X1423409Y2664720D01*
X1422159Y2665653D01*
G01Y2673620D02*
X1422409Y2672873D01*
X1423034Y2672313D01*
X1423784Y2671940D01*
X1424784Y2671660D01*
X1425909Y2671567D01*
X1427034Y2671660D01*
X1428034Y2671940D01*
X1428784Y2672313D01*
X1429409Y2672873D01*
X1429659Y2673620D01*
X1429409Y2674367D01*
X1428784Y2674927D01*
X1428034Y2675300D01*
X1427034Y2675580D01*
X1425909Y2675673D01*
X1424784Y2675580D01*
X1423784Y2675300D01*
X1423034Y2674927D01*
X1422409Y2674367D01*
X1422159Y2673620D01*
G01X1429909Y2681120D02*
X1429784Y2680933D01*
X1429534D01*
X1429409Y2681120D01*
X1429534Y2681307D01*
X1429784D01*
X1429909Y2681120D01*
G01X1422159Y2688620D02*
X1422409Y2687873D01*
X1423034Y2687313D01*
X1423784Y2686940D01*
X1424784Y2686660D01*
X1425909Y2686567D01*
X1427034Y2686660D01*
X1428034Y2686940D01*
X1428784Y2687313D01*
X1429409Y2687873D01*
X1429659Y2688620D01*
X1429409Y2689367D01*
X1428784Y2689927D01*
X1428034Y2690300D01*
X1427034Y2690580D01*
X1425909Y2690673D01*
X1424784Y2690580D01*
X1423784Y2690300D01*
X1423034Y2689927D01*
X1422409Y2689367D01*
X1422159Y2688620D01*
G01X1423409Y2694347D02*
X1422659Y2694907D01*
X1422284Y2695560D01*
X1422159Y2696307D01*
X1422409Y2697240D01*
X1423034Y2697893D01*
X1423784Y2698080D01*
X1424534Y2697987D01*
X1425159Y2697613D01*
X1426409Y2695747D01*
X1427284Y2694907D01*
X1428534Y2694347D01*
X1429659Y2694160D01*
Y2698080D01*
G01X1428159Y2701567D02*
X1429034Y2702127D01*
X1429534Y2702873D01*
X1429659Y2703713D01*
X1429534Y2704460D01*
X1428909Y2705207D01*
X1428159Y2705673D01*
X1427409Y2705767D01*
X1426534Y2705580D01*
X1425909Y2704927D01*
X1425659Y2704273D01*
Y2703433D01*
G01Y2704273D02*
X1425284Y2704833D01*
X1424659Y2705300D01*
X1423909Y2705487D01*
X1423159Y2705300D01*
X1422534Y2704833D01*
X1422159Y2703993D01*
X1422284Y2703153D01*
X1422784Y2702313D01*
G01X1426534Y2709347D02*
X1425659Y2710000D01*
X1425159Y2710560D01*
X1424909Y2711307D01*
X1425159Y2711960D01*
X1425659Y2712427D01*
X1426409Y2712800D01*
X1427284Y2712893D01*
X1428034Y2712800D01*
X1428784Y2712427D01*
X1429409Y2711867D01*
X1429659Y2711213D01*
X1429409Y2710467D01*
X1428659Y2709813D01*
X1427534Y2709440D01*
X1426284Y2709347D01*
X1424659Y2709533D01*
X1423784Y2709813D01*
X1422909Y2710280D01*
X1422284Y2710933D01*
X1422159Y2711587D01*
X1422409Y2712240D01*
X1423034Y2712707D01*
G01X1423784Y2717780D02*
X1422159Y2718247D01*
G01Y2719460D02*
X1423784Y2718993D01*
G01X1432159Y2726587D02*
X1430909Y2727520D01*
X1429659Y2727987D01*
X1424659D01*
X1423409Y2727520D01*
X1422159Y2726587D01*
G01X1429909Y2733620D02*
X1429784Y2733433D01*
X1429534D01*
X1429409Y2733620D01*
X1429534Y2733807D01*
X1429784D01*
X1429909Y2733620D01*
G01X1446110Y-415620D02*
X1433610D01*
X1436110Y-417480D01*
G01X1446110D02*
Y-413760D01*
G01Y-401360D02*
X1433610D01*
X1442568Y-407095D01*
Y-399345D01*
G01X1446110Y-390820D02*
X1433610D01*
X1436110Y-392680D01*
G01X1446110D02*
Y-388960D01*
G01X1440902Y-381365D02*
X1439443Y-380280D01*
X1438610Y-379350D01*
X1438193Y-378110D01*
X1438610Y-377025D01*
X1439443Y-376250D01*
X1440693Y-375630D01*
X1442152Y-375475D01*
X1443402Y-375630D01*
X1444652Y-376250D01*
X1445693Y-377180D01*
X1446110Y-378265D01*
X1445693Y-379505D01*
X1444444Y-380590D01*
X1442568Y-381210D01*
X1440485Y-381365D01*
X1437777Y-381055D01*
X1436318Y-380590D01*
X1434860Y-379815D01*
X1433818Y-378730D01*
X1433610Y-377645D01*
X1434027Y-376560D01*
X1435068Y-375785D01*
G01X1446110Y-364160D02*
X1433610D01*
X1442568Y-369895D01*
Y-362145D01*
G01X1446527Y-353620D02*
X1446318Y-353930D01*
X1445902D01*
X1445693Y-353620D01*
X1445902Y-353310D01*
X1446318D01*
X1446527Y-353620D01*
G01X1443610Y-344630D02*
X1445069Y-343700D01*
X1445902Y-342460D01*
X1446110Y-341065D01*
X1445902Y-339825D01*
X1444860Y-338585D01*
X1443610Y-337810D01*
X1442360Y-337655D01*
X1440902Y-337965D01*
X1439860Y-339050D01*
X1439443Y-340135D01*
Y-341530D01*
G01Y-340135D02*
X1438818Y-339205D01*
X1437777Y-338430D01*
X1436527Y-338120D01*
X1435277Y-338430D01*
X1434235Y-339205D01*
X1433610Y-340600D01*
X1433818Y-341995D01*
X1434652Y-343390D01*
G01X1446110Y-329130D02*
X1443402Y-328820D01*
X1441110Y-328355D01*
X1439027Y-327735D01*
X1436735Y-326960D01*
X1433610Y-325720D01*
Y-331920D01*
G01X1443610Y-297630D02*
X1445069Y-296700D01*
X1445902Y-295460D01*
X1446110Y-294065D01*
X1445902Y-292825D01*
X1444860Y-291585D01*
X1443610Y-290810D01*
X1442360Y-290655D01*
X1440902Y-290965D01*
X1439860Y-292050D01*
X1439443Y-293135D01*
Y-294530D01*
G01Y-293135D02*
X1438818Y-292205D01*
X1437777Y-291430D01*
X1436527Y-291120D01*
X1435277Y-291430D01*
X1434235Y-292205D01*
X1433610Y-293600D01*
X1433818Y-294995D01*
X1434652Y-296390D01*
G01X1444235Y-285230D02*
X1445277Y-284300D01*
X1445902Y-283215D01*
X1446110Y-281820D01*
X1445693Y-280425D01*
X1444860Y-279340D01*
X1443402Y-278565D01*
X1441735Y-278410D01*
X1440068Y-278720D01*
X1439027Y-279495D01*
X1438193Y-280580D01*
X1437985Y-281665D01*
X1438193Y-282750D01*
X1439027Y-284145D01*
X1433610Y-283680D01*
Y-279495D01*
G01X1444652Y-272055D02*
X1445693Y-270970D01*
X1446110Y-269730D01*
X1445693Y-268490D01*
X1444444Y-267405D01*
X1442568Y-266630D01*
X1440693Y-266320D01*
X1438402D01*
X1436527Y-266630D01*
X1434860Y-267405D01*
X1434027Y-268335D01*
X1433610Y-269420D01*
X1434027Y-270660D01*
X1434860Y-271590D01*
X1436110Y-272210D01*
X1437777Y-272520D01*
X1439235Y-272210D01*
X1440693Y-271435D01*
X1441527Y-270505D01*
X1441735Y-269420D01*
X1441319Y-268180D01*
X1440277Y-267250D01*
X1438402Y-266320D01*
G01X1446527Y-257020D02*
X1446318Y-257330D01*
X1445902D01*
X1445693Y-257020D01*
X1445902Y-256710D01*
X1446318D01*
X1446527Y-257020D01*
G01X1446110Y-244930D02*
X1443402Y-244620D01*
X1441110Y-244155D01*
X1439027Y-243535D01*
X1436735Y-242760D01*
X1433610Y-241520D01*
Y-247720D01*
G01X1446110Y-232530D02*
X1443402Y-232220D01*
X1441110Y-231755D01*
X1439027Y-231135D01*
X1436735Y-230360D01*
X1433610Y-229120D01*
Y-235320D01*
G01X1441559Y1966660D02*
X1442184Y1967407D01*
X1442559Y1968247D01*
Y1968993D01*
X1442184Y1969740D01*
X1441559Y1970300D01*
X1440684Y1970580D01*
X1439809Y1970393D01*
X1439059Y1969927D01*
X1438559Y1969087D01*
X1438309Y1967967D01*
X1437809Y1967313D01*
X1436934Y1967033D01*
X1436059Y1967220D01*
X1435434Y1967687D01*
X1435059Y1968340D01*
Y1968993D01*
X1435309Y1969647D01*
X1435934Y1970207D01*
G01X1435059Y1975000D02*
Y1977240D01*
G01Y1976120D02*
X1442559D01*
G01Y1975000D02*
Y1977240D01*
G01X1435059Y1981753D02*
X1442559D01*
Y1985487D01*
G01X1435059Y1988787D02*
X1442559Y1991120D01*
X1435059Y1993453D01*
G01X1442559Y2000487D02*
Y1996753D01*
X1435059D01*
Y2000487D01*
G01X1438684Y1998993D02*
Y1996753D01*
G01X1442559Y2004253D02*
X1435059D01*
Y2006587D01*
X1435434Y2007333D01*
X1435934Y2007800D01*
X1436934Y2007987D01*
X1437934Y2007800D01*
X1438559Y2007240D01*
X1438934Y2006587D01*
Y2004253D01*
G01Y2006587D02*
X1442559Y2007987D01*
G01X1445059Y2013153D02*
X1443809Y2012220D01*
X1442559Y2011753D01*
X1437559D01*
X1436309Y2012220D01*
X1435059Y2013153D01*
G01Y2020000D02*
Y2022240D01*
G01Y2021120D02*
X1442559D01*
G01Y2020000D02*
Y2022240D01*
G01Y2026193D02*
X1435059D01*
X1441309Y2028620D01*
X1435059Y2031047D01*
X1442559D01*
G01Y2033693D02*
X1435059D01*
X1441309Y2036120D01*
X1435059Y2038547D01*
X1442559D01*
G01Y2045487D02*
Y2041753D01*
X1435059D01*
Y2045487D01*
G01X1438684Y2043993D02*
Y2041753D01*
G01X1442559Y2049253D02*
X1435059D01*
Y2051587D01*
X1435434Y2052333D01*
X1435934Y2052800D01*
X1436934Y2052987D01*
X1437934Y2052800D01*
X1438559Y2052240D01*
X1438934Y2051587D01*
Y2049253D01*
G01Y2051587D02*
X1442559Y2052987D01*
G01X1441559Y2056660D02*
X1442184Y2057407D01*
X1442559Y2058247D01*
Y2058993D01*
X1442184Y2059740D01*
X1441559Y2060300D01*
X1440684Y2060580D01*
X1439809Y2060393D01*
X1439059Y2059927D01*
X1438559Y2059087D01*
X1438309Y2057967D01*
X1437809Y2057313D01*
X1436934Y2057033D01*
X1436059Y2057220D01*
X1435434Y2057687D01*
X1435059Y2058340D01*
Y2058993D01*
X1435309Y2059647D01*
X1435934Y2060207D01*
G01X1435059Y2065000D02*
Y2067240D01*
G01Y2066120D02*
X1442559D01*
G01Y2065000D02*
Y2067240D01*
G01Y2073620D02*
X1442434Y2072873D01*
X1441934Y2072220D01*
X1441184Y2071660D01*
X1440309Y2071287D01*
X1439309Y2071100D01*
X1438309D01*
X1437309Y2071287D01*
X1436434Y2071660D01*
X1435684Y2072220D01*
X1435184Y2072873D01*
X1435059Y2073620D01*
X1435184Y2074367D01*
X1435684Y2075020D01*
X1436434Y2075580D01*
X1437309Y2075953D01*
X1438309Y2076140D01*
X1439309D01*
X1440309Y2075953D01*
X1441184Y2075580D01*
X1441934Y2075020D01*
X1442434Y2074367D01*
X1442559Y2073620D01*
G01Y2078973D02*
X1435059D01*
X1442559Y2083267D01*
X1435059D01*
G01X1445059Y2089087D02*
X1443809Y2090020D01*
X1442559Y2090487D01*
X1437559D01*
X1436309Y2090020D01*
X1435059Y2089087D01*
G01X1442809Y2096120D02*
X1442684Y2095933D01*
X1442434D01*
X1442309Y2096120D01*
X1442434Y2096307D01*
X1442684D01*
X1442809Y2096120D01*
G01X1439434D02*
X1439309Y2095933D01*
X1439059D01*
X1438934Y2096120D01*
X1439059Y2096307D01*
X1439309D01*
X1439434Y2096120D01*
G01X1442559Y2101753D02*
X1435059D01*
Y2104087D01*
X1435434Y2104833D01*
X1435934Y2105300D01*
X1436934Y2105487D01*
X1437934Y2105300D01*
X1438559Y2104740D01*
X1438934Y2104087D01*
Y2101753D01*
G01Y2104087D02*
X1442559Y2105487D01*
G01Y2112987D02*
Y2109253D01*
X1435059D01*
Y2112987D01*
G01X1438684Y2111493D02*
Y2109253D01*
G01X1435684Y2120673D02*
X1435309Y2120113D01*
X1435059Y2119460D01*
Y2118713D01*
X1435434Y2117873D01*
X1436059Y2117220D01*
X1436809Y2116753D01*
X1438059Y2116380D01*
X1439184Y2116287D01*
X1440309Y2116473D01*
X1441059Y2116753D01*
X1441809Y2117313D01*
X1442309Y2117967D01*
X1442559Y2118620D01*
Y2119273D01*
X1442309Y2119927D01*
X1441934Y2120487D01*
X1441434Y2120953D01*
G01X1442559Y2126120D02*
X1442434Y2125373D01*
X1441934Y2124720D01*
X1441184Y2124160D01*
X1440309Y2123787D01*
X1439309Y2123600D01*
X1438309D01*
X1437309Y2123787D01*
X1436434Y2124160D01*
X1435684Y2124720D01*
X1435184Y2125373D01*
X1435059Y2126120D01*
X1435184Y2126867D01*
X1435684Y2127520D01*
X1436434Y2128080D01*
X1437309Y2128453D01*
X1438309Y2128640D01*
X1439309D01*
X1440309Y2128453D01*
X1441184Y2128080D01*
X1441934Y2127520D01*
X1442434Y2126867D01*
X1442559Y2126120D01*
G01Y2131193D02*
X1435059D01*
X1441309Y2133620D01*
X1435059Y2136047D01*
X1442559D01*
G01Y2138693D02*
X1435059D01*
X1441309Y2141120D01*
X1435059Y2143547D01*
X1442559D01*
G01Y2150487D02*
Y2146753D01*
X1435059D01*
Y2150487D01*
G01X1438684Y2148993D02*
Y2146753D01*
G01X1442559Y2153973D02*
X1435059D01*
X1442559Y2158267D01*
X1435059D01*
G01X1442559Y2161567D02*
X1435059D01*
Y2163433D01*
X1435434Y2164180D01*
X1435934Y2164740D01*
X1436684Y2165207D01*
X1437559Y2165580D01*
X1438809Y2165673D01*
X1440059Y2165580D01*
X1440934Y2165207D01*
X1441684Y2164740D01*
X1442184Y2164180D01*
X1442559Y2163433D01*
Y2161567D01*
G01Y2172987D02*
Y2169253D01*
X1435059D01*
Y2172987D01*
G01X1438684Y2171493D02*
Y2169253D01*
G01X1442559Y2176567D02*
X1435059D01*
Y2178433D01*
X1435434Y2179180D01*
X1435934Y2179740D01*
X1436684Y2180207D01*
X1437559Y2180580D01*
X1438809Y2180673D01*
X1440059Y2180580D01*
X1440934Y2180207D01*
X1441684Y2179740D01*
X1442184Y2179180D01*
X1442559Y2178433D01*
Y2176567D01*
G01Y2191567D02*
X1435059D01*
Y2193433D01*
X1435434Y2194180D01*
X1435934Y2194740D01*
X1436684Y2195207D01*
X1437559Y2195580D01*
X1438809Y2195673D01*
X1440059Y2195580D01*
X1440934Y2195207D01*
X1441684Y2194740D01*
X1442184Y2194180D01*
X1442559Y2193433D01*
Y2191567D01*
G01Y2199253D02*
X1435059D01*
Y2201587D01*
X1435434Y2202333D01*
X1435934Y2202800D01*
X1436934Y2202987D01*
X1437934Y2202800D01*
X1438559Y2202240D01*
X1438934Y2201587D01*
Y2199253D01*
G01Y2201587D02*
X1442559Y2202987D01*
G01X1435059Y2207500D02*
Y2209740D01*
G01Y2208620D02*
X1442559D01*
G01Y2207500D02*
Y2209740D01*
G01X1435059Y2214253D02*
X1442559D01*
Y2217987D01*
G01X1435059Y2221753D02*
X1442559D01*
Y2225487D01*
G01X1441559Y2236660D02*
X1442184Y2237407D01*
X1442559Y2238247D01*
Y2238993D01*
X1442184Y2239740D01*
X1441559Y2240300D01*
X1440684Y2240580D01*
X1439809Y2240393D01*
X1439059Y2239927D01*
X1438559Y2239087D01*
X1438309Y2237967D01*
X1437809Y2237313D01*
X1436934Y2237033D01*
X1436059Y2237220D01*
X1435434Y2237687D01*
X1435059Y2238340D01*
Y2238993D01*
X1435309Y2239647D01*
X1435934Y2240207D01*
G01X1435059Y2245000D02*
Y2247240D01*
G01Y2246120D02*
X1442559D01*
G01Y2245000D02*
Y2247240D01*
G01X1435059Y2251847D02*
Y2255393D01*
X1442559Y2251847D01*
Y2255393D01*
G01Y2262987D02*
Y2259253D01*
X1435059D01*
Y2262987D01*
G01X1438684Y2261493D02*
Y2259253D01*
G01X1442559Y2274347D02*
X1435059D01*
Y2277893D01*
G01X1438684Y2276587D02*
Y2274347D01*
G01X1442559Y2283620D02*
X1442434Y2282873D01*
X1441934Y2282220D01*
X1441184Y2281660D01*
X1440309Y2281287D01*
X1439309Y2281100D01*
X1438309D01*
X1437309Y2281287D01*
X1436434Y2281660D01*
X1435684Y2282220D01*
X1435184Y2282873D01*
X1435059Y2283620D01*
X1435184Y2284367D01*
X1435684Y2285020D01*
X1436434Y2285580D01*
X1437309Y2285953D01*
X1438309Y2286140D01*
X1439309D01*
X1440309Y2285953D01*
X1441184Y2285580D01*
X1441934Y2285020D01*
X1442434Y2284367D01*
X1442559Y2283620D01*
G01Y2289253D02*
X1435059D01*
Y2291587D01*
X1435434Y2292333D01*
X1435934Y2292800D01*
X1436934Y2292987D01*
X1437934Y2292800D01*
X1438559Y2292240D01*
X1438934Y2291587D01*
Y2289253D01*
G01Y2291587D02*
X1442559Y2292987D01*
G01X1435059Y2306120D02*
X1435309Y2305373D01*
X1435934Y2304813D01*
X1436684Y2304440D01*
X1437684Y2304160D01*
X1438809Y2304067D01*
X1439934Y2304160D01*
X1440934Y2304440D01*
X1441684Y2304813D01*
X1442309Y2305373D01*
X1442559Y2306120D01*
X1442309Y2306867D01*
X1441684Y2307427D01*
X1440934Y2307800D01*
X1439934Y2308080D01*
X1438809Y2308173D01*
X1437684Y2308080D01*
X1436684Y2307800D01*
X1435934Y2307427D01*
X1435309Y2306867D01*
X1435059Y2306120D01*
G01X1442809Y2313620D02*
X1442684Y2313433D01*
X1442434D01*
X1442309Y2313620D01*
X1442434Y2313807D01*
X1442684D01*
X1442809Y2313620D01*
G01X1441434Y2319067D02*
X1442059Y2319627D01*
X1442434Y2320280D01*
X1442559Y2321120D01*
X1442309Y2321960D01*
X1441809Y2322613D01*
X1440934Y2323080D01*
X1439934Y2323173D01*
X1438934Y2322987D01*
X1438309Y2322520D01*
X1437809Y2321867D01*
X1437684Y2321213D01*
X1437809Y2320560D01*
X1438309Y2319720D01*
X1435059Y2320000D01*
Y2322520D01*
G01X1442559Y2326193D02*
X1435059D01*
X1441309Y2328620D01*
X1435059Y2331047D01*
X1442559D01*
G01Y2333693D02*
X1435059D01*
X1441309Y2336120D01*
X1435059Y2338547D01*
X1442559D01*
G01Y2349347D02*
X1435059D01*
Y2352893D01*
G01X1438684Y2351587D02*
Y2349347D01*
G01X1435059Y2357500D02*
Y2359740D01*
G01Y2358620D02*
X1442559D01*
G01Y2357500D02*
Y2359740D01*
G01Y2363973D02*
X1435059D01*
X1442559Y2368267D01*
X1435059D01*
G01Y2372500D02*
Y2374740D01*
G01Y2373620D02*
X1442559D01*
G01Y2372500D02*
Y2374740D01*
G01X1441559Y2379160D02*
X1442184Y2379907D01*
X1442559Y2380747D01*
Y2381493D01*
X1442184Y2382240D01*
X1441559Y2382800D01*
X1440684Y2383080D01*
X1439809Y2382893D01*
X1439059Y2382427D01*
X1438559Y2381587D01*
X1438309Y2380467D01*
X1437809Y2379813D01*
X1436934Y2379533D01*
X1436059Y2379720D01*
X1435434Y2380187D01*
X1435059Y2380840D01*
Y2381493D01*
X1435309Y2382147D01*
X1435934Y2382707D01*
G01X1442559Y2386660D02*
X1435059D01*
G01Y2390580D02*
X1442559D01*
G01X1438809D02*
Y2386660D01*
G01X1442559Y2397987D02*
Y2394253D01*
X1435059D01*
Y2397987D01*
G01X1438684Y2396493D02*
Y2394253D01*
G01X1442559Y2401567D02*
X1435059D01*
Y2403433D01*
X1435434Y2404180D01*
X1435934Y2404740D01*
X1436684Y2405207D01*
X1437559Y2405580D01*
X1438809Y2405673D01*
X1440059Y2405580D01*
X1440934Y2405207D01*
X1441684Y2404740D01*
X1442184Y2404180D01*
X1442559Y2403433D01*
Y2401567D01*
G01Y2416753D02*
X1435059D01*
Y2418993D01*
X1435434Y2419740D01*
X1436309Y2420300D01*
X1437309Y2420487D01*
X1438309Y2420300D01*
X1439059Y2419833D01*
X1439434Y2418993D01*
Y2416753D01*
G01X1435059Y2426120D02*
X1442559D01*
G01X1435059Y2423973D02*
Y2428267D01*
G01X1442559Y2431660D02*
X1435059D01*
G01Y2435580D02*
X1442559D01*
G01X1438809D02*
Y2431660D01*
G01X1435059Y2447500D02*
Y2449740D01*
G01Y2448620D02*
X1442559D01*
G01Y2447500D02*
Y2449740D01*
G01X1441559Y2454160D02*
X1442184Y2454907D01*
X1442559Y2455747D01*
Y2456493D01*
X1442184Y2457240D01*
X1441559Y2457800D01*
X1440684Y2458080D01*
X1439809Y2457893D01*
X1439059Y2457427D01*
X1438559Y2456587D01*
X1438309Y2455467D01*
X1437809Y2454813D01*
X1436934Y2454533D01*
X1436059Y2454720D01*
X1435434Y2455187D01*
X1435059Y2455840D01*
Y2456493D01*
X1435309Y2457147D01*
X1435934Y2457707D01*
G01X1435059Y2471120D02*
X1435309Y2470373D01*
X1435934Y2469813D01*
X1436684Y2469440D01*
X1437684Y2469160D01*
X1438809Y2469067D01*
X1439934Y2469160D01*
X1440934Y2469440D01*
X1441684Y2469813D01*
X1442309Y2470373D01*
X1442559Y2471120D01*
X1442309Y2471867D01*
X1441684Y2472427D01*
X1440934Y2472800D01*
X1439934Y2473080D01*
X1438809Y2473173D01*
X1437684Y2473080D01*
X1436684Y2472800D01*
X1435934Y2472427D01*
X1435309Y2471867D01*
X1435059Y2471120D01*
G01X1442809Y2478620D02*
X1442684Y2478433D01*
X1442434D01*
X1442309Y2478620D01*
X1442434Y2478807D01*
X1442684D01*
X1442809Y2478620D01*
G01X1439434Y2484347D02*
X1438559Y2485000D01*
X1438059Y2485560D01*
X1437809Y2486307D01*
X1438059Y2486960D01*
X1438559Y2487427D01*
X1439309Y2487800D01*
X1440184Y2487893D01*
X1440934Y2487800D01*
X1441684Y2487427D01*
X1442309Y2486867D01*
X1442559Y2486213D01*
X1442309Y2485467D01*
X1441559Y2484813D01*
X1440434Y2484440D01*
X1439184Y2484347D01*
X1437559Y2484533D01*
X1436684Y2484813D01*
X1435809Y2485280D01*
X1435184Y2485933D01*
X1435059Y2486587D01*
X1435309Y2487240D01*
X1435934Y2487707D01*
G01X1442559Y2491193D02*
X1435059D01*
X1441309Y2493620D01*
X1435059Y2496047D01*
X1442559D01*
G01Y2498693D02*
X1435059D01*
X1441309Y2501120D01*
X1435059Y2503547D01*
X1442559D01*
G01Y2513693D02*
X1435059D01*
X1441309Y2516120D01*
X1435059Y2518547D01*
X1442559D01*
G01Y2525487D02*
Y2521753D01*
X1435059D01*
Y2525487D01*
G01X1438684Y2523993D02*
Y2521753D01*
G01X1435059Y2531120D02*
X1442559D01*
G01X1435059Y2528973D02*
Y2533267D01*
G01X1442559Y2536753D02*
X1435059D01*
Y2539087D01*
X1435434Y2539833D01*
X1435934Y2540300D01*
X1436934Y2540487D01*
X1437934Y2540300D01*
X1438559Y2539740D01*
X1438934Y2539087D01*
Y2536753D01*
G01Y2539087D02*
X1442559Y2540487D01*
G01X1435059Y2545000D02*
Y2547240D01*
G01Y2546120D02*
X1442559D01*
G01Y2545000D02*
Y2547240D01*
G01X1435684Y2555673D02*
X1435309Y2555113D01*
X1435059Y2554460D01*
Y2553713D01*
X1435434Y2552873D01*
X1436059Y2552220D01*
X1436809Y2551753D01*
X1438059Y2551380D01*
X1439184Y2551287D01*
X1440309Y2551473D01*
X1441059Y2551753D01*
X1441809Y2552313D01*
X1442309Y2552967D01*
X1442559Y2553620D01*
Y2554273D01*
X1442309Y2554927D01*
X1441934Y2555487D01*
X1441434Y2555953D01*
G01X1442559Y2566567D02*
X1435059D01*
Y2568433D01*
X1435434Y2569180D01*
X1435934Y2569740D01*
X1436684Y2570207D01*
X1437559Y2570580D01*
X1438809Y2570673D01*
X1440059Y2570580D01*
X1440934Y2570207D01*
X1441684Y2569740D01*
X1442184Y2569180D01*
X1442559Y2568433D01*
Y2566567D01*
G01Y2574253D02*
X1435059D01*
Y2576587D01*
X1435434Y2577333D01*
X1435934Y2577800D01*
X1436934Y2577987D01*
X1437934Y2577800D01*
X1438559Y2577240D01*
X1438934Y2576587D01*
Y2574253D01*
G01Y2576587D02*
X1442559Y2577987D01*
G01X1435059Y2582500D02*
Y2584740D01*
G01Y2583620D02*
X1442559D01*
G01Y2582500D02*
Y2584740D01*
G01X1435059Y2589253D02*
X1442559D01*
Y2592987D01*
G01X1435059Y2596753D02*
X1442559D01*
Y2600487D01*
G01X1445059Y2605653D02*
X1443809Y2604720D01*
X1442559Y2604253D01*
X1437559D01*
X1436309Y2604720D01*
X1435059Y2605653D01*
G01Y2613620D02*
X1435309Y2612873D01*
X1435934Y2612313D01*
X1436684Y2611940D01*
X1437684Y2611660D01*
X1438809Y2611567D01*
X1439934Y2611660D01*
X1440934Y2611940D01*
X1441684Y2612313D01*
X1442309Y2612873D01*
X1442559Y2613620D01*
X1442309Y2614367D01*
X1441684Y2614927D01*
X1440934Y2615300D01*
X1439934Y2615580D01*
X1438809Y2615673D01*
X1437684Y2615580D01*
X1436684Y2615300D01*
X1435934Y2614927D01*
X1435309Y2614367D01*
X1435059Y2613620D01*
G01X1442809Y2621120D02*
X1442684Y2620933D01*
X1442434D01*
X1442309Y2621120D01*
X1442434Y2621307D01*
X1442684D01*
X1442809Y2621120D01*
G01X1435059Y2628620D02*
X1435309Y2627873D01*
X1435934Y2627313D01*
X1436684Y2626940D01*
X1437684Y2626660D01*
X1438809Y2626567D01*
X1439934Y2626660D01*
X1440934Y2626940D01*
X1441684Y2627313D01*
X1442309Y2627873D01*
X1442559Y2628620D01*
X1442309Y2629367D01*
X1441684Y2629927D01*
X1440934Y2630300D01*
X1439934Y2630580D01*
X1438809Y2630673D01*
X1437684Y2630580D01*
X1436684Y2630300D01*
X1435934Y2629927D01*
X1435309Y2629367D01*
X1435059Y2628620D01*
G01X1436309Y2634347D02*
X1435559Y2634907D01*
X1435184Y2635560D01*
X1435059Y2636307D01*
X1435309Y2637240D01*
X1435934Y2637893D01*
X1436684Y2638080D01*
X1437434Y2637987D01*
X1438059Y2637613D01*
X1439309Y2635747D01*
X1440184Y2634907D01*
X1441434Y2634347D01*
X1442559Y2634160D01*
Y2638080D01*
G01X1441059Y2641567D02*
X1441934Y2642127D01*
X1442434Y2642873D01*
X1442559Y2643713D01*
X1442434Y2644460D01*
X1441809Y2645207D01*
X1441059Y2645673D01*
X1440309Y2645767D01*
X1439434Y2645580D01*
X1438809Y2644927D01*
X1438559Y2644273D01*
Y2643433D01*
G01Y2644273D02*
X1438184Y2644833D01*
X1437559Y2645300D01*
X1436809Y2645487D01*
X1436059Y2645300D01*
X1435434Y2644833D01*
X1435059Y2643993D01*
X1435184Y2643153D01*
X1435684Y2642313D01*
G01X1439434Y2649347D02*
X1438559Y2650000D01*
X1438059Y2650560D01*
X1437809Y2651307D01*
X1438059Y2651960D01*
X1438559Y2652427D01*
X1439309Y2652800D01*
X1440184Y2652893D01*
X1440934Y2652800D01*
X1441684Y2652427D01*
X1442309Y2651867D01*
X1442559Y2651213D01*
X1442309Y2650467D01*
X1441559Y2649813D01*
X1440434Y2649440D01*
X1439184Y2649347D01*
X1437559Y2649533D01*
X1436684Y2649813D01*
X1435809Y2650280D01*
X1435184Y2650933D01*
X1435059Y2651587D01*
X1435309Y2652240D01*
X1435934Y2652707D01*
G01X1436684Y2657780D02*
X1435059Y2658247D01*
G01Y2659460D02*
X1436684Y2658993D01*
G01X1445059Y2666587D02*
X1443809Y2667520D01*
X1442559Y2667987D01*
X1437559D01*
X1436309Y2667520D01*
X1435059Y2666587D01*
G01X1442809Y2673620D02*
X1442684Y2673433D01*
X1442434D01*
X1442309Y2673620D01*
X1442434Y2673807D01*
X1442684D01*
X1442809Y2673620D01*
G01X1455379Y1928725D02*
X1447879D01*
X1455379Y1933019D01*
X1447879D01*
G01X1455379Y1938372D02*
X1455254Y1937625D01*
X1454754Y1936972D01*
X1454004Y1936412D01*
X1453129Y1936039D01*
X1452129Y1935852D01*
X1451129D01*
X1450129Y1936039D01*
X1449254Y1936412D01*
X1448504Y1936972D01*
X1448004Y1937625D01*
X1447879Y1938372D01*
X1448004Y1939119D01*
X1448504Y1939772D01*
X1449254Y1940332D01*
X1450129Y1940705D01*
X1451129Y1940892D01*
X1452129D01*
X1453129Y1940705D01*
X1454004Y1940332D01*
X1454754Y1939772D01*
X1455254Y1939119D01*
X1455379Y1938372D01*
G01Y1943725D02*
X1447879D01*
X1455379Y1948019D01*
X1447879D01*
G01X1452879Y1952159D02*
Y1954585D01*
G01X1455379Y1958445D02*
X1447879D01*
X1454129Y1960872D01*
X1447879Y1963299D01*
X1455379D01*
G01Y1966039D02*
X1447879Y1968372D01*
X1455379Y1970705D01*
G01X1452754Y1969865D02*
Y1966879D01*
G01X1455379Y1974005D02*
X1447879D01*
Y1976339D01*
X1448254Y1977085D01*
X1448754Y1977552D01*
X1449754Y1977739D01*
X1450754Y1977552D01*
X1451379Y1976992D01*
X1451754Y1976339D01*
Y1974005D01*
G01Y1976339D02*
X1455379Y1977739D01*
G01Y1981319D02*
X1447879D01*
G01Y1984865D02*
X1452504Y1981319D01*
G01X1455379Y1985425D02*
X1450379Y1982905D01*
G01X1455629Y1990872D02*
X1455504Y1990685D01*
X1455254D01*
X1455129Y1990872D01*
X1455254Y1991059D01*
X1455504D01*
X1455629Y1990872D01*
G01X1452254D02*
X1452129Y1990685D01*
X1451879D01*
X1451754Y1990872D01*
X1451879Y1991059D01*
X1452129D01*
X1452254Y1990872D01*
G01X1447879Y1998372D02*
X1455379D01*
G01X1447879Y1996225D02*
Y2000519D01*
G01Y2004752D02*
Y2006992D01*
G01Y2005872D02*
X1455379D01*
G01Y2004752D02*
Y2006992D01*
G01Y2011225D02*
X1447879D01*
X1455379Y2015519D01*
X1447879D01*
G01Y2026505D02*
X1455379D01*
Y2030239D01*
G01Y2037739D02*
Y2034005D01*
X1447879D01*
Y2037739D01*
G01X1451504Y2036245D02*
Y2034005D01*
G01X1455379Y2041039D02*
X1447879Y2043372D01*
X1455379Y2045705D01*
G01X1452754Y2044865D02*
Y2041879D01*
G01X1455379Y2048819D02*
X1447879D01*
Y2050685D01*
X1448254Y2051432D01*
X1448754Y2051992D01*
X1449504Y2052459D01*
X1450379Y2052832D01*
X1451629Y2052925D01*
X1452879Y2052832D01*
X1453754Y2052459D01*
X1454504Y2051992D01*
X1455004Y2051432D01*
X1455379Y2050685D01*
Y2048819D01*
G01X1455629Y2058372D02*
X1455504Y2058185D01*
X1455254D01*
X1455129Y2058372D01*
X1455254Y2058559D01*
X1455504D01*
X1455629Y2058372D01*
G01X1452254D02*
X1452129Y2058185D01*
X1451879D01*
X1451754Y2058372D01*
X1451879Y2058559D01*
X1452129D01*
X1452254Y2058372D01*
G01X1455379Y2064005D02*
X1447879D01*
Y2066339D01*
X1448254Y2067085D01*
X1448754Y2067552D01*
X1449754Y2067739D01*
X1450754Y2067552D01*
X1451379Y2066992D01*
X1451754Y2066339D01*
Y2064005D01*
G01Y2066339D02*
X1455379Y2067739D01*
G01Y2075239D02*
Y2071505D01*
X1447879D01*
Y2075239D01*
G01X1451504Y2073745D02*
Y2071505D01*
G01X1448504Y2082925D02*
X1448129Y2082365D01*
X1447879Y2081712D01*
Y2080965D01*
X1448254Y2080125D01*
X1448879Y2079472D01*
X1449629Y2079005D01*
X1450879Y2078632D01*
X1452004Y2078539D01*
X1453129Y2078725D01*
X1453879Y2079005D01*
X1454629Y2079565D01*
X1455129Y2080219D01*
X1455379Y2080872D01*
Y2081525D01*
X1455129Y2082179D01*
X1454754Y2082739D01*
X1454254Y2083205D01*
G01X1455379Y2088372D02*
X1455254Y2087625D01*
X1454754Y2086972D01*
X1454004Y2086412D01*
X1453129Y2086039D01*
X1452129Y2085852D01*
X1451129D01*
X1450129Y2086039D01*
X1449254Y2086412D01*
X1448504Y2086972D01*
X1448004Y2087625D01*
X1447879Y2088372D01*
X1448004Y2089119D01*
X1448504Y2089772D01*
X1449254Y2090332D01*
X1450129Y2090705D01*
X1451129Y2090892D01*
X1452129D01*
X1453129Y2090705D01*
X1454004Y2090332D01*
X1454754Y2089772D01*
X1455254Y2089119D01*
X1455379Y2088372D01*
G01Y2093445D02*
X1447879D01*
X1454129Y2095872D01*
X1447879Y2098299D01*
X1455379D01*
G01Y2100945D02*
X1447879D01*
X1454129Y2103372D01*
X1447879Y2105799D01*
X1455379D01*
G01Y2112739D02*
Y2109005D01*
X1447879D01*
Y2112739D01*
G01X1451504Y2111245D02*
Y2109005D01*
G01X1455379Y2116225D02*
X1447879D01*
X1455379Y2120519D01*
X1447879D01*
G01X1455379Y2123819D02*
X1447879D01*
Y2125685D01*
X1448254Y2126432D01*
X1448754Y2126992D01*
X1449504Y2127459D01*
X1450379Y2127832D01*
X1451629Y2127925D01*
X1452879Y2127832D01*
X1453754Y2127459D01*
X1454504Y2126992D01*
X1455004Y2126432D01*
X1455379Y2125685D01*
Y2123819D01*
G01Y2135239D02*
Y2131505D01*
X1447879D01*
Y2135239D01*
G01X1451504Y2133745D02*
Y2131505D01*
G01X1455379Y2138819D02*
X1447879D01*
Y2140685D01*
X1448254Y2141432D01*
X1448754Y2141992D01*
X1449504Y2142459D01*
X1450379Y2142832D01*
X1451629Y2142925D01*
X1452879Y2142832D01*
X1453754Y2142459D01*
X1454504Y2141992D01*
X1455004Y2141432D01*
X1455379Y2140685D01*
Y2138819D01*
G01Y2153819D02*
X1447879D01*
Y2155685D01*
X1448254Y2156432D01*
X1448754Y2156992D01*
X1449504Y2157459D01*
X1450379Y2157832D01*
X1451629Y2157925D01*
X1452879Y2157832D01*
X1453754Y2157459D01*
X1454504Y2156992D01*
X1455004Y2156432D01*
X1455379Y2155685D01*
Y2153819D01*
G01Y2161505D02*
X1447879D01*
Y2163839D01*
X1448254Y2164585D01*
X1448754Y2165052D01*
X1449754Y2165239D01*
X1450754Y2165052D01*
X1451379Y2164492D01*
X1451754Y2163839D01*
Y2161505D01*
G01Y2163839D02*
X1455379Y2165239D01*
G01X1447879Y2169752D02*
Y2171992D01*
G01Y2170872D02*
X1455379D01*
G01Y2169752D02*
Y2171992D01*
G01X1447879Y2176505D02*
X1455379D01*
Y2180239D01*
G01X1447879Y2184005D02*
X1455379D01*
Y2187739D01*
G01X1454379Y2198912D02*
X1455004Y2199659D01*
X1455379Y2200499D01*
Y2201245D01*
X1455004Y2201992D01*
X1454379Y2202552D01*
X1453504Y2202832D01*
X1452629Y2202645D01*
X1451879Y2202179D01*
X1451379Y2201339D01*
X1451129Y2200219D01*
X1450629Y2199565D01*
X1449754Y2199285D01*
X1448879Y2199472D01*
X1448254Y2199939D01*
X1447879Y2200592D01*
Y2201245D01*
X1448129Y2201899D01*
X1448754Y2202459D01*
G01X1447879Y2207252D02*
Y2209492D01*
G01Y2208372D02*
X1455379D01*
G01Y2207252D02*
Y2209492D01*
G01X1447879Y2214099D02*
Y2217645D01*
X1455379Y2214099D01*
Y2217645D01*
G01Y2225239D02*
Y2221505D01*
X1447879D01*
Y2225239D01*
G01X1451504Y2223745D02*
Y2221505D01*
G01X1455379Y2236599D02*
X1447879D01*
Y2240145D01*
G01X1451504Y2238839D02*
Y2236599D01*
G01X1455379Y2245872D02*
X1455254Y2245125D01*
X1454754Y2244472D01*
X1454004Y2243912D01*
X1453129Y2243539D01*
X1452129Y2243352D01*
X1451129D01*
X1450129Y2243539D01*
X1449254Y2243912D01*
X1448504Y2244472D01*
X1448004Y2245125D01*
X1447879Y2245872D01*
X1448004Y2246619D01*
X1448504Y2247272D01*
X1449254Y2247832D01*
X1450129Y2248205D01*
X1451129Y2248392D01*
X1452129D01*
X1453129Y2248205D01*
X1454004Y2247832D01*
X1454754Y2247272D01*
X1455254Y2246619D01*
X1455379Y2245872D01*
G01Y2251505D02*
X1447879D01*
Y2253839D01*
X1448254Y2254585D01*
X1448754Y2255052D01*
X1449754Y2255239D01*
X1450754Y2255052D01*
X1451379Y2254492D01*
X1451754Y2253839D01*
Y2251505D01*
G01Y2253839D02*
X1455379Y2255239D01*
G01X1447879Y2268372D02*
X1448129Y2267625D01*
X1448754Y2267065D01*
X1449504Y2266692D01*
X1450504Y2266412D01*
X1451629Y2266319D01*
X1452754Y2266412D01*
X1453754Y2266692D01*
X1454504Y2267065D01*
X1455129Y2267625D01*
X1455379Y2268372D01*
X1455129Y2269119D01*
X1454504Y2269679D01*
X1453754Y2270052D01*
X1452754Y2270332D01*
X1451629Y2270425D01*
X1450504Y2270332D01*
X1449504Y2270052D01*
X1448754Y2269679D01*
X1448129Y2269119D01*
X1447879Y2268372D01*
G01X1455629Y2275872D02*
X1455504Y2275685D01*
X1455254D01*
X1455129Y2275872D01*
X1455254Y2276059D01*
X1455504D01*
X1455629Y2275872D01*
G01X1453879Y2281319D02*
X1454754Y2281879D01*
X1455254Y2282625D01*
X1455379Y2283465D01*
X1455254Y2284212D01*
X1454629Y2284959D01*
X1453879Y2285425D01*
X1453129Y2285519D01*
X1452254Y2285332D01*
X1451629Y2284679D01*
X1451379Y2284025D01*
Y2283185D01*
G01Y2284025D02*
X1451004Y2284585D01*
X1450379Y2285052D01*
X1449629Y2285239D01*
X1448879Y2285052D01*
X1448254Y2284585D01*
X1447879Y2283745D01*
X1448004Y2282905D01*
X1448504Y2282065D01*
G01X1452254Y2289099D02*
X1451379Y2289752D01*
X1450879Y2290312D01*
X1450629Y2291059D01*
X1450879Y2291712D01*
X1451379Y2292179D01*
X1452129Y2292552D01*
X1453004Y2292645D01*
X1453754Y2292552D01*
X1454504Y2292179D01*
X1455129Y2291619D01*
X1455379Y2290965D01*
X1455129Y2290219D01*
X1454379Y2289565D01*
X1453254Y2289192D01*
X1452004Y2289099D01*
X1450379Y2289285D01*
X1449504Y2289565D01*
X1448629Y2290032D01*
X1448004Y2290685D01*
X1447879Y2291339D01*
X1448129Y2291992D01*
X1448754Y2292459D01*
G01X1455379Y2295945D02*
X1447879D01*
X1454129Y2298372D01*
X1447879Y2300799D01*
X1455379D01*
G01Y2303445D02*
X1447879D01*
X1454129Y2305872D01*
X1447879Y2308299D01*
X1455379D01*
G01Y2319099D02*
X1447879D01*
Y2322645D01*
G01X1451504Y2321339D02*
Y2319099D01*
G01X1447879Y2327252D02*
Y2329492D01*
G01Y2328372D02*
X1455379D01*
G01Y2327252D02*
Y2329492D01*
G01Y2333725D02*
X1447879D01*
X1455379Y2338019D01*
X1447879D01*
G01Y2342252D02*
Y2344492D01*
G01Y2343372D02*
X1455379D01*
G01Y2342252D02*
Y2344492D01*
G01X1454379Y2348912D02*
X1455004Y2349659D01*
X1455379Y2350499D01*
Y2351245D01*
X1455004Y2351992D01*
X1454379Y2352552D01*
X1453504Y2352832D01*
X1452629Y2352645D01*
X1451879Y2352179D01*
X1451379Y2351339D01*
X1451129Y2350219D01*
X1450629Y2349565D01*
X1449754Y2349285D01*
X1448879Y2349472D01*
X1448254Y2349939D01*
X1447879Y2350592D01*
Y2351245D01*
X1448129Y2351899D01*
X1448754Y2352459D01*
G01X1455379Y2356412D02*
X1447879D01*
G01Y2360332D02*
X1455379D01*
G01X1451629D02*
Y2356412D01*
G01X1455379Y2367739D02*
Y2364005D01*
X1447879D01*
Y2367739D01*
G01X1451504Y2366245D02*
Y2364005D01*
G01X1455379Y2371319D02*
X1447879D01*
Y2373185D01*
X1448254Y2373932D01*
X1448754Y2374492D01*
X1449504Y2374959D01*
X1450379Y2375332D01*
X1451629Y2375425D01*
X1452879Y2375332D01*
X1453754Y2374959D01*
X1454504Y2374492D01*
X1455004Y2373932D01*
X1455379Y2373185D01*
Y2371319D01*
G01Y2386505D02*
X1447879D01*
Y2388745D01*
X1448254Y2389492D01*
X1449129Y2390052D01*
X1450129Y2390239D01*
X1451129Y2390052D01*
X1451879Y2389585D01*
X1452254Y2388745D01*
Y2386505D01*
G01X1447879Y2395872D02*
X1455379D01*
G01X1447879Y2393725D02*
Y2398019D01*
G01X1455379Y2401412D02*
X1447879D01*
G01Y2405332D02*
X1455379D01*
G01X1451629D02*
Y2401412D01*
G01X1447879Y2417252D02*
Y2419492D01*
G01Y2418372D02*
X1455379D01*
G01Y2417252D02*
Y2419492D01*
G01X1454379Y2423912D02*
X1455004Y2424659D01*
X1455379Y2425499D01*
Y2426245D01*
X1455004Y2426992D01*
X1454379Y2427552D01*
X1453504Y2427832D01*
X1452629Y2427645D01*
X1451879Y2427179D01*
X1451379Y2426339D01*
X1451129Y2425219D01*
X1450629Y2424565D01*
X1449754Y2424285D01*
X1448879Y2424472D01*
X1448254Y2424939D01*
X1447879Y2425592D01*
Y2426245D01*
X1448129Y2426899D01*
X1448754Y2427459D01*
G01X1447879Y2440872D02*
X1448129Y2440125D01*
X1448754Y2439565D01*
X1449504Y2439192D01*
X1450504Y2438912D01*
X1451629Y2438819D01*
X1452754Y2438912D01*
X1453754Y2439192D01*
X1454504Y2439565D01*
X1455129Y2440125D01*
X1455379Y2440872D01*
X1455129Y2441619D01*
X1454504Y2442179D01*
X1453754Y2442552D01*
X1452754Y2442832D01*
X1451629Y2442925D01*
X1450504Y2442832D01*
X1449504Y2442552D01*
X1448754Y2442179D01*
X1448129Y2441619D01*
X1447879Y2440872D01*
G01X1455629Y2448372D02*
X1455504Y2448185D01*
X1455254D01*
X1455129Y2448372D01*
X1455254Y2448559D01*
X1455504D01*
X1455629Y2448372D01*
G01X1455379Y2456992D02*
X1447879D01*
X1453254Y2453539D01*
Y2458205D01*
G01X1454254Y2461319D02*
X1454879Y2461879D01*
X1455254Y2462532D01*
X1455379Y2463372D01*
X1455129Y2464212D01*
X1454629Y2464865D01*
X1453754Y2465332D01*
X1452754Y2465425D01*
X1451754Y2465239D01*
X1451129Y2464772D01*
X1450629Y2464119D01*
X1450504Y2463465D01*
X1450629Y2462812D01*
X1451129Y2461972D01*
X1447879Y2462252D01*
Y2464772D01*
G01X1455379Y2468445D02*
X1447879D01*
X1454129Y2470872D01*
X1447879Y2473299D01*
X1455379D01*
G01Y2475945D02*
X1447879D01*
X1454129Y2478372D01*
X1447879Y2480799D01*
X1455379D01*
G01Y2490945D02*
X1447879D01*
X1454129Y2493372D01*
X1447879Y2495799D01*
X1455379D01*
G01Y2502739D02*
Y2499005D01*
X1447879D01*
Y2502739D01*
G01X1451504Y2501245D02*
Y2499005D01*
G01X1447879Y2508372D02*
X1455379D01*
G01X1447879Y2506225D02*
Y2510519D01*
G01X1455379Y2514005D02*
X1447879D01*
Y2516339D01*
X1448254Y2517085D01*
X1448754Y2517552D01*
X1449754Y2517739D01*
X1450754Y2517552D01*
X1451379Y2516992D01*
X1451754Y2516339D01*
Y2514005D01*
G01Y2516339D02*
X1455379Y2517739D01*
G01X1447879Y2522252D02*
Y2524492D01*
G01Y2523372D02*
X1455379D01*
G01Y2522252D02*
Y2524492D01*
G01X1448504Y2532925D02*
X1448129Y2532365D01*
X1447879Y2531712D01*
Y2530965D01*
X1448254Y2530125D01*
X1448879Y2529472D01*
X1449629Y2529005D01*
X1450879Y2528632D01*
X1452004Y2528539D01*
X1453129Y2528725D01*
X1453879Y2529005D01*
X1454629Y2529565D01*
X1455129Y2530219D01*
X1455379Y2530872D01*
Y2531525D01*
X1455129Y2532179D01*
X1454754Y2532739D01*
X1454254Y2533205D01*
G01X1455379Y2543819D02*
X1447879D01*
Y2545685D01*
X1448254Y2546432D01*
X1448754Y2546992D01*
X1449504Y2547459D01*
X1450379Y2547832D01*
X1451629Y2547925D01*
X1452879Y2547832D01*
X1453754Y2547459D01*
X1454504Y2546992D01*
X1455004Y2546432D01*
X1455379Y2545685D01*
Y2543819D01*
G01Y2551505D02*
X1447879D01*
Y2553839D01*
X1448254Y2554585D01*
X1448754Y2555052D01*
X1449754Y2555239D01*
X1450754Y2555052D01*
X1451379Y2554492D01*
X1451754Y2553839D01*
Y2551505D01*
G01Y2553839D02*
X1455379Y2555239D01*
G01X1447879Y2559752D02*
Y2561992D01*
G01Y2560872D02*
X1455379D01*
G01Y2559752D02*
Y2561992D01*
G01X1447879Y2566505D02*
X1455379D01*
Y2570239D01*
G01X1447879Y2574005D02*
X1455379D01*
Y2577739D01*
G01X1457879Y2582905D02*
X1456629Y2581972D01*
X1455379Y2581505D01*
X1450379D01*
X1449129Y2581972D01*
X1447879Y2582905D01*
G01Y2590872D02*
X1448129Y2590125D01*
X1448754Y2589565D01*
X1449504Y2589192D01*
X1450504Y2588912D01*
X1451629Y2588819D01*
X1452754Y2588912D01*
X1453754Y2589192D01*
X1454504Y2589565D01*
X1455129Y2590125D01*
X1455379Y2590872D01*
X1455129Y2591619D01*
X1454504Y2592179D01*
X1453754Y2592552D01*
X1452754Y2592832D01*
X1451629Y2592925D01*
X1450504Y2592832D01*
X1449504Y2592552D01*
X1448754Y2592179D01*
X1448129Y2591619D01*
X1447879Y2590872D01*
G01X1455629Y2598372D02*
X1455504Y2598185D01*
X1455254D01*
X1455129Y2598372D01*
X1455254Y2598559D01*
X1455504D01*
X1455629Y2598372D01*
G01X1447879Y2605872D02*
X1448129Y2605125D01*
X1448754Y2604565D01*
X1449504Y2604192D01*
X1450504Y2603912D01*
X1451629Y2603819D01*
X1452754Y2603912D01*
X1453754Y2604192D01*
X1454504Y2604565D01*
X1455129Y2605125D01*
X1455379Y2605872D01*
X1455129Y2606619D01*
X1454504Y2607179D01*
X1453754Y2607552D01*
X1452754Y2607832D01*
X1451629Y2607925D01*
X1450504Y2607832D01*
X1449504Y2607552D01*
X1448754Y2607179D01*
X1448129Y2606619D01*
X1447879Y2605872D01*
G01X1455379Y2613372D02*
X1447879D01*
X1449379Y2612252D01*
G01X1455379D02*
Y2614492D01*
G01Y2620685D02*
X1453754Y2620872D01*
X1452379Y2621152D01*
X1451129Y2621525D01*
X1449754Y2621992D01*
X1447879Y2622739D01*
Y2619005D01*
G01X1455379Y2628185D02*
X1453754Y2628372D01*
X1452379Y2628652D01*
X1451129Y2629025D01*
X1449754Y2629492D01*
X1447879Y2630239D01*
Y2626505D01*
G01X1449504Y2635032D02*
X1447879Y2635499D01*
G01Y2636712D02*
X1449504Y2636245D01*
G01X1457879Y2643839D02*
X1456629Y2644772D01*
X1455379Y2645239D01*
X1450379D01*
X1449129Y2644772D01*
X1447879Y2643839D01*
G01X1455629Y2650872D02*
X1455504Y2650685D01*
X1455254D01*
X1455129Y2650872D01*
X1455254Y2651059D01*
X1455504D01*
X1455629Y2650872D01*
G01X1468056Y-404020D02*
X1455556D01*
X1458056Y-405880D01*
G01X1468056D02*
Y-402160D01*
G01Y-389760D02*
X1455556D01*
X1464514Y-395495D01*
Y-387745D01*
G01X1462848Y-382165D02*
X1461389Y-381080D01*
X1460556Y-380150D01*
X1460139Y-378910D01*
X1460556Y-377825D01*
X1461389Y-377050D01*
X1462639Y-376430D01*
X1464098Y-376275D01*
X1465348Y-376430D01*
X1466598Y-377050D01*
X1467639Y-377980D01*
X1468056Y-379065D01*
X1467639Y-380305D01*
X1466390Y-381390D01*
X1464514Y-382010D01*
X1462431Y-382165D01*
X1459723Y-381855D01*
X1458264Y-381390D01*
X1456806Y-380615D01*
X1455764Y-379530D01*
X1455556Y-378445D01*
X1455973Y-377360D01*
X1457014Y-376585D01*
G01X1468056Y-366820D02*
X1455556D01*
X1458056Y-368680D01*
G01X1468056D02*
Y-364960D01*
G01Y-354420D02*
X1467848Y-353335D01*
X1467223Y-352095D01*
X1466181Y-351320D01*
X1464723Y-351010D01*
X1463265Y-351320D01*
X1462014Y-352250D01*
X1461389Y-353645D01*
Y-355195D01*
X1460973Y-356125D01*
X1459931Y-356900D01*
X1458473Y-357210D01*
X1457014Y-356745D01*
X1455973Y-355660D01*
X1455556Y-354420D01*
X1455973Y-353180D01*
X1457014Y-352095D01*
X1458473Y-351630D01*
X1459931Y-351940D01*
X1460973Y-352715D01*
X1461389Y-353645D01*
Y-355195D01*
X1462014Y-356590D01*
X1463265Y-357520D01*
X1464723Y-357830D01*
X1466181Y-357520D01*
X1467223Y-356745D01*
X1467848Y-355505D01*
X1468056Y-354420D01*
G01X1468473Y-342020D02*
X1468264Y-342330D01*
X1467848D01*
X1467639Y-342020D01*
X1467848Y-341710D01*
X1468264D01*
X1468473Y-342020D01*
G01X1455556Y-329620D02*
X1455973Y-330860D01*
X1457014Y-331790D01*
X1458264Y-332410D01*
X1459931Y-332875D01*
X1461806Y-333030D01*
X1463681Y-332875D01*
X1465348Y-332410D01*
X1466598Y-331790D01*
X1467639Y-330860D01*
X1468056Y-329620D01*
X1467639Y-328380D01*
X1466598Y-327450D01*
X1465348Y-326830D01*
X1463681Y-326365D01*
X1461806Y-326210D01*
X1459931Y-326365D01*
X1458264Y-326830D01*
X1457014Y-327450D01*
X1455973Y-328380D01*
X1455556Y-329620D01*
G01X1462848Y-320165D02*
X1461389Y-319080D01*
X1460556Y-318150D01*
X1460139Y-316910D01*
X1460556Y-315825D01*
X1461389Y-315050D01*
X1462639Y-314430D01*
X1464098Y-314275D01*
X1465348Y-314430D01*
X1466598Y-315050D01*
X1467639Y-315980D01*
X1468056Y-317065D01*
X1467639Y-318305D01*
X1466390Y-319390D01*
X1464514Y-320010D01*
X1462431Y-320165D01*
X1459723Y-319855D01*
X1458264Y-319390D01*
X1456806Y-318615D01*
X1455764Y-317530D01*
X1455556Y-316445D01*
X1455973Y-315360D01*
X1457014Y-314585D01*
G01X1465556Y-286030D02*
X1467015Y-285100D01*
X1467848Y-283860D01*
X1468056Y-282465D01*
X1467848Y-281225D01*
X1466806Y-279985D01*
X1465556Y-279210D01*
X1464306Y-279055D01*
X1462848Y-279365D01*
X1461806Y-280450D01*
X1461389Y-281535D01*
Y-282930D01*
G01Y-281535D02*
X1460764Y-280605D01*
X1459723Y-279830D01*
X1458473Y-279520D01*
X1457223Y-279830D01*
X1456181Y-280605D01*
X1455556Y-282000D01*
X1455764Y-283395D01*
X1456598Y-284790D01*
G01X1468056Y-270530D02*
X1465348Y-270220D01*
X1463056Y-269755D01*
X1460973Y-269135D01*
X1458681Y-268360D01*
X1455556Y-267120D01*
Y-273320D01*
G01X1468056Y-257820D02*
X1455556D01*
X1458056Y-259680D01*
G01X1468056D02*
Y-255960D01*
G01X1468473Y-245420D02*
X1468264Y-245730D01*
X1467848D01*
X1467639Y-245420D01*
X1467848Y-245110D01*
X1468264D01*
X1468473Y-245420D01*
G01X1465556Y-236430D02*
X1467015Y-235500D01*
X1467848Y-234260D01*
X1468056Y-232865D01*
X1467848Y-231625D01*
X1466806Y-230385D01*
X1465556Y-229610D01*
X1464306Y-229455D01*
X1462848Y-229765D01*
X1461806Y-230850D01*
X1461389Y-231935D01*
Y-233330D01*
G01Y-231935D02*
X1460764Y-231005D01*
X1459723Y-230230D01*
X1458473Y-229920D01*
X1457223Y-230230D01*
X1456181Y-231005D01*
X1455556Y-232400D01*
X1455764Y-233795D01*
X1456598Y-235190D01*
G01X1462304Y1962675D02*
X1461929Y1962115D01*
X1461679Y1961462D01*
Y1960715D01*
X1462054Y1959875D01*
X1462679Y1959222D01*
X1463429Y1958755D01*
X1464679Y1958382D01*
X1465804Y1958289D01*
X1466929Y1958475D01*
X1467679Y1958755D01*
X1468429Y1959315D01*
X1468929Y1959969D01*
X1469179Y1960622D01*
Y1961275D01*
X1468929Y1961929D01*
X1468554Y1962489D01*
X1468054Y1962955D01*
G01X1469179Y1968122D02*
X1469054Y1967375D01*
X1468554Y1966722D01*
X1467804Y1966162D01*
X1466929Y1965789D01*
X1465929Y1965602D01*
X1464929D01*
X1463929Y1965789D01*
X1463054Y1966162D01*
X1462304Y1966722D01*
X1461804Y1967375D01*
X1461679Y1968122D01*
X1461804Y1968869D01*
X1462304Y1969522D01*
X1463054Y1970082D01*
X1463929Y1970455D01*
X1464929Y1970642D01*
X1465929D01*
X1466929Y1970455D01*
X1467804Y1970082D01*
X1468554Y1969522D01*
X1469054Y1968869D01*
X1469179Y1968122D01*
G01Y1973755D02*
X1461679D01*
Y1975995D01*
X1462054Y1976742D01*
X1462929Y1977302D01*
X1463929Y1977489D01*
X1464929Y1977302D01*
X1465679Y1976835D01*
X1466054Y1975995D01*
Y1973755D01*
G01X1469179Y1981255D02*
X1461679D01*
Y1983495D01*
X1462054Y1984242D01*
X1462929Y1984802D01*
X1463929Y1984989D01*
X1464929Y1984802D01*
X1465679Y1984335D01*
X1466054Y1983495D01*
Y1981255D01*
G01X1469179Y1992489D02*
Y1988755D01*
X1461679D01*
Y1992489D01*
G01X1465304Y1990995D02*
Y1988755D01*
G01X1469179Y1996255D02*
X1461679D01*
Y1998589D01*
X1462054Y1999335D01*
X1462554Y1999802D01*
X1463554Y1999989D01*
X1464554Y1999802D01*
X1465179Y1999242D01*
X1465554Y1998589D01*
Y1996255D01*
G01Y1998589D02*
X1469179Y1999989D01*
G01Y2013122D02*
X1469054Y2012375D01*
X1468554Y2011722D01*
X1467804Y2011162D01*
X1466929Y2010789D01*
X1465929Y2010602D01*
X1464929D01*
X1463929Y2010789D01*
X1463054Y2011162D01*
X1462304Y2011722D01*
X1461804Y2012375D01*
X1461679Y2013122D01*
X1461804Y2013869D01*
X1462304Y2014522D01*
X1463054Y2015082D01*
X1463929Y2015455D01*
X1464929Y2015642D01*
X1465929D01*
X1466929Y2015455D01*
X1467804Y2015082D01*
X1468554Y2014522D01*
X1469054Y2013869D01*
X1469179Y2013122D01*
G01X1468179Y2018662D02*
X1468804Y2019409D01*
X1469179Y2020249D01*
Y2020995D01*
X1468804Y2021742D01*
X1468179Y2022302D01*
X1467304Y2022582D01*
X1466429Y2022395D01*
X1465679Y2021929D01*
X1465179Y2021089D01*
X1464929Y2019969D01*
X1464429Y2019315D01*
X1463554Y2019035D01*
X1462679Y2019222D01*
X1462054Y2019689D01*
X1461679Y2020342D01*
Y2020995D01*
X1461929Y2021649D01*
X1462554Y2022209D01*
G01X1469179Y2026255D02*
X1461679D01*
Y2028495D01*
X1462054Y2029242D01*
X1462929Y2029802D01*
X1463929Y2029989D01*
X1464929Y2029802D01*
X1465679Y2029335D01*
X1466054Y2028495D01*
Y2026255D01*
G01X1469429Y2033942D02*
X1461679Y2037302D01*
G01Y2043122D02*
X1469179D01*
G01X1461679Y2040975D02*
Y2045269D01*
G01Y2049502D02*
Y2051742D01*
G01Y2050622D02*
X1469179D01*
G01Y2049502D02*
Y2051742D01*
G01Y2055975D02*
X1461679D01*
X1469179Y2060269D01*
X1461679D01*
G01X1471679Y2065155D02*
X1470429Y2064222D01*
X1469179Y2063755D01*
X1464179D01*
X1462929Y2064222D01*
X1461679Y2065155D01*
G01Y2072002D02*
Y2074242D01*
G01Y2073122D02*
X1469179D01*
G01Y2072002D02*
Y2074242D01*
G01Y2078195D02*
X1461679D01*
X1467929Y2080622D01*
X1461679Y2083049D01*
X1469179D01*
G01Y2085695D02*
X1461679D01*
X1467929Y2088122D01*
X1461679Y2090549D01*
X1469179D01*
G01Y2097489D02*
Y2093755D01*
X1461679D01*
Y2097489D01*
G01X1465304Y2095995D02*
Y2093755D01*
G01X1469179Y2101255D02*
X1461679D01*
Y2103589D01*
X1462054Y2104335D01*
X1462554Y2104802D01*
X1463554Y2104989D01*
X1464554Y2104802D01*
X1465179Y2104242D01*
X1465554Y2103589D01*
Y2101255D01*
G01Y2103589D02*
X1469179Y2104989D01*
G01X1468179Y2108662D02*
X1468804Y2109409D01*
X1469179Y2110249D01*
Y2110995D01*
X1468804Y2111742D01*
X1468179Y2112302D01*
X1467304Y2112582D01*
X1466429Y2112395D01*
X1465679Y2111929D01*
X1465179Y2111089D01*
X1464929Y2109969D01*
X1464429Y2109315D01*
X1463554Y2109035D01*
X1462679Y2109222D01*
X1462054Y2109689D01*
X1461679Y2110342D01*
Y2110995D01*
X1461929Y2111649D01*
X1462554Y2112209D01*
G01X1461679Y2117002D02*
Y2119242D01*
G01Y2118122D02*
X1469179D01*
G01Y2117002D02*
Y2119242D01*
G01Y2125622D02*
X1469054Y2124875D01*
X1468554Y2124222D01*
X1467804Y2123662D01*
X1466929Y2123289D01*
X1465929Y2123102D01*
X1464929D01*
X1463929Y2123289D01*
X1463054Y2123662D01*
X1462304Y2124222D01*
X1461804Y2124875D01*
X1461679Y2125622D01*
X1461804Y2126369D01*
X1462304Y2127022D01*
X1463054Y2127582D01*
X1463929Y2127955D01*
X1464929Y2128142D01*
X1465929D01*
X1466929Y2127955D01*
X1467804Y2127582D01*
X1468554Y2127022D01*
X1469054Y2126369D01*
X1469179Y2125622D01*
G01Y2130975D02*
X1461679D01*
X1469179Y2135269D01*
X1461679D01*
G01X1471679Y2141089D02*
X1470429Y2142022D01*
X1469179Y2142489D01*
X1464179D01*
X1462929Y2142022D01*
X1461679Y2141089D01*
G01X1469429Y2148122D02*
X1469304Y2147935D01*
X1469054D01*
X1468929Y2148122D01*
X1469054Y2148309D01*
X1469304D01*
X1469429Y2148122D01*
G01X1466054D02*
X1465929Y2147935D01*
X1465679D01*
X1465554Y2148122D01*
X1465679Y2148309D01*
X1465929D01*
X1466054Y2148122D01*
G01X1469179Y2153755D02*
X1461679D01*
Y2156089D01*
X1462054Y2156835D01*
X1462554Y2157302D01*
X1463554Y2157489D01*
X1464554Y2157302D01*
X1465179Y2156742D01*
X1465554Y2156089D01*
Y2153755D01*
G01Y2156089D02*
X1469179Y2157489D01*
G01Y2164989D02*
Y2161255D01*
X1461679D01*
Y2164989D01*
G01X1465304Y2163495D02*
Y2161255D01*
G01X1462304Y2172675D02*
X1461929Y2172115D01*
X1461679Y2171462D01*
Y2170715D01*
X1462054Y2169875D01*
X1462679Y2169222D01*
X1463429Y2168755D01*
X1464679Y2168382D01*
X1465804Y2168289D01*
X1466929Y2168475D01*
X1467679Y2168755D01*
X1468429Y2169315D01*
X1468929Y2169969D01*
X1469179Y2170622D01*
Y2171275D01*
X1468929Y2171929D01*
X1468554Y2172489D01*
X1468054Y2172955D01*
G01X1469179Y2178122D02*
X1469054Y2177375D01*
X1468554Y2176722D01*
X1467804Y2176162D01*
X1466929Y2175789D01*
X1465929Y2175602D01*
X1464929D01*
X1463929Y2175789D01*
X1463054Y2176162D01*
X1462304Y2176722D01*
X1461804Y2177375D01*
X1461679Y2178122D01*
X1461804Y2178869D01*
X1462304Y2179522D01*
X1463054Y2180082D01*
X1463929Y2180455D01*
X1464929Y2180642D01*
X1465929D01*
X1466929Y2180455D01*
X1467804Y2180082D01*
X1468554Y2179522D01*
X1469054Y2178869D01*
X1469179Y2178122D01*
G01Y2183195D02*
X1461679D01*
X1467929Y2185622D01*
X1461679Y2188049D01*
X1469179D01*
G01Y2190695D02*
X1461679D01*
X1467929Y2193122D01*
X1461679Y2195549D01*
X1469179D01*
G01Y2202489D02*
Y2198755D01*
X1461679D01*
Y2202489D01*
G01X1465304Y2200995D02*
Y2198755D01*
G01X1469179Y2205975D02*
X1461679D01*
X1469179Y2210269D01*
X1461679D01*
G01X1469179Y2213569D02*
X1461679D01*
Y2215435D01*
X1462054Y2216182D01*
X1462554Y2216742D01*
X1463304Y2217209D01*
X1464179Y2217582D01*
X1465429Y2217675D01*
X1466679Y2217582D01*
X1467554Y2217209D01*
X1468304Y2216742D01*
X1468804Y2216182D01*
X1469179Y2215435D01*
Y2213569D01*
G01Y2224989D02*
Y2221255D01*
X1461679D01*
Y2224989D01*
G01X1465304Y2223495D02*
Y2221255D01*
G01X1469179Y2228569D02*
X1461679D01*
Y2230435D01*
X1462054Y2231182D01*
X1462554Y2231742D01*
X1463304Y2232209D01*
X1464179Y2232582D01*
X1465429Y2232675D01*
X1466679Y2232582D01*
X1467554Y2232209D01*
X1468304Y2231742D01*
X1468804Y2231182D01*
X1469179Y2230435D01*
Y2228569D01*
G01Y2243569D02*
X1461679D01*
Y2245435D01*
X1462054Y2246182D01*
X1462554Y2246742D01*
X1463304Y2247209D01*
X1464179Y2247582D01*
X1465429Y2247675D01*
X1466679Y2247582D01*
X1467554Y2247209D01*
X1468304Y2246742D01*
X1468804Y2246182D01*
X1469179Y2245435D01*
Y2243569D01*
G01Y2251255D02*
X1461679D01*
Y2253589D01*
X1462054Y2254335D01*
X1462554Y2254802D01*
X1463554Y2254989D01*
X1464554Y2254802D01*
X1465179Y2254242D01*
X1465554Y2253589D01*
Y2251255D01*
G01Y2253589D02*
X1469179Y2254989D01*
G01X1461679Y2259502D02*
Y2261742D01*
G01Y2260622D02*
X1469179D01*
G01Y2259502D02*
Y2261742D01*
G01X1461679Y2266255D02*
X1469179D01*
Y2269989D01*
G01X1461679Y2273755D02*
X1469179D01*
Y2277489D01*
G01X1468179Y2288662D02*
X1468804Y2289409D01*
X1469179Y2290249D01*
Y2290995D01*
X1468804Y2291742D01*
X1468179Y2292302D01*
X1467304Y2292582D01*
X1466429Y2292395D01*
X1465679Y2291929D01*
X1465179Y2291089D01*
X1464929Y2289969D01*
X1464429Y2289315D01*
X1463554Y2289035D01*
X1462679Y2289222D01*
X1462054Y2289689D01*
X1461679Y2290342D01*
Y2290995D01*
X1461929Y2291649D01*
X1462554Y2292209D01*
G01X1461679Y2297002D02*
Y2299242D01*
G01Y2298122D02*
X1469179D01*
G01Y2297002D02*
Y2299242D01*
G01X1461679Y2303849D02*
Y2307395D01*
X1469179Y2303849D01*
Y2307395D01*
G01Y2314989D02*
Y2311255D01*
X1461679D01*
Y2314989D01*
G01X1465304Y2313495D02*
Y2311255D01*
G01X1469179Y2326349D02*
X1461679D01*
Y2329895D01*
G01X1465304Y2328589D02*
Y2326349D01*
G01X1469179Y2335622D02*
X1469054Y2334875D01*
X1468554Y2334222D01*
X1467804Y2333662D01*
X1466929Y2333289D01*
X1465929Y2333102D01*
X1464929D01*
X1463929Y2333289D01*
X1463054Y2333662D01*
X1462304Y2334222D01*
X1461804Y2334875D01*
X1461679Y2335622D01*
X1461804Y2336369D01*
X1462304Y2337022D01*
X1463054Y2337582D01*
X1463929Y2337955D01*
X1464929Y2338142D01*
X1465929D01*
X1466929Y2337955D01*
X1467804Y2337582D01*
X1468554Y2337022D01*
X1469054Y2336369D01*
X1469179Y2335622D01*
G01Y2341255D02*
X1461679D01*
Y2343589D01*
X1462054Y2344335D01*
X1462554Y2344802D01*
X1463554Y2344989D01*
X1464554Y2344802D01*
X1465179Y2344242D01*
X1465554Y2343589D01*
Y2341255D01*
G01Y2343589D02*
X1469179Y2344989D01*
G01X1461679Y2358122D02*
X1461929Y2357375D01*
X1462554Y2356815D01*
X1463304Y2356442D01*
X1464304Y2356162D01*
X1465429Y2356069D01*
X1466554Y2356162D01*
X1467554Y2356442D01*
X1468304Y2356815D01*
X1468929Y2357375D01*
X1469179Y2358122D01*
X1468929Y2358869D01*
X1468304Y2359429D01*
X1467554Y2359802D01*
X1466554Y2360082D01*
X1465429Y2360175D01*
X1464304Y2360082D01*
X1463304Y2359802D01*
X1462554Y2359429D01*
X1461929Y2358869D01*
X1461679Y2358122D01*
G01X1469429Y2365622D02*
X1469304Y2365435D01*
X1469054D01*
X1468929Y2365622D01*
X1469054Y2365809D01*
X1469304D01*
X1469429Y2365622D01*
G01X1467679Y2371069D02*
X1468554Y2371629D01*
X1469054Y2372375D01*
X1469179Y2373215D01*
X1469054Y2373962D01*
X1468429Y2374709D01*
X1467679Y2375175D01*
X1466929Y2375269D01*
X1466054Y2375082D01*
X1465429Y2374429D01*
X1465179Y2373775D01*
Y2372935D01*
G01Y2373775D02*
X1464804Y2374335D01*
X1464179Y2374802D01*
X1463429Y2374989D01*
X1462679Y2374802D01*
X1462054Y2374335D01*
X1461679Y2373495D01*
X1461804Y2372655D01*
X1462304Y2371815D01*
G01X1466054Y2378849D02*
X1465179Y2379502D01*
X1464679Y2380062D01*
X1464429Y2380809D01*
X1464679Y2381462D01*
X1465179Y2381929D01*
X1465929Y2382302D01*
X1466804Y2382395D01*
X1467554Y2382302D01*
X1468304Y2381929D01*
X1468929Y2381369D01*
X1469179Y2380715D01*
X1468929Y2379969D01*
X1468179Y2379315D01*
X1467054Y2378942D01*
X1465804Y2378849D01*
X1464179Y2379035D01*
X1463304Y2379315D01*
X1462429Y2379782D01*
X1461804Y2380435D01*
X1461679Y2381089D01*
X1461929Y2381742D01*
X1462554Y2382209D01*
G01X1469179Y2385695D02*
X1461679D01*
X1467929Y2388122D01*
X1461679Y2390549D01*
X1469179D01*
G01Y2393195D02*
X1461679D01*
X1467929Y2395622D01*
X1461679Y2398049D01*
X1469179D01*
G01Y2408849D02*
X1461679D01*
Y2412395D01*
G01X1465304Y2411089D02*
Y2408849D01*
G01X1461679Y2417002D02*
Y2419242D01*
G01Y2418122D02*
X1469179D01*
G01Y2417002D02*
Y2419242D01*
G01Y2423475D02*
X1461679D01*
X1469179Y2427769D01*
X1461679D01*
G01Y2432002D02*
Y2434242D01*
G01Y2433122D02*
X1469179D01*
G01Y2432002D02*
Y2434242D01*
G01X1468179Y2438662D02*
X1468804Y2439409D01*
X1469179Y2440249D01*
Y2440995D01*
X1468804Y2441742D01*
X1468179Y2442302D01*
X1467304Y2442582D01*
X1466429Y2442395D01*
X1465679Y2441929D01*
X1465179Y2441089D01*
X1464929Y2439969D01*
X1464429Y2439315D01*
X1463554Y2439035D01*
X1462679Y2439222D01*
X1462054Y2439689D01*
X1461679Y2440342D01*
Y2440995D01*
X1461929Y2441649D01*
X1462554Y2442209D01*
G01X1469179Y2446162D02*
X1461679D01*
G01Y2450082D02*
X1469179D01*
G01X1465429D02*
Y2446162D01*
G01X1469179Y2457489D02*
Y2453755D01*
X1461679D01*
Y2457489D01*
G01X1465304Y2455995D02*
Y2453755D01*
G01X1469179Y2461069D02*
X1461679D01*
Y2462935D01*
X1462054Y2463682D01*
X1462554Y2464242D01*
X1463304Y2464709D01*
X1464179Y2465082D01*
X1465429Y2465175D01*
X1466679Y2465082D01*
X1467554Y2464709D01*
X1468304Y2464242D01*
X1468804Y2463682D01*
X1469179Y2462935D01*
Y2461069D01*
G01Y2476255D02*
X1461679D01*
Y2478495D01*
X1462054Y2479242D01*
X1462929Y2479802D01*
X1463929Y2479989D01*
X1464929Y2479802D01*
X1465679Y2479335D01*
X1466054Y2478495D01*
Y2476255D01*
G01X1461679Y2485622D02*
X1469179D01*
G01X1461679Y2483475D02*
Y2487769D01*
G01X1469179Y2491162D02*
X1461679D01*
G01Y2495082D02*
X1469179D01*
G01X1465429D02*
Y2491162D01*
G01X1461679Y2507002D02*
Y2509242D01*
G01Y2508122D02*
X1469179D01*
G01Y2507002D02*
Y2509242D01*
G01X1468179Y2513662D02*
X1468804Y2514409D01*
X1469179Y2515249D01*
Y2515995D01*
X1468804Y2516742D01*
X1468179Y2517302D01*
X1467304Y2517582D01*
X1466429Y2517395D01*
X1465679Y2516929D01*
X1465179Y2516089D01*
X1464929Y2514969D01*
X1464429Y2514315D01*
X1463554Y2514035D01*
X1462679Y2514222D01*
X1462054Y2514689D01*
X1461679Y2515342D01*
Y2515995D01*
X1461929Y2516649D01*
X1462554Y2517209D01*
G01X1461679Y2530622D02*
X1461929Y2529875D01*
X1462554Y2529315D01*
X1463304Y2528942D01*
X1464304Y2528662D01*
X1465429Y2528569D01*
X1466554Y2528662D01*
X1467554Y2528942D01*
X1468304Y2529315D01*
X1468929Y2529875D01*
X1469179Y2530622D01*
X1468929Y2531369D01*
X1468304Y2531929D01*
X1467554Y2532302D01*
X1466554Y2532582D01*
X1465429Y2532675D01*
X1464304Y2532582D01*
X1463304Y2532302D01*
X1462554Y2531929D01*
X1461929Y2531369D01*
X1461679Y2530622D01*
G01X1469429Y2538122D02*
X1469304Y2537935D01*
X1469054D01*
X1468929Y2538122D01*
X1469054Y2538309D01*
X1469304D01*
X1469429Y2538122D01*
G01X1469179Y2546742D02*
X1461679D01*
X1467054Y2543289D01*
Y2547955D01*
G01X1468054Y2551069D02*
X1468679Y2551629D01*
X1469054Y2552282D01*
X1469179Y2553122D01*
X1468929Y2553962D01*
X1468429Y2554615D01*
X1467554Y2555082D01*
X1466554Y2555175D01*
X1465554Y2554989D01*
X1464929Y2554522D01*
X1464429Y2553869D01*
X1464304Y2553215D01*
X1464429Y2552562D01*
X1464929Y2551722D01*
X1461679Y2552002D01*
Y2554522D01*
G01X1469179Y2558195D02*
X1461679D01*
X1467929Y2560622D01*
X1461679Y2563049D01*
X1469179D01*
G01Y2565695D02*
X1461679D01*
X1467929Y2568122D01*
X1461679Y2570549D01*
X1469179D01*
G01Y2580695D02*
X1461679D01*
X1467929Y2583122D01*
X1461679Y2585549D01*
X1469179D01*
G01Y2592489D02*
Y2588755D01*
X1461679D01*
Y2592489D01*
G01X1465304Y2590995D02*
Y2588755D01*
G01X1461679Y2598122D02*
X1469179D01*
G01X1461679Y2595975D02*
Y2600269D01*
G01X1469179Y2603755D02*
X1461679D01*
Y2606089D01*
X1462054Y2606835D01*
X1462554Y2607302D01*
X1463554Y2607489D01*
X1464554Y2607302D01*
X1465179Y2606742D01*
X1465554Y2606089D01*
Y2603755D01*
G01Y2606089D02*
X1469179Y2607489D01*
G01X1461679Y2612002D02*
Y2614242D01*
G01Y2613122D02*
X1469179D01*
G01Y2612002D02*
Y2614242D01*
G01X1462304Y2622675D02*
X1461929Y2622115D01*
X1461679Y2621462D01*
Y2620715D01*
X1462054Y2619875D01*
X1462679Y2619222D01*
X1463429Y2618755D01*
X1464679Y2618382D01*
X1465804Y2618289D01*
X1466929Y2618475D01*
X1467679Y2618755D01*
X1468429Y2619315D01*
X1468929Y2619969D01*
X1469179Y2620622D01*
Y2621275D01*
X1468929Y2621929D01*
X1468554Y2622489D01*
X1468054Y2622955D01*
G01X1469179Y2633569D02*
X1461679D01*
Y2635435D01*
X1462054Y2636182D01*
X1462554Y2636742D01*
X1463304Y2637209D01*
X1464179Y2637582D01*
X1465429Y2637675D01*
X1466679Y2637582D01*
X1467554Y2637209D01*
X1468304Y2636742D01*
X1468804Y2636182D01*
X1469179Y2635435D01*
Y2633569D01*
G01Y2641255D02*
X1461679D01*
Y2643589D01*
X1462054Y2644335D01*
X1462554Y2644802D01*
X1463554Y2644989D01*
X1464554Y2644802D01*
X1465179Y2644242D01*
X1465554Y2643589D01*
Y2641255D01*
G01Y2643589D02*
X1469179Y2644989D01*
G01X1461679Y2649502D02*
Y2651742D01*
G01Y2650622D02*
X1469179D01*
G01Y2649502D02*
Y2651742D01*
G01X1461679Y2656255D02*
X1469179D01*
Y2659989D01*
G01X1461679Y2663755D02*
X1469179D01*
Y2667489D01*
G01X1471679Y2672655D02*
X1470429Y2671722D01*
X1469179Y2671255D01*
X1464179D01*
X1462929Y2671722D01*
X1461679Y2672655D01*
G01Y2680622D02*
X1461929Y2679875D01*
X1462554Y2679315D01*
X1463304Y2678942D01*
X1464304Y2678662D01*
X1465429Y2678569D01*
X1466554Y2678662D01*
X1467554Y2678942D01*
X1468304Y2679315D01*
X1468929Y2679875D01*
X1469179Y2680622D01*
X1468929Y2681369D01*
X1468304Y2681929D01*
X1467554Y2682302D01*
X1466554Y2682582D01*
X1465429Y2682675D01*
X1464304Y2682582D01*
X1463304Y2682302D01*
X1462554Y2681929D01*
X1461929Y2681369D01*
X1461679Y2680622D01*
G01X1469429Y2688122D02*
X1469304Y2687935D01*
X1469054D01*
X1468929Y2688122D01*
X1469054Y2688309D01*
X1469304D01*
X1469429Y2688122D01*
G01X1461679Y2695622D02*
X1461929Y2694875D01*
X1462554Y2694315D01*
X1463304Y2693942D01*
X1464304Y2693662D01*
X1465429Y2693569D01*
X1466554Y2693662D01*
X1467554Y2693942D01*
X1468304Y2694315D01*
X1468929Y2694875D01*
X1469179Y2695622D01*
X1468929Y2696369D01*
X1468304Y2696929D01*
X1467554Y2697302D01*
X1466554Y2697582D01*
X1465429Y2697675D01*
X1464304Y2697582D01*
X1463304Y2697302D01*
X1462554Y2696929D01*
X1461929Y2696369D01*
X1461679Y2695622D01*
G01X1469179Y2703122D02*
X1461679D01*
X1463179Y2702002D01*
G01X1469179D02*
Y2704242D01*
G01Y2710435D02*
X1467554Y2710622D01*
X1466179Y2710902D01*
X1464929Y2711275D01*
X1463554Y2711742D01*
X1461679Y2712489D01*
Y2708755D01*
G01X1469179Y2717935D02*
X1467554Y2718122D01*
X1466179Y2718402D01*
X1464929Y2718775D01*
X1463554Y2719242D01*
X1461679Y2719989D01*
Y2716255D01*
G01X1463304Y2724782D02*
X1461679Y2725249D01*
G01Y2726462D02*
X1463304Y2725995D01*
G01X1471679Y2733589D02*
X1470429Y2734522D01*
X1469179Y2734989D01*
X1464179D01*
X1462929Y2734522D01*
X1461679Y2733589D01*
G01X1469429Y2740622D02*
X1469304Y2740435D01*
X1469054D01*
X1468929Y2740622D01*
X1469054Y2740809D01*
X1469304D01*
X1469429Y2740622D01*
G01X1480159Y1957490D02*
X1480784Y1958237D01*
X1481159Y1959077D01*
Y1959823D01*
X1480784Y1960570D01*
X1480159Y1961130D01*
X1479284Y1961410D01*
X1478409Y1961223D01*
X1477659Y1960757D01*
X1477159Y1959917D01*
X1476909Y1958797D01*
X1476409Y1958143D01*
X1475534Y1957863D01*
X1474659Y1958050D01*
X1474034Y1958517D01*
X1473659Y1959170D01*
Y1959823D01*
X1473909Y1960477D01*
X1474534Y1961037D01*
G01X1473659Y1965830D02*
Y1968070D01*
G01Y1966950D02*
X1481159D01*
G01Y1965830D02*
Y1968070D01*
G01X1473659Y1972583D02*
X1481159D01*
Y1976317D01*
G01X1473659Y1979617D02*
X1481159Y1981950D01*
X1473659Y1984283D01*
G01X1481159Y1991317D02*
Y1987583D01*
X1473659D01*
Y1991317D01*
G01X1477284Y1989823D02*
Y1987583D01*
G01X1481159Y1995083D02*
X1473659D01*
Y1997417D01*
X1474034Y1998163D01*
X1474534Y1998630D01*
X1475534Y1998817D01*
X1476534Y1998630D01*
X1477159Y1998070D01*
X1477534Y1997417D01*
Y1995083D01*
G01Y1997417D02*
X1481159Y1998817D01*
G01X1483659Y2003983D02*
X1482409Y2003050D01*
X1481159Y2002583D01*
X1476159D01*
X1474909Y2003050D01*
X1473659Y2003983D01*
G01Y2010830D02*
Y2013070D01*
G01Y2011950D02*
X1481159D01*
G01Y2010830D02*
Y2013070D01*
G01Y2017023D02*
X1473659D01*
X1479909Y2019450D01*
X1473659Y2021877D01*
X1481159D01*
G01Y2024523D02*
X1473659D01*
X1479909Y2026950D01*
X1473659Y2029377D01*
X1481159D01*
G01Y2036317D02*
Y2032583D01*
X1473659D01*
Y2036317D01*
G01X1477284Y2034823D02*
Y2032583D01*
G01X1481159Y2040083D02*
X1473659D01*
Y2042417D01*
X1474034Y2043163D01*
X1474534Y2043630D01*
X1475534Y2043817D01*
X1476534Y2043630D01*
X1477159Y2043070D01*
X1477534Y2042417D01*
Y2040083D01*
G01Y2042417D02*
X1481159Y2043817D01*
G01X1480159Y2047490D02*
X1480784Y2048237D01*
X1481159Y2049077D01*
Y2049823D01*
X1480784Y2050570D01*
X1480159Y2051130D01*
X1479284Y2051410D01*
X1478409Y2051223D01*
X1477659Y2050757D01*
X1477159Y2049917D01*
X1476909Y2048797D01*
X1476409Y2048143D01*
X1475534Y2047863D01*
X1474659Y2048050D01*
X1474034Y2048517D01*
X1473659Y2049170D01*
Y2049823D01*
X1473909Y2050477D01*
X1474534Y2051037D01*
G01X1473659Y2055830D02*
Y2058070D01*
G01Y2056950D02*
X1481159D01*
G01Y2055830D02*
Y2058070D01*
G01Y2064450D02*
X1481034Y2063703D01*
X1480534Y2063050D01*
X1479784Y2062490D01*
X1478909Y2062117D01*
X1477909Y2061930D01*
X1476909D01*
X1475909Y2062117D01*
X1475034Y2062490D01*
X1474284Y2063050D01*
X1473784Y2063703D01*
X1473659Y2064450D01*
X1473784Y2065197D01*
X1474284Y2065850D01*
X1475034Y2066410D01*
X1475909Y2066783D01*
X1476909Y2066970D01*
X1477909D01*
X1478909Y2066783D01*
X1479784Y2066410D01*
X1480534Y2065850D01*
X1481034Y2065197D01*
X1481159Y2064450D01*
G01Y2069803D02*
X1473659D01*
X1481159Y2074097D01*
X1473659D01*
G01X1483659Y2079917D02*
X1482409Y2080850D01*
X1481159Y2081317D01*
X1476159D01*
X1474909Y2080850D01*
X1473659Y2079917D01*
G01X1481409Y2086950D02*
X1481284Y2086763D01*
X1481034D01*
X1480909Y2086950D01*
X1481034Y2087137D01*
X1481284D01*
X1481409Y2086950D01*
G01X1478034D02*
X1477909Y2086763D01*
X1477659D01*
X1477534Y2086950D01*
X1477659Y2087137D01*
X1477909D01*
X1478034Y2086950D01*
G01X1481159Y2092583D02*
X1473659D01*
Y2094917D01*
X1474034Y2095663D01*
X1474534Y2096130D01*
X1475534Y2096317D01*
X1476534Y2096130D01*
X1477159Y2095570D01*
X1477534Y2094917D01*
Y2092583D01*
G01Y2094917D02*
X1481159Y2096317D01*
G01Y2103817D02*
Y2100083D01*
X1473659D01*
Y2103817D01*
G01X1477284Y2102323D02*
Y2100083D01*
G01X1474284Y2111503D02*
X1473909Y2110943D01*
X1473659Y2110290D01*
Y2109543D01*
X1474034Y2108703D01*
X1474659Y2108050D01*
X1475409Y2107583D01*
X1476659Y2107210D01*
X1477784Y2107117D01*
X1478909Y2107303D01*
X1479659Y2107583D01*
X1480409Y2108143D01*
X1480909Y2108797D01*
X1481159Y2109450D01*
Y2110103D01*
X1480909Y2110757D01*
X1480534Y2111317D01*
X1480034Y2111783D01*
G01X1481159Y2116950D02*
X1481034Y2116203D01*
X1480534Y2115550D01*
X1479784Y2114990D01*
X1478909Y2114617D01*
X1477909Y2114430D01*
X1476909D01*
X1475909Y2114617D01*
X1475034Y2114990D01*
X1474284Y2115550D01*
X1473784Y2116203D01*
X1473659Y2116950D01*
X1473784Y2117697D01*
X1474284Y2118350D01*
X1475034Y2118910D01*
X1475909Y2119283D01*
X1476909Y2119470D01*
X1477909D01*
X1478909Y2119283D01*
X1479784Y2118910D01*
X1480534Y2118350D01*
X1481034Y2117697D01*
X1481159Y2116950D01*
G01Y2122023D02*
X1473659D01*
X1479909Y2124450D01*
X1473659Y2126877D01*
X1481159D01*
G01Y2129523D02*
X1473659D01*
X1479909Y2131950D01*
X1473659Y2134377D01*
X1481159D01*
G01Y2141317D02*
Y2137583D01*
X1473659D01*
Y2141317D01*
G01X1477284Y2139823D02*
Y2137583D01*
G01X1481159Y2144803D02*
X1473659D01*
X1481159Y2149097D01*
X1473659D01*
G01X1481159Y2152397D02*
X1473659D01*
Y2154263D01*
X1474034Y2155010D01*
X1474534Y2155570D01*
X1475284Y2156037D01*
X1476159Y2156410D01*
X1477409Y2156503D01*
X1478659Y2156410D01*
X1479534Y2156037D01*
X1480284Y2155570D01*
X1480784Y2155010D01*
X1481159Y2154263D01*
Y2152397D01*
G01Y2163817D02*
Y2160083D01*
X1473659D01*
Y2163817D01*
G01X1477284Y2162323D02*
Y2160083D01*
G01X1481159Y2167397D02*
X1473659D01*
Y2169263D01*
X1474034Y2170010D01*
X1474534Y2170570D01*
X1475284Y2171037D01*
X1476159Y2171410D01*
X1477409Y2171503D01*
X1478659Y2171410D01*
X1479534Y2171037D01*
X1480284Y2170570D01*
X1480784Y2170010D01*
X1481159Y2169263D01*
Y2167397D01*
G01Y2182397D02*
X1473659D01*
Y2184263D01*
X1474034Y2185010D01*
X1474534Y2185570D01*
X1475284Y2186037D01*
X1476159Y2186410D01*
X1477409Y2186503D01*
X1478659Y2186410D01*
X1479534Y2186037D01*
X1480284Y2185570D01*
X1480784Y2185010D01*
X1481159Y2184263D01*
Y2182397D01*
G01Y2190083D02*
X1473659D01*
Y2192417D01*
X1474034Y2193163D01*
X1474534Y2193630D01*
X1475534Y2193817D01*
X1476534Y2193630D01*
X1477159Y2193070D01*
X1477534Y2192417D01*
Y2190083D01*
G01Y2192417D02*
X1481159Y2193817D01*
G01X1473659Y2198330D02*
Y2200570D01*
G01Y2199450D02*
X1481159D01*
G01Y2198330D02*
Y2200570D01*
G01X1473659Y2205083D02*
X1481159D01*
Y2208817D01*
G01X1473659Y2212583D02*
X1481159D01*
Y2216317D01*
G01X1480159Y2227490D02*
X1480784Y2228237D01*
X1481159Y2229077D01*
Y2229823D01*
X1480784Y2230570D01*
X1480159Y2231130D01*
X1479284Y2231410D01*
X1478409Y2231223D01*
X1477659Y2230757D01*
X1477159Y2229917D01*
X1476909Y2228797D01*
X1476409Y2228143D01*
X1475534Y2227863D01*
X1474659Y2228050D01*
X1474034Y2228517D01*
X1473659Y2229170D01*
Y2229823D01*
X1473909Y2230477D01*
X1474534Y2231037D01*
G01X1473659Y2235830D02*
Y2238070D01*
G01Y2236950D02*
X1481159D01*
G01Y2235830D02*
Y2238070D01*
G01X1473659Y2242677D02*
Y2246223D01*
X1481159Y2242677D01*
Y2246223D01*
G01Y2253817D02*
Y2250083D01*
X1473659D01*
Y2253817D01*
G01X1477284Y2252323D02*
Y2250083D01*
G01X1481159Y2265177D02*
X1473659D01*
Y2268723D01*
G01X1477284Y2267417D02*
Y2265177D01*
G01X1481159Y2274450D02*
X1481034Y2273703D01*
X1480534Y2273050D01*
X1479784Y2272490D01*
X1478909Y2272117D01*
X1477909Y2271930D01*
X1476909D01*
X1475909Y2272117D01*
X1475034Y2272490D01*
X1474284Y2273050D01*
X1473784Y2273703D01*
X1473659Y2274450D01*
X1473784Y2275197D01*
X1474284Y2275850D01*
X1475034Y2276410D01*
X1475909Y2276783D01*
X1476909Y2276970D01*
X1477909D01*
X1478909Y2276783D01*
X1479784Y2276410D01*
X1480534Y2275850D01*
X1481034Y2275197D01*
X1481159Y2274450D01*
G01Y2280083D02*
X1473659D01*
Y2282417D01*
X1474034Y2283163D01*
X1474534Y2283630D01*
X1475534Y2283817D01*
X1476534Y2283630D01*
X1477159Y2283070D01*
X1477534Y2282417D01*
Y2280083D01*
G01Y2282417D02*
X1481159Y2283817D01*
G01X1473659Y2296950D02*
X1473909Y2296203D01*
X1474534Y2295643D01*
X1475284Y2295270D01*
X1476284Y2294990D01*
X1477409Y2294897D01*
X1478534Y2294990D01*
X1479534Y2295270D01*
X1480284Y2295643D01*
X1480909Y2296203D01*
X1481159Y2296950D01*
X1480909Y2297697D01*
X1480284Y2298257D01*
X1479534Y2298630D01*
X1478534Y2298910D01*
X1477409Y2299003D01*
X1476284Y2298910D01*
X1475284Y2298630D01*
X1474534Y2298257D01*
X1473909Y2297697D01*
X1473659Y2296950D01*
G01X1481409Y2304450D02*
X1481284Y2304263D01*
X1481034D01*
X1480909Y2304450D01*
X1481034Y2304637D01*
X1481284D01*
X1481409Y2304450D01*
G01X1479659Y2309897D02*
X1480534Y2310457D01*
X1481034Y2311203D01*
X1481159Y2312043D01*
X1481034Y2312790D01*
X1480409Y2313537D01*
X1479659Y2314003D01*
X1478909Y2314097D01*
X1478034Y2313910D01*
X1477409Y2313257D01*
X1477159Y2312603D01*
Y2311763D01*
G01Y2312603D02*
X1476784Y2313163D01*
X1476159Y2313630D01*
X1475409Y2313817D01*
X1474659Y2313630D01*
X1474034Y2313163D01*
X1473659Y2312323D01*
X1473784Y2311483D01*
X1474284Y2310643D01*
G01X1478034Y2317677D02*
X1477159Y2318330D01*
X1476659Y2318890D01*
X1476409Y2319637D01*
X1476659Y2320290D01*
X1477159Y2320757D01*
X1477909Y2321130D01*
X1478784Y2321223D01*
X1479534Y2321130D01*
X1480284Y2320757D01*
X1480909Y2320197D01*
X1481159Y2319543D01*
X1480909Y2318797D01*
X1480159Y2318143D01*
X1479034Y2317770D01*
X1477784Y2317677D01*
X1476159Y2317863D01*
X1475284Y2318143D01*
X1474409Y2318610D01*
X1473784Y2319263D01*
X1473659Y2319917D01*
X1473909Y2320570D01*
X1474534Y2321037D01*
G01X1481159Y2324523D02*
X1473659D01*
X1479909Y2326950D01*
X1473659Y2329377D01*
X1481159D01*
G01Y2332023D02*
X1473659D01*
X1479909Y2334450D01*
X1473659Y2336877D01*
X1481159D01*
G01Y2347677D02*
X1473659D01*
Y2351223D01*
G01X1477284Y2349917D02*
Y2347677D01*
G01X1473659Y2355830D02*
Y2358070D01*
G01Y2356950D02*
X1481159D01*
G01Y2355830D02*
Y2358070D01*
G01Y2362303D02*
X1473659D01*
X1481159Y2366597D01*
X1473659D01*
G01Y2370830D02*
Y2373070D01*
G01Y2371950D02*
X1481159D01*
G01Y2370830D02*
Y2373070D01*
G01X1480159Y2377490D02*
X1480784Y2378237D01*
X1481159Y2379077D01*
Y2379823D01*
X1480784Y2380570D01*
X1480159Y2381130D01*
X1479284Y2381410D01*
X1478409Y2381223D01*
X1477659Y2380757D01*
X1477159Y2379917D01*
X1476909Y2378797D01*
X1476409Y2378143D01*
X1475534Y2377863D01*
X1474659Y2378050D01*
X1474034Y2378517D01*
X1473659Y2379170D01*
Y2379823D01*
X1473909Y2380477D01*
X1474534Y2381037D01*
G01X1481159Y2384990D02*
X1473659D01*
G01Y2388910D02*
X1481159D01*
G01X1477409D02*
Y2384990D01*
G01X1481159Y2396317D02*
Y2392583D01*
X1473659D01*
Y2396317D01*
G01X1477284Y2394823D02*
Y2392583D01*
G01X1481159Y2399897D02*
X1473659D01*
Y2401763D01*
X1474034Y2402510D01*
X1474534Y2403070D01*
X1475284Y2403537D01*
X1476159Y2403910D01*
X1477409Y2404003D01*
X1478659Y2403910D01*
X1479534Y2403537D01*
X1480284Y2403070D01*
X1480784Y2402510D01*
X1481159Y2401763D01*
Y2399897D01*
G01Y2415083D02*
X1473659D01*
Y2417323D01*
X1474034Y2418070D01*
X1474909Y2418630D01*
X1475909Y2418817D01*
X1476909Y2418630D01*
X1477659Y2418163D01*
X1478034Y2417323D01*
Y2415083D01*
G01X1473659Y2424450D02*
X1481159D01*
G01X1473659Y2422303D02*
Y2426597D01*
G01X1481159Y2429990D02*
X1473659D01*
G01Y2433910D02*
X1481159D01*
G01X1477409D02*
Y2429990D01*
G01X1473659Y2445830D02*
Y2448070D01*
G01Y2446950D02*
X1481159D01*
G01Y2445830D02*
Y2448070D01*
G01X1480159Y2452490D02*
X1480784Y2453237D01*
X1481159Y2454077D01*
Y2454823D01*
X1480784Y2455570D01*
X1480159Y2456130D01*
X1479284Y2456410D01*
X1478409Y2456223D01*
X1477659Y2455757D01*
X1477159Y2454917D01*
X1476909Y2453797D01*
X1476409Y2453143D01*
X1475534Y2452863D01*
X1474659Y2453050D01*
X1474034Y2453517D01*
X1473659Y2454170D01*
Y2454823D01*
X1473909Y2455477D01*
X1474534Y2456037D01*
G01X1473659Y2469450D02*
X1473909Y2468703D01*
X1474534Y2468143D01*
X1475284Y2467770D01*
X1476284Y2467490D01*
X1477409Y2467397D01*
X1478534Y2467490D01*
X1479534Y2467770D01*
X1480284Y2468143D01*
X1480909Y2468703D01*
X1481159Y2469450D01*
X1480909Y2470197D01*
X1480284Y2470757D01*
X1479534Y2471130D01*
X1478534Y2471410D01*
X1477409Y2471503D01*
X1476284Y2471410D01*
X1475284Y2471130D01*
X1474534Y2470757D01*
X1473909Y2470197D01*
X1473659Y2469450D01*
G01X1481409Y2476950D02*
X1481284Y2476763D01*
X1481034D01*
X1480909Y2476950D01*
X1481034Y2477137D01*
X1481284D01*
X1481409Y2476950D01*
G01X1481159Y2485570D02*
X1473659D01*
X1479034Y2482117D01*
Y2486783D01*
G01X1480034Y2489897D02*
X1480659Y2490457D01*
X1481034Y2491110D01*
X1481159Y2491950D01*
X1480909Y2492790D01*
X1480409Y2493443D01*
X1479534Y2493910D01*
X1478534Y2494003D01*
X1477534Y2493817D01*
X1476909Y2493350D01*
X1476409Y2492697D01*
X1476284Y2492043D01*
X1476409Y2491390D01*
X1476909Y2490550D01*
X1473659Y2490830D01*
Y2493350D01*
G01X1481159Y2497023D02*
X1473659D01*
X1479909Y2499450D01*
X1473659Y2501877D01*
X1481159D01*
G01Y2504523D02*
X1473659D01*
X1479909Y2506950D01*
X1473659Y2509377D01*
X1481159D01*
G01Y2519523D02*
X1473659D01*
X1479909Y2521950D01*
X1473659Y2524377D01*
X1481159D01*
G01Y2531317D02*
Y2527583D01*
X1473659D01*
Y2531317D01*
G01X1477284Y2529823D02*
Y2527583D01*
G01X1473659Y2536950D02*
X1481159D01*
G01X1473659Y2534803D02*
Y2539097D01*
G01X1481159Y2542583D02*
X1473659D01*
Y2544917D01*
X1474034Y2545663D01*
X1474534Y2546130D01*
X1475534Y2546317D01*
X1476534Y2546130D01*
X1477159Y2545570D01*
X1477534Y2544917D01*
Y2542583D01*
G01Y2544917D02*
X1481159Y2546317D01*
G01X1473659Y2550830D02*
Y2553070D01*
G01Y2551950D02*
X1481159D01*
G01Y2550830D02*
Y2553070D01*
G01X1474284Y2561503D02*
X1473909Y2560943D01*
X1473659Y2560290D01*
Y2559543D01*
X1474034Y2558703D01*
X1474659Y2558050D01*
X1475409Y2557583D01*
X1476659Y2557210D01*
X1477784Y2557117D01*
X1478909Y2557303D01*
X1479659Y2557583D01*
X1480409Y2558143D01*
X1480909Y2558797D01*
X1481159Y2559450D01*
Y2560103D01*
X1480909Y2560757D01*
X1480534Y2561317D01*
X1480034Y2561783D01*
G01X1481159Y2572397D02*
X1473659D01*
Y2574263D01*
X1474034Y2575010D01*
X1474534Y2575570D01*
X1475284Y2576037D01*
X1476159Y2576410D01*
X1477409Y2576503D01*
X1478659Y2576410D01*
X1479534Y2576037D01*
X1480284Y2575570D01*
X1480784Y2575010D01*
X1481159Y2574263D01*
Y2572397D01*
G01Y2580083D02*
X1473659D01*
Y2582417D01*
X1474034Y2583163D01*
X1474534Y2583630D01*
X1475534Y2583817D01*
X1476534Y2583630D01*
X1477159Y2583070D01*
X1477534Y2582417D01*
Y2580083D01*
G01Y2582417D02*
X1481159Y2583817D01*
G01X1473659Y2588330D02*
Y2590570D01*
G01Y2589450D02*
X1481159D01*
G01Y2588330D02*
Y2590570D01*
G01X1473659Y2595083D02*
X1481159D01*
Y2598817D01*
G01X1473659Y2602583D02*
X1481159D01*
Y2606317D01*
G01X1483659Y2611483D02*
X1482409Y2610550D01*
X1481159Y2610083D01*
X1476159D01*
X1474909Y2610550D01*
X1473659Y2611483D01*
G01Y2619450D02*
X1473909Y2618703D01*
X1474534Y2618143D01*
X1475284Y2617770D01*
X1476284Y2617490D01*
X1477409Y2617397D01*
X1478534Y2617490D01*
X1479534Y2617770D01*
X1480284Y2618143D01*
X1480909Y2618703D01*
X1481159Y2619450D01*
X1480909Y2620197D01*
X1480284Y2620757D01*
X1479534Y2621130D01*
X1478534Y2621410D01*
X1477409Y2621503D01*
X1476284Y2621410D01*
X1475284Y2621130D01*
X1474534Y2620757D01*
X1473909Y2620197D01*
X1473659Y2619450D01*
G01X1481409Y2626950D02*
X1481284Y2626763D01*
X1481034D01*
X1480909Y2626950D01*
X1481034Y2627137D01*
X1481284D01*
X1481409Y2626950D01*
G01X1473659Y2634450D02*
X1473909Y2633703D01*
X1474534Y2633143D01*
X1475284Y2632770D01*
X1476284Y2632490D01*
X1477409Y2632397D01*
X1478534Y2632490D01*
X1479534Y2632770D01*
X1480284Y2633143D01*
X1480909Y2633703D01*
X1481159Y2634450D01*
X1480909Y2635197D01*
X1480284Y2635757D01*
X1479534Y2636130D01*
X1478534Y2636410D01*
X1477409Y2636503D01*
X1476284Y2636410D01*
X1475284Y2636130D01*
X1474534Y2635757D01*
X1473909Y2635197D01*
X1473659Y2634450D01*
G01X1481159Y2641950D02*
X1473659D01*
X1475159Y2640830D01*
G01X1481159D02*
Y2643070D01*
G01Y2649263D02*
X1479534Y2649450D01*
X1478159Y2649730D01*
X1476909Y2650103D01*
X1475534Y2650570D01*
X1473659Y2651317D01*
Y2647583D01*
G01X1481159Y2656763D02*
X1479534Y2656950D01*
X1478159Y2657230D01*
X1476909Y2657603D01*
X1475534Y2658070D01*
X1473659Y2658817D01*
Y2655083D01*
G01X1475284Y2663610D02*
X1473659Y2664077D01*
G01Y2665290D02*
X1475284Y2664823D01*
G01X1483659Y2672417D02*
X1482409Y2673350D01*
X1481159Y2673817D01*
X1476159D01*
X1474909Y2673350D01*
X1473659Y2672417D01*
G01X1481409Y2679450D02*
X1481284Y2679263D01*
X1481034D01*
X1480909Y2679450D01*
X1481034Y2679637D01*
X1481284D01*
X1481409Y2679450D01*
G01X1505856Y-403250D02*
X1493356D01*
X1495856Y-405110D01*
G01X1505856D02*
Y-401390D01*
G01Y-388990D02*
X1493356D01*
X1502314Y-394725D01*
Y-386975D01*
G01X1504398Y-381085D02*
X1505439Y-380000D01*
X1505856Y-378760D01*
X1505439Y-377520D01*
X1504190Y-376435D01*
X1502314Y-375660D01*
X1500439Y-375350D01*
X1498148D01*
X1496273Y-375660D01*
X1494606Y-376435D01*
X1493773Y-377365D01*
X1493356Y-378450D01*
X1493773Y-379690D01*
X1494606Y-380620D01*
X1495856Y-381240D01*
X1497523Y-381550D01*
X1498981Y-381240D01*
X1500439Y-380465D01*
X1501273Y-379535D01*
X1501481Y-378450D01*
X1501065Y-377210D01*
X1500023Y-376280D01*
X1498148Y-375350D01*
G01X1504398Y-368685D02*
X1505439Y-367600D01*
X1505856Y-366360D01*
X1505439Y-365120D01*
X1504190Y-364035D01*
X1502314Y-363260D01*
X1500439Y-362950D01*
X1498148D01*
X1496273Y-363260D01*
X1494606Y-364035D01*
X1493773Y-364965D01*
X1493356Y-366050D01*
X1493773Y-367290D01*
X1494606Y-368220D01*
X1495856Y-368840D01*
X1497523Y-369150D01*
X1498981Y-368840D01*
X1500439Y-368065D01*
X1501273Y-367135D01*
X1501481Y-366050D01*
X1501065Y-364810D01*
X1500023Y-363880D01*
X1498148Y-362950D01*
G01X1500648Y-356595D02*
X1499189Y-355510D01*
X1498356Y-354580D01*
X1497939Y-353340D01*
X1498356Y-352255D01*
X1499189Y-351480D01*
X1500439Y-350860D01*
X1501898Y-350705D01*
X1503148Y-350860D01*
X1504398Y-351480D01*
X1505439Y-352410D01*
X1505856Y-353495D01*
X1505439Y-354735D01*
X1504190Y-355820D01*
X1502314Y-356440D01*
X1500231Y-356595D01*
X1497523Y-356285D01*
X1496064Y-355820D01*
X1494606Y-355045D01*
X1493564Y-353960D01*
X1493356Y-352875D01*
X1493773Y-351790D01*
X1494814Y-351015D01*
G01X1506273Y-341250D02*
X1506064Y-341560D01*
X1505648D01*
X1505439Y-341250D01*
X1505648Y-340940D01*
X1506064D01*
X1506273Y-341250D01*
G01X1493356Y-328850D02*
X1493773Y-330090D01*
X1494814Y-331020D01*
X1496064Y-331640D01*
X1497731Y-332105D01*
X1499606Y-332260D01*
X1501481Y-332105D01*
X1503148Y-331640D01*
X1504398Y-331020D01*
X1505439Y-330090D01*
X1505856Y-328850D01*
X1505439Y-327610D01*
X1504398Y-326680D01*
X1503148Y-326060D01*
X1501481Y-325595D01*
X1499606Y-325440D01*
X1497731Y-325595D01*
X1496064Y-326060D01*
X1494814Y-326680D01*
X1493773Y-327610D01*
X1493356Y-328850D01*
G01X1500648Y-319395D02*
X1499189Y-318310D01*
X1498356Y-317380D01*
X1497939Y-316140D01*
X1498356Y-315055D01*
X1499189Y-314280D01*
X1500439Y-313660D01*
X1501898Y-313505D01*
X1503148Y-313660D01*
X1504398Y-314280D01*
X1505439Y-315210D01*
X1505856Y-316295D01*
X1505439Y-317535D01*
X1504190Y-318620D01*
X1502314Y-319240D01*
X1500231Y-319395D01*
X1497523Y-319085D01*
X1496064Y-318620D01*
X1494606Y-317845D01*
X1493564Y-316760D01*
X1493356Y-315675D01*
X1493773Y-314590D01*
X1494814Y-313815D01*
G01X1503356Y-285260D02*
X1504815Y-284330D01*
X1505648Y-283090D01*
X1505856Y-281695D01*
X1505648Y-280455D01*
X1504606Y-279215D01*
X1503356Y-278440D01*
X1502106Y-278285D01*
X1500648Y-278595D01*
X1499606Y-279680D01*
X1499189Y-280765D01*
Y-282160D01*
G01Y-280765D02*
X1498564Y-279835D01*
X1497523Y-279060D01*
X1496273Y-278750D01*
X1495023Y-279060D01*
X1493981Y-279835D01*
X1493356Y-281230D01*
X1493564Y-282625D01*
X1494398Y-284020D01*
G01X1505856Y-269450D02*
X1505648Y-268365D01*
X1505023Y-267125D01*
X1503981Y-266350D01*
X1502523Y-266040D01*
X1501065Y-266350D01*
X1499814Y-267280D01*
X1499189Y-268675D01*
Y-270225D01*
X1498773Y-271155D01*
X1497731Y-271930D01*
X1496273Y-272240D01*
X1494814Y-271775D01*
X1493773Y-270690D01*
X1493356Y-269450D01*
X1493773Y-268210D01*
X1494814Y-267125D01*
X1496273Y-266660D01*
X1497731Y-266970D01*
X1498773Y-267745D01*
X1499189Y-268675D01*
Y-270225D01*
X1499814Y-271620D01*
X1501065Y-272550D01*
X1502523Y-272860D01*
X1503981Y-272550D01*
X1505023Y-271775D01*
X1505648Y-270535D01*
X1505856Y-269450D01*
G01X1493356Y-257050D02*
X1493773Y-258290D01*
X1494814Y-259220D01*
X1496064Y-259840D01*
X1497731Y-260305D01*
X1499606Y-260460D01*
X1501481Y-260305D01*
X1503148Y-259840D01*
X1504398Y-259220D01*
X1505439Y-258290D01*
X1505856Y-257050D01*
X1505439Y-255810D01*
X1504398Y-254880D01*
X1503148Y-254260D01*
X1501481Y-253795D01*
X1499606Y-253640D01*
X1497731Y-253795D01*
X1496064Y-254260D01*
X1494814Y-254880D01*
X1493773Y-255810D01*
X1493356Y-257050D01*
G01X1506273Y-244650D02*
X1506064Y-244960D01*
X1505648D01*
X1505439Y-244650D01*
X1505648Y-244340D01*
X1506064D01*
X1506273Y-244650D01*
G01X1504398Y-234885D02*
X1505439Y-233800D01*
X1505856Y-232560D01*
X1505439Y-231320D01*
X1504190Y-230235D01*
X1502314Y-229460D01*
X1500439Y-229150D01*
X1498148D01*
X1496273Y-229460D01*
X1494606Y-230235D01*
X1493773Y-231165D01*
X1493356Y-232250D01*
X1493773Y-233490D01*
X1494606Y-234420D01*
X1495856Y-235040D01*
X1497523Y-235350D01*
X1498981Y-235040D01*
X1500439Y-234265D01*
X1501273Y-233335D01*
X1501481Y-232250D01*
X1501065Y-231010D01*
X1500023Y-230080D01*
X1498148Y-229150D01*
G01X1505452Y1672795D02*
G03I-2500J0D01*
G01X1513326Y1676732D02*
G03I-2500J0D01*
G01X1505452Y1686968D02*
G03I-2500J0D01*
G01X1513326Y1690905D02*
G03I-2500J0D01*
G01X1505452Y1701141D02*
G03I-2500J0D01*
G01X1513326Y1705078D02*
G03I-2500J0D01*
G01X1505452Y1715314D02*
G03I-2500J0D01*
G01X1513326Y1719251D02*
G03I-2500J0D01*
G01X1505452Y1729488D02*
G03I-2500J0D01*
G01X1513326Y1733425D02*
G03I-2500J0D01*
G01X1539802Y-414850D02*
X1527302D01*
X1529802Y-416710D01*
G01X1539802D02*
Y-412990D01*
G01X1537927Y-405860D02*
X1538969Y-404930D01*
X1539594Y-403845D01*
X1539802Y-402450D01*
X1539385Y-401055D01*
X1538552Y-399970D01*
X1537094Y-399195D01*
X1535427Y-399040D01*
X1533760Y-399350D01*
X1532719Y-400125D01*
X1531885Y-401210D01*
X1531677Y-402295D01*
X1531885Y-403380D01*
X1532719Y-404775D01*
X1527302Y-404310D01*
Y-400125D01*
G01X1537302Y-393460D02*
X1538761Y-392530D01*
X1539594Y-391290D01*
X1539802Y-389895D01*
X1539594Y-388655D01*
X1538552Y-387415D01*
X1537302Y-386640D01*
X1536052Y-386485D01*
X1534594Y-386795D01*
X1533552Y-387880D01*
X1533135Y-388965D01*
Y-390360D01*
G01Y-388965D02*
X1532510Y-388035D01*
X1531469Y-387260D01*
X1530219Y-386950D01*
X1528969Y-387260D01*
X1527927Y-388035D01*
X1527302Y-389430D01*
X1527510Y-390825D01*
X1528344Y-392220D01*
G01X1537302Y-381060D02*
X1538761Y-380130D01*
X1539594Y-378890D01*
X1539802Y-377495D01*
X1539594Y-376255D01*
X1538552Y-375015D01*
X1537302Y-374240D01*
X1536052Y-374085D01*
X1534594Y-374395D01*
X1533552Y-375480D01*
X1533135Y-376565D01*
Y-377960D01*
G01Y-376565D02*
X1532510Y-375635D01*
X1531469Y-374860D01*
X1530219Y-374550D01*
X1528969Y-374860D01*
X1527927Y-375635D01*
X1527302Y-377030D01*
X1527510Y-378425D01*
X1528344Y-379820D01*
G01X1537927Y-368660D02*
X1538969Y-367730D01*
X1539594Y-366645D01*
X1539802Y-365250D01*
X1539385Y-363855D01*
X1538552Y-362770D01*
X1537094Y-361995D01*
X1535427Y-361840D01*
X1533760Y-362150D01*
X1532719Y-362925D01*
X1531885Y-364010D01*
X1531677Y-365095D01*
X1531885Y-366180D01*
X1532719Y-367575D01*
X1527302Y-367110D01*
Y-362925D01*
G01X1540219Y-352850D02*
X1540010Y-353160D01*
X1539594D01*
X1539385Y-352850D01*
X1539594Y-352540D01*
X1540010D01*
X1540219Y-352850D01*
G01X1537927Y-343860D02*
X1538969Y-342930D01*
X1539594Y-341845D01*
X1539802Y-340450D01*
X1539385Y-339055D01*
X1538552Y-337970D01*
X1537094Y-337195D01*
X1535427Y-337040D01*
X1533760Y-337350D01*
X1532719Y-338125D01*
X1531885Y-339210D01*
X1531677Y-340295D01*
X1531885Y-341380D01*
X1532719Y-342775D01*
X1527302Y-342310D01*
Y-338125D01*
G01X1529385Y-330995D02*
X1528136Y-330065D01*
X1527510Y-328980D01*
X1527302Y-327740D01*
X1527719Y-326190D01*
X1528760Y-325105D01*
X1530010Y-324795D01*
X1531261Y-324950D01*
X1532302Y-325570D01*
X1534385Y-328670D01*
X1535844Y-330065D01*
X1537927Y-330995D01*
X1539802Y-331305D01*
Y-324795D01*
G01X1537302Y-296860D02*
X1538761Y-295930D01*
X1539594Y-294690D01*
X1539802Y-293295D01*
X1539594Y-292055D01*
X1538552Y-290815D01*
X1537302Y-290040D01*
X1536052Y-289885D01*
X1534594Y-290195D01*
X1533552Y-291280D01*
X1533135Y-292365D01*
Y-293760D01*
G01Y-292365D02*
X1532510Y-291435D01*
X1531469Y-290660D01*
X1530219Y-290350D01*
X1528969Y-290660D01*
X1527927Y-291435D01*
X1527302Y-292830D01*
X1527510Y-294225D01*
X1528344Y-295620D01*
G01X1539802Y-281050D02*
X1539594Y-279965D01*
X1538969Y-278725D01*
X1537927Y-277950D01*
X1536469Y-277640D01*
X1535011Y-277950D01*
X1533760Y-278880D01*
X1533135Y-280275D01*
Y-281825D01*
X1532719Y-282755D01*
X1531677Y-283530D01*
X1530219Y-283840D01*
X1528760Y-283375D01*
X1527719Y-282290D01*
X1527302Y-281050D01*
X1527719Y-279810D01*
X1528760Y-278725D01*
X1530219Y-278260D01*
X1531677Y-278570D01*
X1532719Y-279345D01*
X1533135Y-280275D01*
Y-281825D01*
X1533760Y-283220D01*
X1535011Y-284150D01*
X1536469Y-284460D01*
X1537927Y-284150D01*
X1538969Y-283375D01*
X1539594Y-282135D01*
X1539802Y-281050D01*
G01X1538344Y-271285D02*
X1539385Y-270200D01*
X1539802Y-268960D01*
X1539385Y-267720D01*
X1538136Y-266635D01*
X1536260Y-265860D01*
X1534385Y-265550D01*
X1532094D01*
X1530219Y-265860D01*
X1528552Y-266635D01*
X1527719Y-267565D01*
X1527302Y-268650D01*
X1527719Y-269890D01*
X1528552Y-270820D01*
X1529802Y-271440D01*
X1531469Y-271750D01*
X1532927Y-271440D01*
X1534385Y-270665D01*
X1535219Y-269735D01*
X1535427Y-268650D01*
X1535011Y-267410D01*
X1533969Y-266480D01*
X1532094Y-265550D01*
G01X1540219Y-256250D02*
X1540010Y-256560D01*
X1539594D01*
X1539385Y-256250D01*
X1539594Y-255940D01*
X1540010D01*
X1540219Y-256250D01*
G01X1537927Y-247260D02*
X1538969Y-246330D01*
X1539594Y-245245D01*
X1539802Y-243850D01*
X1539385Y-242455D01*
X1538552Y-241370D01*
X1537094Y-240595D01*
X1535427Y-240440D01*
X1533760Y-240750D01*
X1532719Y-241525D01*
X1531885Y-242610D01*
X1531677Y-243695D01*
X1531885Y-244780D01*
X1532719Y-246175D01*
X1527302Y-245710D01*
Y-241525D01*
G01X1529385Y-234395D02*
X1528136Y-233465D01*
X1527510Y-232380D01*
X1527302Y-231140D01*
X1527719Y-229590D01*
X1528760Y-228505D01*
X1530010Y-228195D01*
X1531261Y-228350D01*
X1532302Y-228970D01*
X1534385Y-232070D01*
X1535844Y-233465D01*
X1537927Y-234395D01*
X1539802Y-234705D01*
Y-228195D01*
G01X1521200Y1672795D02*
G03I-2500J0D01*
G01X1529074Y1676732D02*
G03I-2500J0D01*
G01X1521200Y1686968D02*
G03I-2500J0D01*
G01X1529074Y1690905D02*
G03I-2500J0D01*
G01X1521200Y1701141D02*
G03I-2500J0D01*
G01X1529074Y1705078D02*
G03I-2500J0D01*
G01X1521200Y1715314D02*
G03I-2500J0D01*
G01X1529074Y1719251D02*
G03I-2500J0D01*
G01X1521200Y1729488D02*
G03I-2500J0D01*
G01X1529074Y1733425D02*
G03I-2500J0D01*
G01X1536948Y1672795D02*
G03I-2500J0D01*
G01X1544822Y1676732D02*
G03I-2500J0D01*
G01X1536948Y1686968D02*
G03I-2500J0D01*
G01X1544822Y1690905D02*
G03I-2500J0D01*
G01X1536948Y1701141D02*
G03I-2500J0D01*
G01X1544822Y1705078D02*
G03I-2500J0D01*
G01X1536948Y1715314D02*
G03I-2500J0D01*
G01X1544822Y1719251D02*
G03I-2500J0D01*
G01X1536948Y1729488D02*
G03I-2500J0D01*
G01X1544822Y1733425D02*
G03I-2500J0D01*
G01X1568660Y-413300D02*
X1556160D01*
X1558660Y-415160D01*
G01X1568660D02*
Y-411440D01*
G01X1566785Y-404310D02*
X1567827Y-403380D01*
X1568452Y-402295D01*
X1568660Y-400900D01*
X1568243Y-399505D01*
X1567410Y-398420D01*
X1565952Y-397645D01*
X1564285Y-397490D01*
X1562618Y-397800D01*
X1561577Y-398575D01*
X1560743Y-399660D01*
X1560535Y-400745D01*
X1560743Y-401830D01*
X1561577Y-403225D01*
X1556160Y-402760D01*
Y-398575D01*
G01X1566160Y-391910D02*
X1567619Y-390980D01*
X1568452Y-389740D01*
X1568660Y-388345D01*
X1568452Y-387105D01*
X1567410Y-385865D01*
X1566160Y-385090D01*
X1564910Y-384935D01*
X1563452Y-385245D01*
X1562410Y-386330D01*
X1561993Y-387415D01*
Y-388810D01*
G01Y-387415D02*
X1561368Y-386485D01*
X1560327Y-385710D01*
X1559077Y-385400D01*
X1557827Y-385710D01*
X1556785Y-386485D01*
X1556160Y-387880D01*
X1556368Y-389275D01*
X1557202Y-390670D01*
G01X1568660Y-376410D02*
X1565952Y-376100D01*
X1563660Y-375635D01*
X1561577Y-375015D01*
X1559285Y-374240D01*
X1556160Y-373000D01*
Y-379200D01*
G01X1558243Y-366645D02*
X1556994Y-365715D01*
X1556368Y-364630D01*
X1556160Y-363390D01*
X1556577Y-361840D01*
X1557618Y-360755D01*
X1558868Y-360445D01*
X1560119Y-360600D01*
X1561160Y-361220D01*
X1563243Y-364320D01*
X1564702Y-365715D01*
X1566785Y-366645D01*
X1568660Y-366955D01*
Y-360445D01*
G01X1569077Y-351300D02*
X1568868Y-351610D01*
X1568452D01*
X1568243Y-351300D01*
X1568452Y-350990D01*
X1568868D01*
X1569077Y-351300D01*
G01X1568660Y-339210D02*
X1565952Y-338900D01*
X1563660Y-338435D01*
X1561577Y-337815D01*
X1559285Y-337040D01*
X1556160Y-335800D01*
Y-342000D01*
G01X1566785Y-329910D02*
X1567827Y-328980D01*
X1568452Y-327895D01*
X1568660Y-326500D01*
X1568243Y-325105D01*
X1567410Y-324020D01*
X1565952Y-323245D01*
X1564285Y-323090D01*
X1562618Y-323400D01*
X1561577Y-324175D01*
X1560743Y-325260D01*
X1560535Y-326345D01*
X1560743Y-327430D01*
X1561577Y-328825D01*
X1556160Y-328360D01*
Y-324175D01*
G01X1566160Y-295310D02*
X1567619Y-294380D01*
X1568452Y-293140D01*
X1568660Y-291745D01*
X1568452Y-290505D01*
X1567410Y-289265D01*
X1566160Y-288490D01*
X1564910Y-288335D01*
X1563452Y-288645D01*
X1562410Y-289730D01*
X1561993Y-290815D01*
Y-292210D01*
G01Y-290815D02*
X1561368Y-289885D01*
X1560327Y-289110D01*
X1559077Y-288800D01*
X1557827Y-289110D01*
X1556785Y-289885D01*
X1556160Y-291280D01*
X1556368Y-292675D01*
X1557202Y-294070D01*
G01X1567202Y-282135D02*
X1568243Y-281050D01*
X1568660Y-279810D01*
X1568243Y-278570D01*
X1566994Y-277485D01*
X1565118Y-276710D01*
X1563243Y-276400D01*
X1560952D01*
X1559077Y-276710D01*
X1557410Y-277485D01*
X1556577Y-278415D01*
X1556160Y-279500D01*
X1556577Y-280740D01*
X1557410Y-281670D01*
X1558660Y-282290D01*
X1560327Y-282600D01*
X1561785Y-282290D01*
X1563243Y-281515D01*
X1564077Y-280585D01*
X1564285Y-279500D01*
X1563869Y-278260D01*
X1562827Y-277330D01*
X1560952Y-276400D01*
G01X1556160Y-267100D02*
X1556577Y-268340D01*
X1557618Y-269270D01*
X1558868Y-269890D01*
X1560535Y-270355D01*
X1562410Y-270510D01*
X1564285Y-270355D01*
X1565952Y-269890D01*
X1567202Y-269270D01*
X1568243Y-268340D01*
X1568660Y-267100D01*
X1568243Y-265860D01*
X1567202Y-264930D01*
X1565952Y-264310D01*
X1564285Y-263845D01*
X1562410Y-263690D01*
X1560535Y-263845D01*
X1558868Y-264310D01*
X1557618Y-264930D01*
X1556577Y-265860D01*
X1556160Y-267100D01*
G01X1569077Y-254700D02*
X1568868Y-255010D01*
X1568452D01*
X1568243Y-254700D01*
X1568452Y-254390D01*
X1568868D01*
X1569077Y-254700D01*
G01X1568660Y-240440D02*
X1556160D01*
X1565118Y-246175D01*
Y-238425D01*
G01X1568660Y-230210D02*
X1565952Y-229900D01*
X1563660Y-229435D01*
X1561577Y-228815D01*
X1559285Y-228040D01*
X1556160Y-226800D01*
Y-233000D01*
G01X1552696Y1672795D02*
G03I-2500J0D01*
G01X1560570Y1676732D02*
G03I-2500J0D01*
G01X1552696Y1686968D02*
G03I-2500J0D01*
G01X1560570Y1690905D02*
G03I-2500J0D01*
G01X1552696Y1701141D02*
G03I-2500J0D01*
G01X1560570Y1705078D02*
G03I-2500J0D01*
G01X1552696Y1715314D02*
G03I-2500J0D01*
G01X1560570Y1719251D02*
G03I-2500J0D01*
G01X1552696Y1729488D02*
G03I-2500J0D01*
G01X1560570Y1733425D02*
G03I-2500J0D01*
G01X1572382Y1672795D02*
G03I-2500J0D01*
G01Y1686968D02*
G03I-2500J0D01*
G01Y1701141D02*
G03I-2500J0D01*
G01Y1715314D02*
G03I-2500J0D01*
G01Y1729488D02*
G03I-2500J0D01*
G01X1588801Y-414850D02*
X1576301D01*
X1578801Y-416710D01*
G01X1588801D02*
Y-412990D01*
G01X1586926Y-405860D02*
X1587968Y-404930D01*
X1588593Y-403845D01*
X1588801Y-402450D01*
X1588384Y-401055D01*
X1587551Y-399970D01*
X1586093Y-399195D01*
X1584426Y-399040D01*
X1582759Y-399350D01*
X1581718Y-400125D01*
X1580884Y-401210D01*
X1580676Y-402295D01*
X1580884Y-403380D01*
X1581718Y-404775D01*
X1576301Y-404310D01*
Y-400125D01*
G01X1588801Y-390050D02*
X1588593Y-388965D01*
X1587968Y-387725D01*
X1586926Y-386950D01*
X1585468Y-386640D01*
X1584010Y-386950D01*
X1582759Y-387880D01*
X1582134Y-389275D01*
Y-390825D01*
X1581718Y-391755D01*
X1580676Y-392530D01*
X1579218Y-392840D01*
X1577759Y-392375D01*
X1576718Y-391290D01*
X1576301Y-390050D01*
X1576718Y-388810D01*
X1577759Y-387725D01*
X1579218Y-387260D01*
X1580676Y-387570D01*
X1581718Y-388345D01*
X1582134Y-389275D01*
Y-390825D01*
X1582759Y-392220D01*
X1584010Y-393150D01*
X1585468Y-393460D01*
X1586926Y-393150D01*
X1587968Y-392375D01*
X1588593Y-391135D01*
X1588801Y-390050D01*
G01X1578384Y-380595D02*
X1577135Y-379665D01*
X1576509Y-378580D01*
X1576301Y-377340D01*
X1576718Y-375790D01*
X1577759Y-374705D01*
X1579009Y-374395D01*
X1580260Y-374550D01*
X1581301Y-375170D01*
X1583384Y-378270D01*
X1584843Y-379665D01*
X1586926Y-380595D01*
X1588801Y-380905D01*
Y-374395D01*
G01X1586926Y-368660D02*
X1587968Y-367730D01*
X1588593Y-366645D01*
X1588801Y-365250D01*
X1588384Y-363855D01*
X1587551Y-362770D01*
X1586093Y-361995D01*
X1584426Y-361840D01*
X1582759Y-362150D01*
X1581718Y-362925D01*
X1580884Y-364010D01*
X1580676Y-365095D01*
X1580884Y-366180D01*
X1581718Y-367575D01*
X1576301Y-367110D01*
Y-362925D01*
G01X1589218Y-352850D02*
X1589009Y-353160D01*
X1588593D01*
X1588384Y-352850D01*
X1588593Y-352540D01*
X1589009D01*
X1589218Y-352850D01*
G01X1586926Y-343860D02*
X1587968Y-342930D01*
X1588593Y-341845D01*
X1588801Y-340450D01*
X1588384Y-339055D01*
X1587551Y-337970D01*
X1586093Y-337195D01*
X1584426Y-337040D01*
X1582759Y-337350D01*
X1581718Y-338125D01*
X1580884Y-339210D01*
X1580676Y-340295D01*
X1580884Y-341380D01*
X1581718Y-342775D01*
X1576301Y-342310D01*
Y-338125D01*
G01X1588801Y-328050D02*
X1576301D01*
X1578801Y-329910D01*
G01X1588801D02*
Y-326190D01*
G01Y-291590D02*
X1576301D01*
X1585259Y-297325D01*
Y-289575D01*
G01X1576301Y-281050D02*
X1576718Y-282290D01*
X1577759Y-283220D01*
X1579009Y-283840D01*
X1580676Y-284305D01*
X1582551Y-284460D01*
X1584426Y-284305D01*
X1586093Y-283840D01*
X1587343Y-283220D01*
X1588384Y-282290D01*
X1588801Y-281050D01*
X1588384Y-279810D01*
X1587343Y-278880D01*
X1586093Y-278260D01*
X1584426Y-277795D01*
X1582551Y-277640D01*
X1580676Y-277795D01*
X1579009Y-278260D01*
X1577759Y-278880D01*
X1576718Y-279810D01*
X1576301Y-281050D01*
G01X1588801Y-268650D02*
X1576301D01*
X1578801Y-270510D01*
G01X1588801D02*
Y-266790D01*
G01X1589218Y-256250D02*
X1589009Y-256560D01*
X1588593D01*
X1588384Y-256250D01*
X1588593Y-255940D01*
X1589009D01*
X1589218Y-256250D01*
G01X1587343Y-246485D02*
X1588384Y-245400D01*
X1588801Y-244160D01*
X1588384Y-242920D01*
X1587135Y-241835D01*
X1585259Y-241060D01*
X1583384Y-240750D01*
X1581093D01*
X1579218Y-241060D01*
X1577551Y-241835D01*
X1576718Y-242765D01*
X1576301Y-243850D01*
X1576718Y-245090D01*
X1577551Y-246020D01*
X1578801Y-246640D01*
X1580468Y-246950D01*
X1581926Y-246640D01*
X1583384Y-245865D01*
X1584218Y-244935D01*
X1584426Y-243850D01*
X1584010Y-242610D01*
X1582968Y-241680D01*
X1581093Y-240750D01*
G01X1588801Y-231760D02*
X1586093Y-231450D01*
X1583801Y-230985D01*
X1581718Y-230365D01*
X1579426Y-229590D01*
X1576301Y-228350D01*
Y-234550D01*
G01X1588130Y1672795D02*
G03I-2500J0D01*
G01Y1686968D02*
G03I-2500J0D01*
G01X1580256Y1676732D02*
G03I-2500J0D01*
G01X1588130Y1701141D02*
G03I-2500J0D01*
G01X1580256Y1690905D02*
G03I-2500J0D01*
G01X1588130Y1715314D02*
G03I-2500J0D01*
G01X1580256Y1705078D02*
G03I-2500J0D01*
G01X1588130Y1729488D02*
G03I-2500J0D01*
G01X1580256Y1719251D02*
G03I-2500J0D01*
G01Y1733425D02*
G03I-2500J0D01*
G01X1603878Y1672795D02*
G03I-2500J0D01*
G01X1596004Y1676732D02*
G03I-2500J0D01*
G01X1603878Y1686968D02*
G03I-2500J0D01*
G01X1596004Y1690905D02*
G03I-2500J0D01*
G01X1603878Y1701141D02*
G03I-2500J0D01*
G01X1596004Y1705078D02*
G03I-2500J0D01*
G01X1603878Y1715314D02*
G03I-2500J0D01*
G01X1596004Y1719251D02*
G03I-2500J0D01*
G01X1603878Y1729488D02*
G03I-2500J0D01*
G01X1596004Y1733425D02*
G03I-2500J0D01*
G01X1619626Y1672795D02*
G03I-2500J0D01*
G01X1611752Y1676732D02*
G03I-2500J0D01*
G01X1619626Y1686968D02*
G03I-2500J0D01*
G01X1611752Y1690905D02*
G03I-2500J0D01*
G01X1619626Y1701141D02*
G03I-2500J0D01*
G01X1611752Y1705078D02*
G03I-2500J0D01*
G01X1619626Y1715314D02*
G03I-2500J0D01*
G01X1611752Y1719251D02*
G03I-2500J0D01*
G01X1619626Y1729488D02*
G03I-2500J0D01*
G01X1611752Y1733425D02*
G03I-2500J0D01*
G01X1635982Y-415620D02*
X1623482D01*
X1625982Y-417480D01*
G01X1635982D02*
Y-413760D01*
G01X1630774Y-406165D02*
X1629315Y-405080D01*
X1628482Y-404150D01*
X1628065Y-402910D01*
X1628482Y-401825D01*
X1629315Y-401050D01*
X1630565Y-400430D01*
X1632024Y-400275D01*
X1633274Y-400430D01*
X1634524Y-401050D01*
X1635565Y-401980D01*
X1635982Y-403065D01*
X1635565Y-404305D01*
X1634316Y-405390D01*
X1632440Y-406010D01*
X1630357Y-406165D01*
X1627649Y-405855D01*
X1626190Y-405390D01*
X1624732Y-404615D01*
X1623690Y-403530D01*
X1623482Y-402445D01*
X1623899Y-401360D01*
X1624940Y-400585D01*
G01X1625565Y-393765D02*
X1624316Y-392835D01*
X1623690Y-391750D01*
X1623482Y-390510D01*
X1623899Y-388960D01*
X1624940Y-387875D01*
X1626190Y-387565D01*
X1627441Y-387720D01*
X1628482Y-388340D01*
X1630565Y-391440D01*
X1632024Y-392835D01*
X1634107Y-393765D01*
X1635982Y-394075D01*
Y-387565D01*
G01X1634524Y-381055D02*
X1635565Y-379970D01*
X1635982Y-378730D01*
X1635565Y-377490D01*
X1634316Y-376405D01*
X1632440Y-375630D01*
X1630565Y-375320D01*
X1628274D01*
X1626399Y-375630D01*
X1624732Y-376405D01*
X1623899Y-377335D01*
X1623482Y-378420D01*
X1623899Y-379660D01*
X1624732Y-380590D01*
X1625982Y-381210D01*
X1627649Y-381520D01*
X1629107Y-381210D01*
X1630565Y-380435D01*
X1631399Y-379505D01*
X1631607Y-378420D01*
X1631191Y-377180D01*
X1630149Y-376250D01*
X1628274Y-375320D01*
G01X1635982Y-366330D02*
X1633274Y-366020D01*
X1630982Y-365555D01*
X1628899Y-364935D01*
X1626607Y-364160D01*
X1623482Y-362920D01*
Y-369120D01*
G01X1636399Y-353620D02*
X1636190Y-353930D01*
X1635774D01*
X1635565Y-353620D01*
X1635774Y-353310D01*
X1636190D01*
X1636399Y-353620D01*
G01X1633482Y-344630D02*
X1634941Y-343700D01*
X1635774Y-342460D01*
X1635982Y-341065D01*
X1635774Y-339825D01*
X1634732Y-338585D01*
X1633482Y-337810D01*
X1632232Y-337655D01*
X1630774Y-337965D01*
X1629732Y-339050D01*
X1629315Y-340135D01*
Y-341530D01*
G01Y-340135D02*
X1628690Y-339205D01*
X1627649Y-338430D01*
X1626399Y-338120D01*
X1625149Y-338430D01*
X1624107Y-339205D01*
X1623482Y-340600D01*
X1623690Y-341995D01*
X1624524Y-343390D01*
G01X1625565Y-331765D02*
X1624316Y-330835D01*
X1623690Y-329750D01*
X1623482Y-328510D01*
X1623899Y-326960D01*
X1624940Y-325875D01*
X1626190Y-325565D01*
X1627441Y-325720D01*
X1628482Y-326340D01*
X1630565Y-329440D01*
X1632024Y-330835D01*
X1634107Y-331765D01*
X1635982Y-332075D01*
Y-325565D01*
G01Y-292360D02*
X1623482D01*
X1632440Y-298095D01*
Y-290345D01*
G01X1635982Y-281820D02*
X1623482D01*
X1625982Y-283680D01*
G01X1635982D02*
Y-279960D01*
G01X1633482Y-272830D02*
X1634941Y-271900D01*
X1635774Y-270660D01*
X1635982Y-269265D01*
X1635774Y-268025D01*
X1634732Y-266785D01*
X1633482Y-266010D01*
X1632232Y-265855D01*
X1630774Y-266165D01*
X1629732Y-267250D01*
X1629315Y-268335D01*
Y-269730D01*
G01Y-268335D02*
X1628690Y-267405D01*
X1627649Y-266630D01*
X1626399Y-266320D01*
X1625149Y-266630D01*
X1624107Y-267405D01*
X1623482Y-268800D01*
X1623690Y-270195D01*
X1624524Y-271590D01*
G01X1636399Y-257020D02*
X1636190Y-257330D01*
X1635774D01*
X1635565Y-257020D01*
X1635774Y-256710D01*
X1636190D01*
X1636399Y-257020D01*
G01X1634524Y-247255D02*
X1635565Y-246170D01*
X1635982Y-244930D01*
X1635565Y-243690D01*
X1634316Y-242605D01*
X1632440Y-241830D01*
X1630565Y-241520D01*
X1628274D01*
X1626399Y-241830D01*
X1624732Y-242605D01*
X1623899Y-243535D01*
X1623482Y-244620D01*
X1623899Y-245860D01*
X1624732Y-246790D01*
X1625982Y-247410D01*
X1627649Y-247720D01*
X1629107Y-247410D01*
X1630565Y-246635D01*
X1631399Y-245705D01*
X1631607Y-244620D01*
X1631191Y-243380D01*
X1630149Y-242450D01*
X1628274Y-241520D01*
G01X1634107Y-235630D02*
X1635149Y-234700D01*
X1635774Y-233615D01*
X1635982Y-232220D01*
X1635565Y-230825D01*
X1634732Y-229740D01*
X1633274Y-228965D01*
X1631607Y-228810D01*
X1629940Y-229120D01*
X1628899Y-229895D01*
X1628065Y-230980D01*
X1627857Y-232065D01*
X1628065Y-233150D01*
X1628899Y-234545D01*
X1623482Y-234080D01*
Y-229895D01*
G01X1627500Y1676732D02*
G03I-2500J0D01*
G01Y1690905D02*
G03I-2500J0D01*
G01Y1705078D02*
G03I-2500J0D01*
G01Y1719251D02*
G03I-2500J0D01*
G01Y1733425D02*
G03I-2500J0D01*
G01X1671140Y-414080D02*
X1658640D01*
X1661140Y-415940D01*
G01X1671140D02*
Y-412220D01*
G01X1665932Y-404625D02*
X1664473Y-403540D01*
X1663640Y-402610D01*
X1663223Y-401370D01*
X1663640Y-400285D01*
X1664473Y-399510D01*
X1665723Y-398890D01*
X1667182Y-398735D01*
X1668432Y-398890D01*
X1669682Y-399510D01*
X1670723Y-400440D01*
X1671140Y-401525D01*
X1670723Y-402765D01*
X1669474Y-403850D01*
X1667598Y-404470D01*
X1665515Y-404625D01*
X1662807Y-404315D01*
X1661348Y-403850D01*
X1659890Y-403075D01*
X1658848Y-401990D01*
X1658640Y-400905D01*
X1659057Y-399820D01*
X1660098Y-399045D01*
G01X1665932Y-392225D02*
X1664473Y-391140D01*
X1663640Y-390210D01*
X1663223Y-388970D01*
X1663640Y-387885D01*
X1664473Y-387110D01*
X1665723Y-386490D01*
X1667182Y-386335D01*
X1668432Y-386490D01*
X1669682Y-387110D01*
X1670723Y-388040D01*
X1671140Y-389125D01*
X1670723Y-390365D01*
X1669474Y-391450D01*
X1667598Y-392070D01*
X1665515Y-392225D01*
X1662807Y-391915D01*
X1661348Y-391450D01*
X1659890Y-390675D01*
X1658848Y-389590D01*
X1658640Y-388505D01*
X1659057Y-387420D01*
X1660098Y-386645D01*
G01X1671140Y-375020D02*
X1658640D01*
X1667598Y-380755D01*
Y-373005D01*
G01X1671140Y-364480D02*
X1670932Y-363395D01*
X1670307Y-362155D01*
X1669265Y-361380D01*
X1667807Y-361070D01*
X1666349Y-361380D01*
X1665098Y-362310D01*
X1664473Y-363705D01*
Y-365255D01*
X1664057Y-366185D01*
X1663015Y-366960D01*
X1661557Y-367270D01*
X1660098Y-366805D01*
X1659057Y-365720D01*
X1658640Y-364480D01*
X1659057Y-363240D01*
X1660098Y-362155D01*
X1661557Y-361690D01*
X1663015Y-362000D01*
X1664057Y-362775D01*
X1664473Y-363705D01*
Y-365255D01*
X1665098Y-366650D01*
X1666349Y-367580D01*
X1667807Y-367890D01*
X1669265Y-367580D01*
X1670307Y-366805D01*
X1670932Y-365565D01*
X1671140Y-364480D01*
G01X1671557Y-352080D02*
X1671348Y-352390D01*
X1670932D01*
X1670723Y-352080D01*
X1670932Y-351770D01*
X1671348D01*
X1671557Y-352080D01*
G01X1669682Y-342315D02*
X1670723Y-341230D01*
X1671140Y-339990D01*
X1670723Y-338750D01*
X1669474Y-337665D01*
X1667598Y-336890D01*
X1665723Y-336580D01*
X1663432D01*
X1661557Y-336890D01*
X1659890Y-337665D01*
X1659057Y-338595D01*
X1658640Y-339680D01*
X1659057Y-340920D01*
X1659890Y-341850D01*
X1661140Y-342470D01*
X1662807Y-342780D01*
X1664265Y-342470D01*
X1665723Y-341695D01*
X1666557Y-340765D01*
X1666765Y-339680D01*
X1666349Y-338440D01*
X1665307Y-337510D01*
X1663432Y-336580D01*
G01X1658640Y-327280D02*
X1659057Y-328520D01*
X1660098Y-329450D01*
X1661348Y-330070D01*
X1663015Y-330535D01*
X1664890Y-330690D01*
X1666765Y-330535D01*
X1668432Y-330070D01*
X1669682Y-329450D01*
X1670723Y-328520D01*
X1671140Y-327280D01*
X1670723Y-326040D01*
X1669682Y-325110D01*
X1668432Y-324490D01*
X1666765Y-324025D01*
X1664890Y-323870D01*
X1663015Y-324025D01*
X1661348Y-324490D01*
X1660098Y-325110D01*
X1659057Y-326040D01*
X1658640Y-327280D01*
G01X1671140Y-290820D02*
X1658640D01*
X1667598Y-296555D01*
Y-288805D01*
G01X1660723Y-283225D02*
X1659474Y-282295D01*
X1658848Y-281210D01*
X1658640Y-279970D01*
X1659057Y-278420D01*
X1660098Y-277335D01*
X1661348Y-277025D01*
X1662599Y-277180D01*
X1663640Y-277800D01*
X1665723Y-280900D01*
X1667182Y-282295D01*
X1669265Y-283225D01*
X1671140Y-283535D01*
Y-277025D01*
G01X1660723Y-270825D02*
X1659474Y-269895D01*
X1658848Y-268810D01*
X1658640Y-267570D01*
X1659057Y-266020D01*
X1660098Y-264935D01*
X1661348Y-264625D01*
X1662599Y-264780D01*
X1663640Y-265400D01*
X1665723Y-268500D01*
X1667182Y-269895D01*
X1669265Y-270825D01*
X1671140Y-271135D01*
Y-264625D01*
G01X1671557Y-255480D02*
X1671348Y-255790D01*
X1670932D01*
X1670723Y-255480D01*
X1670932Y-255170D01*
X1671348D01*
X1671557Y-255480D01*
G01X1671140Y-243080D02*
X1670932Y-241995D01*
X1670307Y-240755D01*
X1669265Y-239980D01*
X1667807Y-239670D01*
X1666349Y-239980D01*
X1665098Y-240910D01*
X1664473Y-242305D01*
Y-243855D01*
X1664057Y-244785D01*
X1663015Y-245560D01*
X1661557Y-245870D01*
X1660098Y-245405D01*
X1659057Y-244320D01*
X1658640Y-243080D01*
X1659057Y-241840D01*
X1660098Y-240755D01*
X1661557Y-240290D01*
X1663015Y-240600D01*
X1664057Y-241375D01*
X1664473Y-242305D01*
Y-243855D01*
X1665098Y-245250D01*
X1666349Y-246180D01*
X1667807Y-246490D01*
X1669265Y-246180D01*
X1670307Y-245405D01*
X1670932Y-244165D01*
X1671140Y-243080D01*
G01Y-230680D02*
X1670932Y-229595D01*
X1670307Y-228355D01*
X1669265Y-227580D01*
X1667807Y-227270D01*
X1666349Y-227580D01*
X1665098Y-228510D01*
X1664473Y-229905D01*
Y-231455D01*
X1664057Y-232385D01*
X1663015Y-233160D01*
X1661557Y-233470D01*
X1660098Y-233005D01*
X1659057Y-231920D01*
X1658640Y-230680D01*
X1659057Y-229440D01*
X1660098Y-228355D01*
X1661557Y-227890D01*
X1663015Y-228200D01*
X1664057Y-228975D01*
X1664473Y-229905D01*
Y-231455D01*
X1665098Y-232850D01*
X1666349Y-233780D01*
X1667807Y-234090D01*
X1669265Y-233780D01*
X1670307Y-233005D01*
X1670932Y-231765D01*
X1671140Y-230680D01*
G01X1703440Y225890D02*
Y233890D01*
X1708040Y225890D01*
Y233890D01*
G01X1711740Y225890D02*
Y233890D01*
X1714140D01*
X1714940Y233490D01*
X1715540Y232557D01*
X1715740Y231490D01*
X1715540Y230423D01*
X1715040Y229623D01*
X1714140Y229223D01*
X1711740D01*
G01X1721740Y233890D02*
Y225890D01*
G01X1719440Y233890D02*
X1724040D01*
G01X1727640Y225890D02*
Y233890D01*
G01X1731840D02*
Y225890D01*
G01Y229890D02*
X1727640D01*
G01X1743610Y-397890D02*
X1731110D01*
X1733610Y-399750D01*
G01X1743610D02*
Y-396030D01*
G01Y-385800D02*
X1740902Y-385490D01*
X1738610Y-385025D01*
X1736527Y-384405D01*
X1734235Y-383630D01*
X1731110Y-382390D01*
Y-388590D01*
G01X1741110Y-376500D02*
X1742569Y-375570D01*
X1743402Y-374330D01*
X1743610Y-372935D01*
X1743402Y-371695D01*
X1742360Y-370455D01*
X1741110Y-369680D01*
X1739860Y-369525D01*
X1738402Y-369835D01*
X1737360Y-370920D01*
X1736943Y-372005D01*
Y-373400D01*
G01Y-372005D02*
X1736318Y-371075D01*
X1735277Y-370300D01*
X1734027Y-369990D01*
X1732777Y-370300D01*
X1731735Y-371075D01*
X1731110Y-372470D01*
X1731318Y-373865D01*
X1732152Y-375260D01*
G01X1742152Y-363325D02*
X1743193Y-362240D01*
X1743610Y-361000D01*
X1743193Y-359760D01*
X1741944Y-358675D01*
X1740068Y-357900D01*
X1738193Y-357590D01*
X1735902D01*
X1734027Y-357900D01*
X1732360Y-358675D01*
X1731527Y-359605D01*
X1731110Y-360690D01*
X1731527Y-361930D01*
X1732360Y-362860D01*
X1733610Y-363480D01*
X1735277Y-363790D01*
X1736735Y-363480D01*
X1738193Y-362705D01*
X1739027Y-361775D01*
X1739235Y-360690D01*
X1738819Y-359450D01*
X1737777Y-358520D01*
X1735902Y-357590D01*
G01X1742152Y-350925D02*
X1743193Y-349840D01*
X1743610Y-348600D01*
X1743193Y-347360D01*
X1741944Y-346275D01*
X1740068Y-345500D01*
X1738193Y-345190D01*
X1735902D01*
X1734027Y-345500D01*
X1732360Y-346275D01*
X1731527Y-347205D01*
X1731110Y-348290D01*
X1731527Y-349530D01*
X1732360Y-350460D01*
X1733610Y-351080D01*
X1735277Y-351390D01*
X1736735Y-351080D01*
X1738193Y-350305D01*
X1739027Y-349375D01*
X1739235Y-348290D01*
X1738819Y-347050D01*
X1737777Y-346120D01*
X1735902Y-345190D01*
G01X1744027Y-335890D02*
X1743818Y-336200D01*
X1743402D01*
X1743193Y-335890D01*
X1743402Y-335580D01*
X1743818D01*
X1744027Y-335890D01*
G01X1738402Y-326435D02*
X1736943Y-325350D01*
X1736110Y-324420D01*
X1735693Y-323180D01*
X1736110Y-322095D01*
X1736943Y-321320D01*
X1738193Y-320700D01*
X1739652Y-320545D01*
X1740902Y-320700D01*
X1742152Y-321320D01*
X1743193Y-322250D01*
X1743610Y-323335D01*
X1743193Y-324575D01*
X1741944Y-325660D01*
X1740068Y-326280D01*
X1737985Y-326435D01*
X1735277Y-326125D01*
X1733818Y-325660D01*
X1732360Y-324885D01*
X1731318Y-323800D01*
X1731110Y-322715D01*
X1731527Y-321630D01*
X1732568Y-320855D01*
G01X1743610Y-311090D02*
X1743402Y-310005D01*
X1742777Y-308765D01*
X1741735Y-307990D01*
X1740277Y-307680D01*
X1738819Y-307990D01*
X1737568Y-308920D01*
X1736943Y-310315D01*
Y-311865D01*
X1736527Y-312795D01*
X1735485Y-313570D01*
X1734027Y-313880D01*
X1732568Y-313415D01*
X1731527Y-312330D01*
X1731110Y-311090D01*
X1731527Y-309850D01*
X1732568Y-308765D01*
X1734027Y-308300D01*
X1735485Y-308610D01*
X1736527Y-309385D01*
X1736943Y-310315D01*
Y-311865D01*
X1737568Y-313260D01*
X1738819Y-314190D01*
X1740277Y-314500D01*
X1741735Y-314190D01*
X1742777Y-313415D01*
X1743402Y-312175D01*
X1743610Y-311090D01*
G01Y-274630D02*
X1731110D01*
X1740068Y-280365D01*
Y-272615D01*
G01X1743610Y-262230D02*
X1731110D01*
X1740068Y-267965D01*
Y-260215D01*
G01X1743610Y-251690D02*
X1731110D01*
X1733610Y-253550D01*
G01X1743610D02*
Y-249830D01*
G01X1744027Y-239290D02*
X1743818Y-239600D01*
X1743402D01*
X1743193Y-239290D01*
X1743402Y-238980D01*
X1743818D01*
X1744027Y-239290D01*
G01X1742152Y-229525D02*
X1743193Y-228440D01*
X1743610Y-227200D01*
X1743193Y-225960D01*
X1741944Y-224875D01*
X1740068Y-224100D01*
X1738193Y-223790D01*
X1735902D01*
X1734027Y-224100D01*
X1732360Y-224875D01*
X1731527Y-225805D01*
X1731110Y-226890D01*
X1731527Y-228130D01*
X1732360Y-229060D01*
X1733610Y-229680D01*
X1735277Y-229990D01*
X1736735Y-229680D01*
X1738193Y-228905D01*
X1739027Y-227975D01*
X1739235Y-226890D01*
X1738819Y-225650D01*
X1737777Y-224720D01*
X1735902Y-223790D01*
G01X1741735Y-217900D02*
X1742777Y-216970D01*
X1743402Y-215885D01*
X1743610Y-214490D01*
X1743193Y-213095D01*
X1742360Y-212010D01*
X1740902Y-211235D01*
X1739235Y-211080D01*
X1737568Y-211390D01*
X1736527Y-212165D01*
X1735693Y-213250D01*
X1735485Y-214335D01*
X1735693Y-215420D01*
X1736527Y-216815D01*
X1731110Y-216350D01*
Y-212165D01*
G01X1768270Y-397510D02*
X1755770D01*
X1758270Y-399370D01*
G01X1768270D02*
Y-395650D01*
G01Y-385420D02*
X1765562Y-385110D01*
X1763270Y-384645D01*
X1761187Y-384025D01*
X1758895Y-383250D01*
X1755770Y-382010D01*
Y-388210D01*
G01X1763062Y-375655D02*
X1761603Y-374570D01*
X1760770Y-373640D01*
X1760353Y-372400D01*
X1760770Y-371315D01*
X1761603Y-370540D01*
X1762853Y-369920D01*
X1764312Y-369765D01*
X1765562Y-369920D01*
X1766812Y-370540D01*
X1767853Y-371470D01*
X1768270Y-372555D01*
X1767853Y-373795D01*
X1766604Y-374880D01*
X1764728Y-375500D01*
X1762645Y-375655D01*
X1759937Y-375345D01*
X1758478Y-374880D01*
X1757020Y-374105D01*
X1755978Y-373020D01*
X1755770Y-371935D01*
X1756187Y-370850D01*
X1757228Y-370075D01*
G01X1768270Y-360310D02*
X1755770D01*
X1758270Y-362170D01*
G01X1768270D02*
Y-358450D01*
G01X1766395Y-351320D02*
X1767437Y-350390D01*
X1768062Y-349305D01*
X1768270Y-347910D01*
X1767853Y-346515D01*
X1767020Y-345430D01*
X1765562Y-344655D01*
X1763895Y-344500D01*
X1762228Y-344810D01*
X1761187Y-345585D01*
X1760353Y-346670D01*
X1760145Y-347755D01*
X1760353Y-348840D01*
X1761187Y-350235D01*
X1755770Y-349770D01*
Y-345585D01*
G01X1768687Y-335510D02*
X1768478Y-335820D01*
X1768062D01*
X1767853Y-335510D01*
X1768062Y-335200D01*
X1768478D01*
X1768687Y-335510D01*
G01X1768270Y-323420D02*
X1765562Y-323110D01*
X1763270Y-322645D01*
X1761187Y-322025D01*
X1758895Y-321250D01*
X1755770Y-320010D01*
Y-326210D01*
G01X1766395Y-314120D02*
X1767437Y-313190D01*
X1768062Y-312105D01*
X1768270Y-310710D01*
X1767853Y-309315D01*
X1767020Y-308230D01*
X1765562Y-307455D01*
X1763895Y-307300D01*
X1762228Y-307610D01*
X1761187Y-308385D01*
X1760353Y-309470D01*
X1760145Y-310555D01*
X1760353Y-311640D01*
X1761187Y-313035D01*
X1755770Y-312570D01*
Y-308385D01*
G01X1768270Y-274250D02*
X1755770D01*
X1764728Y-279985D01*
Y-272235D01*
G01X1768270Y-261850D02*
X1755770D01*
X1764728Y-267585D01*
Y-259835D01*
G01X1768270Y-251620D02*
X1765562Y-251310D01*
X1763270Y-250845D01*
X1761187Y-250225D01*
X1758895Y-249450D01*
X1755770Y-248210D01*
Y-254410D01*
G01X1768687Y-238910D02*
X1768478Y-239220D01*
X1768062D01*
X1767853Y-238910D01*
X1768062Y-238600D01*
X1768478D01*
X1768687Y-238910D01*
G01X1768270Y-224650D02*
X1755770D01*
X1764728Y-230385D01*
Y-222635D01*
G01X1768270Y-212250D02*
X1755770D01*
X1764728Y-217985D01*
Y-210235D01*
G01X1792160Y-390530D02*
X1779660D01*
X1782160Y-392390D01*
G01X1792160D02*
Y-388670D01*
G01Y-378440D02*
X1789452Y-378130D01*
X1787160Y-377665D01*
X1785077Y-377045D01*
X1782785Y-376270D01*
X1779660Y-375030D01*
Y-381230D01*
G01X1786952Y-368675D02*
X1785493Y-367590D01*
X1784660Y-366660D01*
X1784243Y-365420D01*
X1784660Y-364335D01*
X1785493Y-363560D01*
X1786743Y-362940D01*
X1788202Y-362785D01*
X1789452Y-362940D01*
X1790702Y-363560D01*
X1791743Y-364490D01*
X1792160Y-365575D01*
X1791743Y-366815D01*
X1790494Y-367900D01*
X1788618Y-368520D01*
X1786535Y-368675D01*
X1783827Y-368365D01*
X1782368Y-367900D01*
X1780910Y-367125D01*
X1779868Y-366040D01*
X1779660Y-364955D01*
X1780077Y-363870D01*
X1781118Y-363095D01*
G01X1786952Y-356275D02*
X1785493Y-355190D01*
X1784660Y-354260D01*
X1784243Y-353020D01*
X1784660Y-351935D01*
X1785493Y-351160D01*
X1786743Y-350540D01*
X1788202Y-350385D01*
X1789452Y-350540D01*
X1790702Y-351160D01*
X1791743Y-352090D01*
X1792160Y-353175D01*
X1791743Y-354415D01*
X1790494Y-355500D01*
X1788618Y-356120D01*
X1786535Y-356275D01*
X1783827Y-355965D01*
X1782368Y-355500D01*
X1780910Y-354725D01*
X1779868Y-353640D01*
X1779660Y-352555D01*
X1780077Y-351470D01*
X1781118Y-350695D01*
G01X1790702Y-343565D02*
X1791743Y-342480D01*
X1792160Y-341240D01*
X1791743Y-340000D01*
X1790494Y-338915D01*
X1788618Y-338140D01*
X1786743Y-337830D01*
X1784452D01*
X1782577Y-338140D01*
X1780910Y-338915D01*
X1780077Y-339845D01*
X1779660Y-340930D01*
X1780077Y-342170D01*
X1780910Y-343100D01*
X1782160Y-343720D01*
X1783827Y-344030D01*
X1785285Y-343720D01*
X1786743Y-342945D01*
X1787577Y-342015D01*
X1787785Y-340930D01*
X1787369Y-339690D01*
X1786327Y-338760D01*
X1784452Y-337830D01*
G01X1792577Y-328530D02*
X1792368Y-328840D01*
X1791952D01*
X1791743Y-328530D01*
X1791952Y-328220D01*
X1792368D01*
X1792577Y-328530D01*
G01X1781743Y-319075D02*
X1780494Y-318145D01*
X1779868Y-317060D01*
X1779660Y-315820D01*
X1780077Y-314270D01*
X1781118Y-313185D01*
X1782368Y-312875D01*
X1783619Y-313030D01*
X1784660Y-313650D01*
X1786743Y-316750D01*
X1788202Y-318145D01*
X1790285Y-319075D01*
X1792160Y-319385D01*
Y-312875D01*
G01X1790702Y-306365D02*
X1791743Y-305280D01*
X1792160Y-304040D01*
X1791743Y-302800D01*
X1790494Y-301715D01*
X1788618Y-300940D01*
X1786743Y-300630D01*
X1784452D01*
X1782577Y-300940D01*
X1780910Y-301715D01*
X1780077Y-302645D01*
X1779660Y-303730D01*
X1780077Y-304970D01*
X1780910Y-305900D01*
X1782160Y-306520D01*
X1783827Y-306830D01*
X1785285Y-306520D01*
X1786743Y-305745D01*
X1787577Y-304815D01*
X1787785Y-303730D01*
X1787369Y-302490D01*
X1786327Y-301560D01*
X1784452Y-300630D01*
G01X1792160Y-267270D02*
X1779660D01*
X1788618Y-273005D01*
Y-265255D01*
G01X1792160Y-254870D02*
X1779660D01*
X1788618Y-260605D01*
Y-252855D01*
G01X1792160Y-244330D02*
X1791952Y-243245D01*
X1791327Y-242005D01*
X1790285Y-241230D01*
X1788827Y-240920D01*
X1787369Y-241230D01*
X1786118Y-242160D01*
X1785493Y-243555D01*
Y-245105D01*
X1785077Y-246035D01*
X1784035Y-246810D01*
X1782577Y-247120D01*
X1781118Y-246655D01*
X1780077Y-245570D01*
X1779660Y-244330D01*
X1780077Y-243090D01*
X1781118Y-242005D01*
X1782577Y-241540D01*
X1784035Y-241850D01*
X1785077Y-242625D01*
X1785493Y-243555D01*
Y-245105D01*
X1786118Y-246500D01*
X1787369Y-247430D01*
X1788827Y-247740D01*
X1790285Y-247430D01*
X1791327Y-246655D01*
X1791952Y-245415D01*
X1792160Y-244330D01*
G01X1792577Y-231930D02*
X1792368Y-232240D01*
X1791952D01*
X1791743Y-231930D01*
X1791952Y-231620D01*
X1792368D01*
X1792577Y-231930D01*
G01X1792160Y-219530D02*
X1791952Y-218445D01*
X1791327Y-217205D01*
X1790285Y-216430D01*
X1788827Y-216120D01*
X1787369Y-216430D01*
X1786118Y-217360D01*
X1785493Y-218755D01*
Y-220305D01*
X1785077Y-221235D01*
X1784035Y-222010D01*
X1782577Y-222320D01*
X1781118Y-221855D01*
X1780077Y-220770D01*
X1779660Y-219530D01*
X1780077Y-218290D01*
X1781118Y-217205D01*
X1782577Y-216740D01*
X1784035Y-217050D01*
X1785077Y-217825D01*
X1785493Y-218755D01*
Y-220305D01*
X1786118Y-221700D01*
X1787369Y-222630D01*
X1788827Y-222940D01*
X1790285Y-222630D01*
X1791327Y-221855D01*
X1791952Y-220615D01*
X1792160Y-219530D01*
G01X1814130Y-388220D02*
X1801630D01*
X1804130Y-390080D01*
G01X1814130D02*
Y-386360D01*
G01Y-375820D02*
X1813922Y-374735D01*
X1813297Y-373495D01*
X1812255Y-372720D01*
X1810797Y-372410D01*
X1809339Y-372720D01*
X1808088Y-373650D01*
X1807463Y-375045D01*
Y-376595D01*
X1807047Y-377525D01*
X1806005Y-378300D01*
X1804547Y-378610D01*
X1803088Y-378145D01*
X1802047Y-377060D01*
X1801630Y-375820D01*
X1802047Y-374580D01*
X1803088Y-373495D01*
X1804547Y-373030D01*
X1806005Y-373340D01*
X1807047Y-374115D01*
X1807463Y-375045D01*
Y-376595D01*
X1808088Y-377990D01*
X1809339Y-378920D01*
X1810797Y-379230D01*
X1812255Y-378920D01*
X1813297Y-378145D01*
X1813922Y-376905D01*
X1814130Y-375820D01*
G01X1801630Y-363420D02*
X1802047Y-364660D01*
X1803088Y-365590D01*
X1804338Y-366210D01*
X1806005Y-366675D01*
X1807880Y-366830D01*
X1809755Y-366675D01*
X1811422Y-366210D01*
X1812672Y-365590D01*
X1813713Y-364660D01*
X1814130Y-363420D01*
X1813713Y-362180D01*
X1812672Y-361250D01*
X1811422Y-360630D01*
X1809755Y-360165D01*
X1807880Y-360010D01*
X1806005Y-360165D01*
X1804338Y-360630D01*
X1803088Y-361250D01*
X1802047Y-362180D01*
X1801630Y-363420D01*
G01X1808922Y-353965D02*
X1807463Y-352880D01*
X1806630Y-351950D01*
X1806213Y-350710D01*
X1806630Y-349625D01*
X1807463Y-348850D01*
X1808713Y-348230D01*
X1810172Y-348075D01*
X1811422Y-348230D01*
X1812672Y-348850D01*
X1813713Y-349780D01*
X1814130Y-350865D01*
X1813713Y-352105D01*
X1812464Y-353190D01*
X1810588Y-353810D01*
X1808505Y-353965D01*
X1805797Y-353655D01*
X1804338Y-353190D01*
X1802880Y-352415D01*
X1801838Y-351330D01*
X1801630Y-350245D01*
X1802047Y-349160D01*
X1803088Y-348385D01*
G01X1803713Y-341565D02*
X1802464Y-340635D01*
X1801838Y-339550D01*
X1801630Y-338310D01*
X1802047Y-336760D01*
X1803088Y-335675D01*
X1804338Y-335365D01*
X1805589Y-335520D01*
X1806630Y-336140D01*
X1808713Y-339240D01*
X1810172Y-340635D01*
X1812255Y-341565D01*
X1814130Y-341875D01*
Y-335365D01*
G01X1814547Y-326220D02*
X1814338Y-326530D01*
X1813922D01*
X1813713Y-326220D01*
X1813922Y-325910D01*
X1814338D01*
X1814547Y-326220D01*
G01X1812672Y-316455D02*
X1813713Y-315370D01*
X1814130Y-314130D01*
X1813713Y-312890D01*
X1812464Y-311805D01*
X1810588Y-311030D01*
X1808713Y-310720D01*
X1806422D01*
X1804547Y-311030D01*
X1802880Y-311805D01*
X1802047Y-312735D01*
X1801630Y-313820D01*
X1802047Y-315060D01*
X1802880Y-315990D01*
X1804130Y-316610D01*
X1805797Y-316920D01*
X1807255Y-316610D01*
X1808713Y-315835D01*
X1809547Y-314905D01*
X1809755Y-313820D01*
X1809339Y-312580D01*
X1808297Y-311650D01*
X1806422Y-310720D01*
G01X1814130Y-301420D02*
X1813922Y-300335D01*
X1813297Y-299095D01*
X1812255Y-298320D01*
X1810797Y-298010D01*
X1809339Y-298320D01*
X1808088Y-299250D01*
X1807463Y-300645D01*
Y-302195D01*
X1807047Y-303125D01*
X1806005Y-303900D01*
X1804547Y-304210D01*
X1803088Y-303745D01*
X1802047Y-302660D01*
X1801630Y-301420D01*
X1802047Y-300180D01*
X1803088Y-299095D01*
X1804547Y-298630D01*
X1806005Y-298940D01*
X1807047Y-299715D01*
X1807463Y-300645D01*
Y-302195D01*
X1808088Y-303590D01*
X1809339Y-304520D01*
X1810797Y-304830D01*
X1812255Y-304520D01*
X1813297Y-303745D01*
X1813922Y-302505D01*
X1814130Y-301420D01*
G01Y-264960D02*
X1801630D01*
X1810588Y-270695D01*
Y-262945D01*
G01X1812255Y-257830D02*
X1813297Y-256900D01*
X1813922Y-255815D01*
X1814130Y-254420D01*
X1813713Y-253025D01*
X1812880Y-251940D01*
X1811422Y-251165D01*
X1809755Y-251010D01*
X1808088Y-251320D01*
X1807047Y-252095D01*
X1806213Y-253180D01*
X1806005Y-254265D01*
X1806213Y-255350D01*
X1807047Y-256745D01*
X1801630Y-256280D01*
Y-252095D01*
G01X1814130Y-242020D02*
X1813922Y-240935D01*
X1813297Y-239695D01*
X1812255Y-238920D01*
X1810797Y-238610D01*
X1809339Y-238920D01*
X1808088Y-239850D01*
X1807463Y-241245D01*
Y-242795D01*
X1807047Y-243725D01*
X1806005Y-244500D01*
X1804547Y-244810D01*
X1803088Y-244345D01*
X1802047Y-243260D01*
X1801630Y-242020D01*
X1802047Y-240780D01*
X1803088Y-239695D01*
X1804547Y-239230D01*
X1806005Y-239540D01*
X1807047Y-240315D01*
X1807463Y-241245D01*
Y-242795D01*
X1808088Y-244190D01*
X1809339Y-245120D01*
X1810797Y-245430D01*
X1812255Y-245120D01*
X1813297Y-244345D01*
X1813922Y-243105D01*
X1814130Y-242020D01*
G01X1814547Y-229620D02*
X1814338Y-229930D01*
X1813922D01*
X1813713Y-229620D01*
X1813922Y-229310D01*
X1814338D01*
X1814547Y-229620D01*
G01X1814130Y-217220D02*
X1813922Y-216135D01*
X1813297Y-214895D01*
X1812255Y-214120D01*
X1810797Y-213810D01*
X1809339Y-214120D01*
X1808088Y-215050D01*
X1807463Y-216445D01*
Y-217995D01*
X1807047Y-218925D01*
X1806005Y-219700D01*
X1804547Y-220010D01*
X1803088Y-219545D01*
X1802047Y-218460D01*
X1801630Y-217220D01*
X1802047Y-215980D01*
X1803088Y-214895D01*
X1804547Y-214430D01*
X1806005Y-214740D01*
X1807047Y-215515D01*
X1807463Y-216445D01*
Y-217995D01*
X1808088Y-219390D01*
X1809339Y-220320D01*
X1810797Y-220630D01*
X1812255Y-220320D01*
X1813297Y-219545D01*
X1813922Y-218305D01*
X1814130Y-217220D01*
G01X1838020Y-397120D02*
X1825520D01*
X1828020Y-398980D01*
G01X1838020D02*
Y-395260D01*
G01Y-384720D02*
X1837812Y-383635D01*
X1837187Y-382395D01*
X1836145Y-381620D01*
X1834687Y-381310D01*
X1833229Y-381620D01*
X1831978Y-382550D01*
X1831353Y-383945D01*
Y-385495D01*
X1830937Y-386425D01*
X1829895Y-387200D01*
X1828437Y-387510D01*
X1826978Y-387045D01*
X1825937Y-385960D01*
X1825520Y-384720D01*
X1825937Y-383480D01*
X1826978Y-382395D01*
X1828437Y-381930D01*
X1829895Y-382240D01*
X1830937Y-383015D01*
X1831353Y-383945D01*
Y-385495D01*
X1831978Y-386890D01*
X1833229Y-387820D01*
X1834687Y-388130D01*
X1836145Y-387820D01*
X1837187Y-387045D01*
X1837812Y-385805D01*
X1838020Y-384720D01*
G01Y-372320D02*
X1825520D01*
X1828020Y-374180D01*
G01X1838020D02*
Y-370460D01*
G01X1832812Y-362865D02*
X1831353Y-361780D01*
X1830520Y-360850D01*
X1830103Y-359610D01*
X1830520Y-358525D01*
X1831353Y-357750D01*
X1832603Y-357130D01*
X1834062Y-356975D01*
X1835312Y-357130D01*
X1836562Y-357750D01*
X1837603Y-358680D01*
X1838020Y-359765D01*
X1837603Y-361005D01*
X1836354Y-362090D01*
X1834478Y-362710D01*
X1832395Y-362865D01*
X1829687Y-362555D01*
X1828228Y-362090D01*
X1826770Y-361315D01*
X1825728Y-360230D01*
X1825520Y-359145D01*
X1825937Y-358060D01*
X1826978Y-357285D01*
G01X1838020Y-347830D02*
X1835312Y-347520D01*
X1833020Y-347055D01*
X1830937Y-346435D01*
X1828645Y-345660D01*
X1825520Y-344420D01*
Y-350620D01*
G01X1838437Y-335120D02*
X1838228Y-335430D01*
X1837812D01*
X1837603Y-335120D01*
X1837812Y-334810D01*
X1838228D01*
X1838437Y-335120D01*
G01X1838020Y-323030D02*
X1835312Y-322720D01*
X1833020Y-322255D01*
X1830937Y-321635D01*
X1828645Y-320860D01*
X1825520Y-319620D01*
Y-325820D01*
G01X1827603Y-313265D02*
X1826354Y-312335D01*
X1825728Y-311250D01*
X1825520Y-310010D01*
X1825937Y-308460D01*
X1826978Y-307375D01*
X1828228Y-307065D01*
X1829479Y-307220D01*
X1830520Y-307840D01*
X1832603Y-310940D01*
X1834062Y-312335D01*
X1836145Y-313265D01*
X1838020Y-313575D01*
Y-307065D01*
G01Y-273860D02*
X1825520D01*
X1834478Y-279595D01*
Y-271845D01*
G01X1832812Y-266265D02*
X1831353Y-265180D01*
X1830520Y-264250D01*
X1830103Y-263010D01*
X1830520Y-261925D01*
X1831353Y-261150D01*
X1832603Y-260530D01*
X1834062Y-260375D01*
X1835312Y-260530D01*
X1836562Y-261150D01*
X1837603Y-262080D01*
X1838020Y-263165D01*
X1837603Y-264405D01*
X1836354Y-265490D01*
X1834478Y-266110D01*
X1832395Y-266265D01*
X1829687Y-265955D01*
X1828228Y-265490D01*
X1826770Y-264715D01*
X1825728Y-263630D01*
X1825520Y-262545D01*
X1825937Y-261460D01*
X1826978Y-260685D01*
G01X1838020Y-250920D02*
X1825520D01*
X1828020Y-252780D01*
G01X1838020D02*
Y-249060D01*
G01X1838437Y-238520D02*
X1838228Y-238830D01*
X1837812D01*
X1837603Y-238520D01*
X1837812Y-238210D01*
X1838228D01*
X1838437Y-238520D01*
G01X1838020Y-224260D02*
X1825520D01*
X1834478Y-229995D01*
Y-222245D01*
G01X1832812Y-216665D02*
X1831353Y-215580D01*
X1830520Y-214650D01*
X1830103Y-213410D01*
X1830520Y-212325D01*
X1831353Y-211550D01*
X1832603Y-210930D01*
X1834062Y-210775D01*
X1835312Y-210930D01*
X1836562Y-211550D01*
X1837603Y-212480D01*
X1838020Y-213565D01*
X1837603Y-214805D01*
X1836354Y-215890D01*
X1834478Y-216510D01*
X1832395Y-216665D01*
X1829687Y-216355D01*
X1828228Y-215890D01*
X1826770Y-215115D01*
X1825728Y-214030D01*
X1825520Y-212945D01*
X1825937Y-211860D01*
X1826978Y-211085D01*
G01X1886960Y-383790D02*
X1874460D01*
X1876960Y-385650D01*
G01X1886960D02*
Y-381930D01*
G01Y-371390D02*
X1886752Y-370305D01*
X1886127Y-369065D01*
X1885085Y-368290D01*
X1883627Y-367980D01*
X1882169Y-368290D01*
X1880918Y-369220D01*
X1880293Y-370615D01*
Y-372165D01*
X1879877Y-373095D01*
X1878835Y-373870D01*
X1877377Y-374180D01*
X1875918Y-373715D01*
X1874877Y-372630D01*
X1874460Y-371390D01*
X1874877Y-370150D01*
X1875918Y-369065D01*
X1877377Y-368600D01*
X1878835Y-368910D01*
X1879877Y-369685D01*
X1880293Y-370615D01*
Y-372165D01*
X1880918Y-373560D01*
X1882169Y-374490D01*
X1883627Y-374800D01*
X1885085Y-374490D01*
X1886127Y-373715D01*
X1886752Y-372475D01*
X1886960Y-371390D01*
G01X1876543Y-361935D02*
X1875294Y-361005D01*
X1874668Y-359920D01*
X1874460Y-358680D01*
X1874877Y-357130D01*
X1875918Y-356045D01*
X1877168Y-355735D01*
X1878419Y-355890D01*
X1879460Y-356510D01*
X1881543Y-359610D01*
X1883002Y-361005D01*
X1885085Y-361935D01*
X1886960Y-362245D01*
Y-355735D01*
G01X1885502Y-349225D02*
X1886543Y-348140D01*
X1886960Y-346900D01*
X1886543Y-345660D01*
X1885294Y-344575D01*
X1883418Y-343800D01*
X1881543Y-343490D01*
X1879252D01*
X1877377Y-343800D01*
X1875710Y-344575D01*
X1874877Y-345505D01*
X1874460Y-346590D01*
X1874877Y-347830D01*
X1875710Y-348760D01*
X1876960Y-349380D01*
X1878627Y-349690D01*
X1880085Y-349380D01*
X1881543Y-348605D01*
X1882377Y-347675D01*
X1882585Y-346590D01*
X1882169Y-345350D01*
X1881127Y-344420D01*
X1879252Y-343490D01*
G01X1885502Y-336825D02*
X1886543Y-335740D01*
X1886960Y-334500D01*
X1886543Y-333260D01*
X1885294Y-332175D01*
X1883418Y-331400D01*
X1881543Y-331090D01*
X1879252D01*
X1877377Y-331400D01*
X1875710Y-332175D01*
X1874877Y-333105D01*
X1874460Y-334190D01*
X1874877Y-335430D01*
X1875710Y-336360D01*
X1876960Y-336980D01*
X1878627Y-337290D01*
X1880085Y-336980D01*
X1881543Y-336205D01*
X1882377Y-335275D01*
X1882585Y-334190D01*
X1882169Y-332950D01*
X1881127Y-332020D01*
X1879252Y-331090D01*
G01X1887377Y-321790D02*
X1887168Y-322100D01*
X1886752D01*
X1886543Y-321790D01*
X1886752Y-321480D01*
X1887168D01*
X1887377Y-321790D01*
G01X1876543Y-312335D02*
X1875294Y-311405D01*
X1874668Y-310320D01*
X1874460Y-309080D01*
X1874877Y-307530D01*
X1875918Y-306445D01*
X1877168Y-306135D01*
X1878419Y-306290D01*
X1879460Y-306910D01*
X1881543Y-310010D01*
X1883002Y-311405D01*
X1885085Y-312335D01*
X1886960Y-312645D01*
Y-306135D01*
G01Y-296990D02*
X1874460D01*
X1876960Y-298850D01*
G01X1886960D02*
Y-295130D01*
G01Y-260530D02*
X1874460D01*
X1883418Y-266265D01*
Y-258515D01*
G01X1881752Y-252935D02*
X1880293Y-251850D01*
X1879460Y-250920D01*
X1879043Y-249680D01*
X1879460Y-248595D01*
X1880293Y-247820D01*
X1881543Y-247200D01*
X1883002Y-247045D01*
X1884252Y-247200D01*
X1885502Y-247820D01*
X1886543Y-248750D01*
X1886960Y-249835D01*
X1886543Y-251075D01*
X1885294Y-252160D01*
X1883418Y-252780D01*
X1881335Y-252935D01*
X1878627Y-252625D01*
X1877168Y-252160D01*
X1875710Y-251385D01*
X1874668Y-250300D01*
X1874460Y-249215D01*
X1874877Y-248130D01*
X1875918Y-247355D01*
G01X1886960Y-235730D02*
X1874460D01*
X1883418Y-241465D01*
Y-233715D01*
G01X1887377Y-225190D02*
X1887168Y-225500D01*
X1886752D01*
X1886543Y-225190D01*
X1886752Y-224880D01*
X1887168D01*
X1887377Y-225190D01*
G01X1886960Y-212790D02*
X1886752Y-211705D01*
X1886127Y-210465D01*
X1885085Y-209690D01*
X1883627Y-209380D01*
X1882169Y-209690D01*
X1880918Y-210620D01*
X1880293Y-212015D01*
Y-213565D01*
X1879877Y-214495D01*
X1878835Y-215270D01*
X1877377Y-215580D01*
X1875918Y-215115D01*
X1874877Y-214030D01*
X1874460Y-212790D01*
X1874877Y-211550D01*
X1875918Y-210465D01*
X1877377Y-210000D01*
X1878835Y-210310D01*
X1879877Y-211085D01*
X1880293Y-212015D01*
Y-213565D01*
X1880918Y-214960D01*
X1882169Y-215890D01*
X1883627Y-216200D01*
X1885085Y-215890D01*
X1886127Y-215115D01*
X1886752Y-213875D01*
X1886960Y-212790D01*
G01X1914700Y-395390D02*
X1902200D01*
X1904700Y-397250D01*
G01X1914700D02*
Y-393530D01*
G01Y-382990D02*
X1914492Y-381905D01*
X1913867Y-380665D01*
X1912825Y-379890D01*
X1911367Y-379580D01*
X1909909Y-379890D01*
X1908658Y-380820D01*
X1908033Y-382215D01*
Y-383765D01*
X1907617Y-384695D01*
X1906575Y-385470D01*
X1905117Y-385780D01*
X1903658Y-385315D01*
X1902617Y-384230D01*
X1902200Y-382990D01*
X1902617Y-381750D01*
X1903658Y-380665D01*
X1905117Y-380200D01*
X1906575Y-380510D01*
X1907617Y-381285D01*
X1908033Y-382215D01*
Y-383765D01*
X1908658Y-385160D01*
X1909909Y-386090D01*
X1911367Y-386400D01*
X1912825Y-386090D01*
X1913867Y-385315D01*
X1914492Y-384075D01*
X1914700Y-382990D01*
G01X1912200Y-374000D02*
X1913659Y-373070D01*
X1914492Y-371830D01*
X1914700Y-370435D01*
X1914492Y-369195D01*
X1913450Y-367955D01*
X1912200Y-367180D01*
X1910950Y-367025D01*
X1909492Y-367335D01*
X1908450Y-368420D01*
X1908033Y-369505D01*
Y-370900D01*
G01Y-369505D02*
X1907408Y-368575D01*
X1906367Y-367800D01*
X1905117Y-367490D01*
X1903867Y-367800D01*
X1902825Y-368575D01*
X1902200Y-369970D01*
X1902408Y-371365D01*
X1903242Y-372760D01*
G01X1914700Y-358190D02*
X1914492Y-357105D01*
X1913867Y-355865D01*
X1912825Y-355090D01*
X1911367Y-354780D01*
X1909909Y-355090D01*
X1908658Y-356020D01*
X1908033Y-357415D01*
Y-358965D01*
X1907617Y-359895D01*
X1906575Y-360670D01*
X1905117Y-360980D01*
X1903658Y-360515D01*
X1902617Y-359430D01*
X1902200Y-358190D01*
X1902617Y-356950D01*
X1903658Y-355865D01*
X1905117Y-355400D01*
X1906575Y-355710D01*
X1907617Y-356485D01*
X1908033Y-357415D01*
Y-358965D01*
X1908658Y-360360D01*
X1909909Y-361290D01*
X1911367Y-361600D01*
X1912825Y-361290D01*
X1913867Y-360515D01*
X1914492Y-359275D01*
X1914700Y-358190D01*
G01Y-345790D02*
X1902200D01*
X1904700Y-347650D01*
G01X1914700D02*
Y-343930D01*
G01X1915117Y-333390D02*
X1914908Y-333700D01*
X1914492D01*
X1914283Y-333390D01*
X1914492Y-333080D01*
X1914908D01*
X1915117Y-333390D01*
G01X1912825Y-324400D02*
X1913867Y-323470D01*
X1914492Y-322385D01*
X1914700Y-320990D01*
X1914283Y-319595D01*
X1913450Y-318510D01*
X1911992Y-317735D01*
X1910325Y-317580D01*
X1908658Y-317890D01*
X1907617Y-318665D01*
X1906783Y-319750D01*
X1906575Y-320835D01*
X1906783Y-321920D01*
X1907617Y-323315D01*
X1902200Y-322850D01*
Y-318665D01*
G01Y-308590D02*
X1902617Y-309830D01*
X1903658Y-310760D01*
X1904908Y-311380D01*
X1906575Y-311845D01*
X1908450Y-312000D01*
X1910325Y-311845D01*
X1911992Y-311380D01*
X1913242Y-310760D01*
X1914283Y-309830D01*
X1914700Y-308590D01*
X1914283Y-307350D01*
X1913242Y-306420D01*
X1911992Y-305800D01*
X1910325Y-305335D01*
X1908450Y-305180D01*
X1906575Y-305335D01*
X1904908Y-305800D01*
X1903658Y-306420D01*
X1902617Y-307350D01*
X1902200Y-308590D01*
G01X1914700Y-272130D02*
X1902200D01*
X1911158Y-277865D01*
Y-270115D01*
G01X1909492Y-264535D02*
X1908033Y-263450D01*
X1907200Y-262520D01*
X1906783Y-261280D01*
X1907200Y-260195D01*
X1908033Y-259420D01*
X1909283Y-258800D01*
X1910742Y-258645D01*
X1911992Y-258800D01*
X1913242Y-259420D01*
X1914283Y-260350D01*
X1914700Y-261435D01*
X1914283Y-262675D01*
X1913034Y-263760D01*
X1911158Y-264380D01*
X1909075Y-264535D01*
X1906367Y-264225D01*
X1904908Y-263760D01*
X1903450Y-262985D01*
X1902408Y-261900D01*
X1902200Y-260815D01*
X1902617Y-259730D01*
X1903658Y-258955D01*
G01X1909492Y-252135D02*
X1908033Y-251050D01*
X1907200Y-250120D01*
X1906783Y-248880D01*
X1907200Y-247795D01*
X1908033Y-247020D01*
X1909283Y-246400D01*
X1910742Y-246245D01*
X1911992Y-246400D01*
X1913242Y-247020D01*
X1914283Y-247950D01*
X1914700Y-249035D01*
X1914283Y-250275D01*
X1913034Y-251360D01*
X1911158Y-251980D01*
X1909075Y-252135D01*
X1906367Y-251825D01*
X1904908Y-251360D01*
X1903450Y-250585D01*
X1902408Y-249500D01*
X1902200Y-248415D01*
X1902617Y-247330D01*
X1903658Y-246555D01*
G01X1915117Y-236790D02*
X1914908Y-237100D01*
X1914492D01*
X1914283Y-236790D01*
X1914492Y-236480D01*
X1914908D01*
X1915117Y-236790D01*
G01X1914700Y-224390D02*
X1914492Y-223305D01*
X1913867Y-222065D01*
X1912825Y-221290D01*
X1911367Y-220980D01*
X1909909Y-221290D01*
X1908658Y-222220D01*
X1908033Y-223615D01*
Y-225165D01*
X1907617Y-226095D01*
X1906575Y-226870D01*
X1905117Y-227180D01*
X1903658Y-226715D01*
X1902617Y-225630D01*
X1902200Y-224390D01*
X1902617Y-223150D01*
X1903658Y-222065D01*
X1905117Y-221600D01*
X1906575Y-221910D01*
X1907617Y-222685D01*
X1908033Y-223615D01*
Y-225165D01*
X1908658Y-226560D01*
X1909909Y-227490D01*
X1911367Y-227800D01*
X1912825Y-227490D01*
X1913867Y-226715D01*
X1914492Y-225475D01*
X1914700Y-224390D01*
G01X1913242Y-214625D02*
X1914283Y-213540D01*
X1914700Y-212300D01*
X1914283Y-211060D01*
X1913034Y-209975D01*
X1911158Y-209200D01*
X1909283Y-208890D01*
X1906992D01*
X1905117Y-209200D01*
X1903450Y-209975D01*
X1902617Y-210905D01*
X1902200Y-211990D01*
X1902617Y-213230D01*
X1903450Y-214160D01*
X1904700Y-214780D01*
X1906367Y-215090D01*
X1907825Y-214780D01*
X1909283Y-214005D01*
X1910117Y-213075D01*
X1910325Y-211990D01*
X1909909Y-210750D01*
X1908867Y-209820D01*
X1906992Y-208890D01*
G01X2111230Y886659D02*
X2098730D01*
X2101230Y884799D01*
G01X2111230D02*
Y888519D01*
G01Y898749D02*
X2108522Y899059D01*
X2106230Y899524D01*
X2104147Y900144D01*
X2101855Y900919D01*
X2098730Y902159D01*
Y895959D01*
G01X2111230Y913319D02*
X2098730D01*
X2107688Y907584D01*
Y915334D01*
G01X2098730Y923859D02*
X2099147Y922619D01*
X2100188Y921689D01*
X2101438Y921069D01*
X2103105Y920604D01*
X2104980Y920449D01*
X2106855Y920604D01*
X2108522Y921069D01*
X2109772Y921689D01*
X2110813Y922619D01*
X2111230Y923859D01*
X2110813Y925099D01*
X2109772Y926029D01*
X2108522Y926649D01*
X2106855Y927114D01*
X2104980Y927269D01*
X2103105Y927114D01*
X2101438Y926649D01*
X2100188Y926029D01*
X2099147Y925099D01*
X2098730Y923859D01*
G01X2111230Y936259D02*
X2098730D01*
X2101230Y934399D01*
G01X2111230D02*
Y938119D01*
G01X2111647Y948659D02*
X2111438Y948349D01*
X2111022D01*
X2110813Y948659D01*
X2111022Y948969D01*
X2111438D01*
X2111647Y948659D01*
G01X2111230Y961059D02*
X2098730D01*
X2101230Y959199D01*
G01X2111230D02*
Y962919D01*
G01Y973459D02*
X2111022Y974544D01*
X2110397Y975784D01*
X2109355Y976559D01*
X2107897Y976869D01*
X2106439Y976559D01*
X2105188Y975629D01*
X2104563Y974234D01*
Y972684D01*
X2104147Y971754D01*
X2103105Y970979D01*
X2101647Y970669D01*
X2100188Y971134D01*
X2099147Y972219D01*
X2098730Y973459D01*
X2099147Y974699D01*
X2100188Y975784D01*
X2101647Y976249D01*
X2103105Y975939D01*
X2104147Y975164D01*
X2104563Y974234D01*
Y972684D01*
X2105188Y971289D01*
X2106439Y970359D01*
X2107897Y970049D01*
X2109355Y970359D01*
X2110397Y971134D01*
X2111022Y972374D01*
X2111230Y973459D01*
G01X2136230Y901069D02*
X2123730D01*
X2132688Y895334D01*
Y903084D01*
G01X2136230Y913469D02*
X2123730D01*
X2132688Y907734D01*
Y915484D01*
G01X2136230Y924009D02*
X2123730D01*
X2126230Y922149D01*
G01X2136230D02*
Y925869D01*
G01X2136647Y936409D02*
X2136438Y936099D01*
X2136022D01*
X2135813Y936409D01*
X2136022Y936719D01*
X2136438D01*
X2136647Y936409D01*
G01X2134772Y946174D02*
X2135813Y947259D01*
X2136230Y948499D01*
X2135813Y949739D01*
X2134564Y950824D01*
X2132688Y951599D01*
X2130813Y951909D01*
X2128522D01*
X2126647Y951599D01*
X2124980Y950824D01*
X2124147Y949894D01*
X2123730Y948809D01*
X2124147Y947569D01*
X2124980Y946639D01*
X2126230Y946019D01*
X2127897Y945709D01*
X2129355Y946019D01*
X2130813Y946794D01*
X2131647Y947724D01*
X2131855Y948809D01*
X2131439Y950049D01*
X2130397Y950979D01*
X2128522Y951909D01*
G01X2134772Y958574D02*
X2135813Y959659D01*
X2136230Y960899D01*
X2135813Y962139D01*
X2134564Y963224D01*
X2132688Y963999D01*
X2130813Y964309D01*
X2128522D01*
X2126647Y963999D01*
X2124980Y963224D01*
X2124147Y962294D01*
X2123730Y961209D01*
X2124147Y959969D01*
X2124980Y959039D01*
X2126230Y958419D01*
X2127897Y958109D01*
X2129355Y958419D01*
X2130813Y959194D01*
X2131647Y960124D01*
X2131855Y961209D01*
X2131439Y962449D01*
X2130397Y963379D01*
X2128522Y964309D01*
G01X2358875Y1549606D02*
Y1562106D01*
X2364765D01*
G01X2362595Y1556064D02*
X2358875D01*
G01X2372360Y1562106D02*
X2376080D01*
G01X2374220D02*
Y1549606D01*
G01X2372360D02*
X2376080D01*
G01X2387550Y1555856D02*
X2390650D01*
Y1552106D01*
X2389720Y1550856D01*
X2388635Y1550023D01*
X2387085Y1549606D01*
X2385535Y1550023D01*
X2384450Y1550856D01*
X2383520Y1552106D01*
X2382900Y1553564D01*
X2382590Y1555231D01*
Y1556689D01*
X2382900Y1557939D01*
X2383520Y1559398D01*
X2384450Y1560648D01*
X2385380Y1561481D01*
X2386620Y1562106D01*
X2387705D01*
X2388945Y1561689D01*
X2389875Y1560856D01*
G01X2395610Y1562106D02*
Y1553148D01*
X2396230Y1551272D01*
X2397470Y1550023D01*
X2399020Y1549606D01*
X2400570Y1550023D01*
X2401810Y1551272D01*
X2402430Y1553148D01*
Y1562106D01*
G01X2408320Y1549606D02*
Y1562106D01*
X2412195D01*
X2413435Y1561481D01*
X2414210Y1560648D01*
X2414520Y1558981D01*
X2414210Y1557314D01*
X2413280Y1556273D01*
X2412195Y1555648D01*
X2408320D01*
G01X2412195D02*
X2414520Y1549606D01*
G01X2426920D02*
X2420720D01*
Y1562106D01*
X2426920D01*
G01X2424440Y1556064D02*
X2420720D01*
G01X2461175Y1549606D02*
Y1562106D01*
X2467065D01*
G01X2464895Y1556064D02*
X2461175D01*
G01X2474660Y1562106D02*
X2478380D01*
G01X2476520D02*
Y1549606D01*
G01X2474660D02*
X2478380D01*
G01X2485355D02*
Y1562106D01*
X2492485Y1549606D01*
Y1562106D01*
G01X2499460D02*
X2503180D01*
G01X2501320D02*
Y1549606D01*
G01X2499460D02*
X2503180D01*
G01X2510465Y1551272D02*
X2511705Y1550231D01*
X2513100Y1549606D01*
X2514340D01*
X2515580Y1550231D01*
X2516510Y1551272D01*
X2516975Y1552731D01*
X2516665Y1554189D01*
X2515890Y1555439D01*
X2514495Y1556273D01*
X2512635Y1556689D01*
X2511550Y1557523D01*
X2511085Y1558981D01*
X2511395Y1560439D01*
X2512170Y1561481D01*
X2513255Y1562106D01*
X2514340D01*
X2515425Y1561689D01*
X2516355Y1560648D01*
G01X2522865Y1549606D02*
Y1562106D01*
G01X2529375D02*
Y1549606D01*
G01Y1555856D02*
X2522865D01*
G01X2541620Y1549606D02*
X2535420D01*
Y1562106D01*
X2541620D01*
G01X2539140Y1556064D02*
X2535420D01*
G01X2547510Y1549606D02*
Y1562106D01*
X2550610D01*
X2551850Y1561481D01*
X2552780Y1560648D01*
X2553555Y1559398D01*
X2554175Y1557939D01*
X2554330Y1555856D01*
X2554175Y1553773D01*
X2553555Y1552314D01*
X2552780Y1551064D01*
X2551850Y1550231D01*
X2550610Y1549606D01*
X2547510D01*
G01X2558670Y1545439D02*
X2567970D01*
G01X2572465Y1551272D02*
X2573705Y1550231D01*
X2575100Y1549606D01*
X2576340D01*
X2577580Y1550231D01*
X2578510Y1551272D01*
X2578975Y1552731D01*
X2578665Y1554189D01*
X2577890Y1555439D01*
X2576495Y1556273D01*
X2574635Y1556689D01*
X2573550Y1557523D01*
X2573085Y1558981D01*
X2573395Y1560439D01*
X2574170Y1561481D01*
X2575255Y1562106D01*
X2576340D01*
X2577425Y1561689D01*
X2578355Y1560648D01*
G01X2586260Y1562106D02*
X2589980D01*
G01X2588120D02*
Y1549606D01*
G01X2586260D02*
X2589980D01*
G01X2597575Y1562106D02*
X2603465D01*
X2597575Y1549606D01*
X2603465D01*
G01X2616020D02*
X2609820D01*
Y1562106D01*
X2616020D01*
G01X2613540Y1556064D02*
X2609820D01*
G01X2473575Y-609627D02*
X2474505Y-608378D01*
X2475590Y-607752D01*
X2476830Y-607544D01*
X2478380Y-607961D01*
X2479465Y-609002D01*
X2479775Y-610252D01*
X2479620Y-611503D01*
X2479000Y-612544D01*
X2475900Y-614627D01*
X2474505Y-616086D01*
X2473575Y-618169D01*
X2473265Y-620044D01*
X2479775D01*
G01X2485510Y-618169D02*
X2486440Y-619211D01*
X2487525Y-619836D01*
X2488920Y-620044D01*
X2490315Y-619627D01*
X2491400Y-618794D01*
X2492175Y-617336D01*
X2492330Y-615669D01*
X2492020Y-614002D01*
X2491245Y-612961D01*
X2490160Y-612127D01*
X2489075Y-611919D01*
X2487990Y-612127D01*
X2486595Y-612961D01*
X2487060Y-607544D01*
X2491245D01*
G01X2497910Y-618169D02*
X2498840Y-619211D01*
X2499925Y-619836D01*
X2501320Y-620044D01*
X2502715Y-619627D01*
X2503800Y-618794D01*
X2504575Y-617336D01*
X2504730Y-615669D01*
X2504420Y-614002D01*
X2503645Y-612961D01*
X2502560Y-612127D01*
X2501475Y-611919D01*
X2500390Y-612127D01*
X2498995Y-612961D01*
X2499460Y-607544D01*
X2503645D01*
G01X2513720Y-620461D02*
X2513410Y-620252D01*
Y-619836D01*
X2513720Y-619627D01*
X2514030Y-619836D01*
Y-620252D01*
X2513720Y-620461D01*
G01X2526120Y-607544D02*
X2524880Y-607961D01*
X2523950Y-609002D01*
X2523330Y-610252D01*
X2522865Y-611919D01*
X2522710Y-613794D01*
X2522865Y-615669D01*
X2523330Y-617336D01*
X2523950Y-618586D01*
X2524880Y-619627D01*
X2526120Y-620044D01*
X2527360Y-619627D01*
X2528290Y-618586D01*
X2528910Y-617336D01*
X2529375Y-615669D01*
X2529530Y-613794D01*
X2529375Y-611919D01*
X2528910Y-610252D01*
X2528290Y-609002D01*
X2527360Y-607961D01*
X2526120Y-607544D01*
G01X2536195Y-611711D02*
X2540845Y-620044D01*
G01Y-611711D02*
X2536195Y-620044D01*
G01X2547975Y-609627D02*
X2548905Y-608378D01*
X2549990Y-607752D01*
X2551230Y-607544D01*
X2552780Y-607961D01*
X2553865Y-609002D01*
X2554175Y-610252D01*
X2554020Y-611503D01*
X2553400Y-612544D01*
X2550300Y-614627D01*
X2548905Y-616086D01*
X2547975Y-618169D01*
X2547665Y-620044D01*
X2554175D01*
G01X2563320Y-607544D02*
X2562080Y-607961D01*
X2561150Y-609002D01*
X2560530Y-610252D01*
X2560065Y-611919D01*
X2559910Y-613794D01*
X2560065Y-615669D01*
X2560530Y-617336D01*
X2561150Y-618586D01*
X2562080Y-619627D01*
X2563320Y-620044D01*
X2564560Y-619627D01*
X2565490Y-618586D01*
X2566110Y-617336D01*
X2566575Y-615669D01*
X2566730Y-613794D01*
X2566575Y-611919D01*
X2566110Y-610252D01*
X2565490Y-609002D01*
X2564560Y-607961D01*
X2563320Y-607544D01*
G01X2575720D02*
X2574480Y-607961D01*
X2573550Y-609002D01*
X2572930Y-610252D01*
X2572465Y-611919D01*
X2572310Y-613794D01*
X2572465Y-615669D01*
X2572930Y-617336D01*
X2573550Y-618586D01*
X2574480Y-619627D01*
X2575720Y-620044D01*
X2576960Y-619627D01*
X2577890Y-618586D01*
X2578510Y-617336D01*
X2578975Y-615669D01*
X2579130Y-613794D01*
X2578975Y-611919D01*
X2578510Y-610252D01*
X2577890Y-609002D01*
X2576960Y-607961D01*
X2575720Y-607544D01*
G01X2588120Y-620461D02*
X2587810Y-620252D01*
Y-619836D01*
X2588120Y-619627D01*
X2588430Y-619836D01*
Y-620252D01*
X2588120Y-620461D01*
G01X2600520Y-607544D02*
X2599280Y-607961D01*
X2598350Y-609002D01*
X2597730Y-610252D01*
X2597265Y-611919D01*
X2597110Y-613794D01*
X2597265Y-615669D01*
X2597730Y-617336D01*
X2598350Y-618586D01*
X2599280Y-619627D01*
X2600520Y-620044D01*
X2601760Y-619627D01*
X2602690Y-618586D01*
X2603310Y-617336D01*
X2603775Y-615669D01*
X2603930Y-613794D01*
X2603775Y-611919D01*
X2603310Y-610252D01*
X2602690Y-609002D01*
X2601760Y-607961D01*
X2600520Y-607544D01*
G01X2476520Y-560944D02*
Y-548444D01*
X2474660Y-550944D01*
G01Y-560944D02*
X2478380D01*
G01X2488920D02*
X2490005Y-560736D01*
X2491245Y-560111D01*
X2492020Y-559069D01*
X2492330Y-557611D01*
X2492020Y-556153D01*
X2491090Y-554902D01*
X2489695Y-554277D01*
X2488145D01*
X2487215Y-553861D01*
X2486440Y-552819D01*
X2486130Y-551361D01*
X2486595Y-549902D01*
X2487680Y-548861D01*
X2488920Y-548444D01*
X2490160Y-548861D01*
X2491245Y-549902D01*
X2491710Y-551361D01*
X2491400Y-552819D01*
X2490625Y-553861D01*
X2489695Y-554277D01*
X2488145D01*
X2486750Y-554902D01*
X2485820Y-556153D01*
X2485510Y-557611D01*
X2485820Y-559069D01*
X2486595Y-560111D01*
X2487835Y-560736D01*
X2488920Y-560944D01*
G01X2498685Y-559486D02*
X2499770Y-560527D01*
X2501010Y-560944D01*
X2502250Y-560527D01*
X2503335Y-559278D01*
X2504110Y-557402D01*
X2504420Y-555527D01*
Y-553236D01*
X2504110Y-551361D01*
X2503335Y-549694D01*
X2502405Y-548861D01*
X2501320Y-548444D01*
X2500080Y-548861D01*
X2499150Y-549694D01*
X2498530Y-550944D01*
X2498220Y-552611D01*
X2498530Y-554069D01*
X2499305Y-555527D01*
X2500235Y-556361D01*
X2501320Y-556569D01*
X2502560Y-556153D01*
X2503490Y-555111D01*
X2504420Y-553236D01*
G01X2513720Y-561361D02*
X2513410Y-561152D01*
Y-560736D01*
X2513720Y-560527D01*
X2514030Y-560736D01*
Y-561152D01*
X2513720Y-561361D01*
G01X2526120Y-548444D02*
X2524880Y-548861D01*
X2523950Y-549902D01*
X2523330Y-551152D01*
X2522865Y-552819D01*
X2522710Y-554694D01*
X2522865Y-556569D01*
X2523330Y-558236D01*
X2523950Y-559486D01*
X2524880Y-560527D01*
X2526120Y-560944D01*
X2527360Y-560527D01*
X2528290Y-559486D01*
X2528910Y-558236D01*
X2529375Y-556569D01*
X2529530Y-554694D01*
X2529375Y-552819D01*
X2528910Y-551152D01*
X2528290Y-549902D01*
X2527360Y-548861D01*
X2526120Y-548444D01*
G01X2536195Y-552611D02*
X2540845Y-560944D01*
G01Y-552611D02*
X2536195Y-560944D01*
G01X2550920D02*
Y-548444D01*
X2549060Y-550944D01*
G01Y-560944D02*
X2552780D01*
G01X2560375Y-550527D02*
X2561305Y-549278D01*
X2562390Y-548652D01*
X2563630Y-548444D01*
X2565180Y-548861D01*
X2566265Y-549902D01*
X2566575Y-551152D01*
X2566420Y-552403D01*
X2565800Y-553444D01*
X2562700Y-555527D01*
X2561305Y-556986D01*
X2560375Y-559069D01*
X2560065Y-560944D01*
X2566575D01*
G01X2572775Y-555736D02*
X2573860Y-554277D01*
X2574790Y-553444D01*
X2576030Y-553027D01*
X2577115Y-553444D01*
X2577890Y-554277D01*
X2578510Y-555527D01*
X2578665Y-556986D01*
X2578510Y-558236D01*
X2577890Y-559486D01*
X2576960Y-560527D01*
X2575875Y-560944D01*
X2574635Y-560527D01*
X2573550Y-559278D01*
X2572930Y-557402D01*
X2572775Y-555319D01*
X2573085Y-552611D01*
X2573550Y-551152D01*
X2574325Y-549694D01*
X2575410Y-548652D01*
X2576495Y-548444D01*
X2577580Y-548861D01*
X2578355Y-549902D01*
G01X2588120Y-561361D02*
X2587810Y-561152D01*
Y-560736D01*
X2588120Y-560527D01*
X2588430Y-560736D01*
Y-561152D01*
X2588120Y-561361D01*
G01X2600520Y-548444D02*
X2599280Y-548861D01*
X2598350Y-549902D01*
X2597730Y-551152D01*
X2597265Y-552819D01*
X2597110Y-554694D01*
X2597265Y-556569D01*
X2597730Y-558236D01*
X2598350Y-559486D01*
X2599280Y-560527D01*
X2600520Y-560944D01*
X2601760Y-560527D01*
X2602690Y-559486D01*
X2603310Y-558236D01*
X2603775Y-556569D01*
X2603930Y-554694D01*
X2603775Y-552819D01*
X2603310Y-551152D01*
X2602690Y-549902D01*
X2601760Y-548861D01*
X2600520Y-548444D01*
G01X2486285Y-500386D02*
X2487370Y-501427D01*
X2488610Y-501844D01*
X2489850Y-501427D01*
X2490935Y-500178D01*
X2491710Y-498302D01*
X2492020Y-496427D01*
Y-494136D01*
X2491710Y-492261D01*
X2490935Y-490594D01*
X2490005Y-489761D01*
X2488920Y-489344D01*
X2487680Y-489761D01*
X2486750Y-490594D01*
X2486130Y-491844D01*
X2485820Y-493511D01*
X2486130Y-494969D01*
X2486905Y-496427D01*
X2487835Y-497261D01*
X2488920Y-497469D01*
X2490160Y-497053D01*
X2491090Y-496011D01*
X2492020Y-494136D01*
G01X2501010Y-501844D02*
X2501320Y-499136D01*
X2501785Y-496844D01*
X2502405Y-494761D01*
X2503180Y-492469D01*
X2504420Y-489344D01*
X2498220D01*
G01X2513720Y-502261D02*
X2513410Y-502052D01*
Y-501636D01*
X2513720Y-501427D01*
X2514030Y-501636D01*
Y-502052D01*
X2513720Y-502261D01*
G01X2526120Y-489344D02*
X2524880Y-489761D01*
X2523950Y-490802D01*
X2523330Y-492052D01*
X2522865Y-493719D01*
X2522710Y-495594D01*
X2522865Y-497469D01*
X2523330Y-499136D01*
X2523950Y-500386D01*
X2524880Y-501427D01*
X2526120Y-501844D01*
X2527360Y-501427D01*
X2528290Y-500386D01*
X2528910Y-499136D01*
X2529375Y-497469D01*
X2529530Y-495594D01*
X2529375Y-493719D01*
X2528910Y-492052D01*
X2528290Y-490802D01*
X2527360Y-489761D01*
X2526120Y-489344D01*
G01X2536195Y-493511D02*
X2540845Y-501844D01*
G01Y-493511D02*
X2536195Y-501844D01*
G01X2552780D02*
Y-489344D01*
X2547045Y-498302D01*
X2554795D01*
G01X2563320Y-501844D02*
X2564405Y-501636D01*
X2565645Y-501011D01*
X2566420Y-499969D01*
X2566730Y-498511D01*
X2566420Y-497053D01*
X2565490Y-495802D01*
X2564095Y-495177D01*
X2562545D01*
X2561615Y-494761D01*
X2560840Y-493719D01*
X2560530Y-492261D01*
X2560995Y-490802D01*
X2562080Y-489761D01*
X2563320Y-489344D01*
X2564560Y-489761D01*
X2565645Y-490802D01*
X2566110Y-492261D01*
X2565800Y-493719D01*
X2565025Y-494761D01*
X2564095Y-495177D01*
X2562545D01*
X2561150Y-495802D01*
X2560220Y-497053D01*
X2559910Y-498511D01*
X2560220Y-499969D01*
X2560995Y-501011D01*
X2562235Y-501636D01*
X2563320Y-501844D01*
G01X2575720Y-502261D02*
X2575410Y-502052D01*
Y-501636D01*
X2575720Y-501427D01*
X2576030Y-501636D01*
Y-502052D01*
X2575720Y-502261D01*
G01X2588120Y-489344D02*
X2586880Y-489761D01*
X2585950Y-490802D01*
X2585330Y-492052D01*
X2584865Y-493719D01*
X2584710Y-495594D01*
X2584865Y-497469D01*
X2585330Y-499136D01*
X2585950Y-500386D01*
X2586880Y-501427D01*
X2588120Y-501844D01*
X2589360Y-501427D01*
X2590290Y-500386D01*
X2590910Y-499136D01*
X2591375Y-497469D01*
X2591530Y-495594D01*
X2591375Y-493719D01*
X2590910Y-492052D01*
X2590290Y-490802D01*
X2589360Y-489761D01*
X2588120Y-489344D01*
G01X2486285Y-441286D02*
X2487370Y-442327D01*
X2488610Y-442744D01*
X2489850Y-442327D01*
X2490935Y-441078D01*
X2491710Y-439202D01*
X2492020Y-437327D01*
Y-435036D01*
X2491710Y-433161D01*
X2490935Y-431494D01*
X2490005Y-430661D01*
X2488920Y-430244D01*
X2487680Y-430661D01*
X2486750Y-431494D01*
X2486130Y-432744D01*
X2485820Y-434411D01*
X2486130Y-435869D01*
X2486905Y-437327D01*
X2487835Y-438161D01*
X2488920Y-438369D01*
X2490160Y-437953D01*
X2491090Y-436911D01*
X2492020Y-435036D01*
G01X2501010Y-442744D02*
X2501320Y-440036D01*
X2501785Y-437744D01*
X2502405Y-435661D01*
X2503180Y-433369D01*
X2504420Y-430244D01*
X2498220D01*
G01X2513720Y-443161D02*
X2513410Y-442952D01*
Y-442536D01*
X2513720Y-442327D01*
X2514030Y-442536D01*
Y-442952D01*
X2513720Y-443161D01*
G01X2526120Y-430244D02*
X2524880Y-430661D01*
X2523950Y-431702D01*
X2523330Y-432952D01*
X2522865Y-434619D01*
X2522710Y-436494D01*
X2522865Y-438369D01*
X2523330Y-440036D01*
X2523950Y-441286D01*
X2524880Y-442327D01*
X2526120Y-442744D01*
X2527360Y-442327D01*
X2528290Y-441286D01*
X2528910Y-440036D01*
X2529375Y-438369D01*
X2529530Y-436494D01*
X2529375Y-434619D01*
X2528910Y-432952D01*
X2528290Y-431702D01*
X2527360Y-430661D01*
X2526120Y-430244D01*
G01X2536195Y-434411D02*
X2540845Y-442744D01*
G01Y-434411D02*
X2536195Y-442744D01*
G01X2552780D02*
Y-430244D01*
X2547045Y-439202D01*
X2554795D01*
G01X2565180Y-442744D02*
Y-430244D01*
X2559445Y-439202D01*
X2567195D01*
G01X2575720Y-443161D02*
X2575410Y-442952D01*
Y-442536D01*
X2575720Y-442327D01*
X2576030Y-442536D01*
Y-442952D01*
X2575720Y-443161D01*
G01X2588120Y-430244D02*
X2586880Y-430661D01*
X2585950Y-431702D01*
X2585330Y-432952D01*
X2584865Y-434619D01*
X2584710Y-436494D01*
X2584865Y-438369D01*
X2585330Y-440036D01*
X2585950Y-441286D01*
X2586880Y-442327D01*
X2588120Y-442744D01*
X2589360Y-442327D01*
X2590290Y-441286D01*
X2590910Y-440036D01*
X2591375Y-438369D01*
X2591530Y-436494D01*
X2591375Y-434619D01*
X2590910Y-432952D01*
X2590290Y-431702D01*
X2589360Y-430661D01*
X2588120Y-430244D01*
G01X2510310Y-381144D02*
X2511240Y-382603D01*
X2512480Y-383436D01*
X2513875Y-383644D01*
X2515115Y-383436D01*
X2516355Y-382394D01*
X2517130Y-381144D01*
X2517285Y-379894D01*
X2516975Y-378436D01*
X2515890Y-377394D01*
X2514805Y-376977D01*
X2513410D01*
G01X2514805D02*
X2515735Y-376352D01*
X2516510Y-375311D01*
X2516820Y-374061D01*
X2516510Y-372811D01*
X2515735Y-371769D01*
X2514340Y-371144D01*
X2512945Y-371352D01*
X2511550Y-372186D01*
G01X2523485Y-382186D02*
X2524570Y-383227D01*
X2525810Y-383644D01*
X2527050Y-383227D01*
X2528135Y-381978D01*
X2528910Y-380102D01*
X2529220Y-378227D01*
Y-375936D01*
X2528910Y-374061D01*
X2528135Y-372394D01*
X2527205Y-371561D01*
X2526120Y-371144D01*
X2524880Y-371561D01*
X2523950Y-372394D01*
X2523330Y-373644D01*
X2523020Y-375311D01*
X2523330Y-376769D01*
X2524105Y-378227D01*
X2525035Y-379061D01*
X2526120Y-379269D01*
X2527360Y-378853D01*
X2528290Y-377811D01*
X2529220Y-375936D01*
G01X2540380Y-383644D02*
Y-371144D01*
X2534645Y-380102D01*
X2542395D01*
G01X2550920Y-384061D02*
X2550610Y-383852D01*
Y-383436D01*
X2550920Y-383227D01*
X2551230Y-383436D01*
Y-383852D01*
X2550920Y-384061D01*
G01X2563320Y-371144D02*
X2562080Y-371561D01*
X2561150Y-372602D01*
X2560530Y-373852D01*
X2560065Y-375519D01*
X2559910Y-377394D01*
X2560065Y-379269D01*
X2560530Y-380936D01*
X2561150Y-382186D01*
X2562080Y-383227D01*
X2563320Y-383644D01*
X2564560Y-383227D01*
X2565490Y-382186D01*
X2566110Y-380936D01*
X2566575Y-379269D01*
X2566730Y-377394D01*
X2566575Y-375519D01*
X2566110Y-373852D01*
X2565490Y-372602D01*
X2564560Y-371561D01*
X2563320Y-371144D01*
G01X2510775Y-314127D02*
X2511705Y-312878D01*
X2512790Y-312252D01*
X2514030Y-312044D01*
X2515580Y-312461D01*
X2516665Y-313502D01*
X2516975Y-314752D01*
X2516820Y-316003D01*
X2516200Y-317044D01*
X2513100Y-319127D01*
X2511705Y-320586D01*
X2510775Y-322669D01*
X2510465Y-324544D01*
X2516975D01*
G01X2526120D02*
Y-312044D01*
X2524260Y-314544D01*
G01Y-324544D02*
X2527980D01*
G01X2538210D02*
X2538520Y-321836D01*
X2538985Y-319544D01*
X2539605Y-317461D01*
X2540380Y-315169D01*
X2541620Y-312044D01*
X2535420D01*
G01X2550920Y-324961D02*
X2550610Y-324752D01*
Y-324336D01*
X2550920Y-324127D01*
X2551230Y-324336D01*
Y-324752D01*
X2550920Y-324961D01*
G01X2563320Y-312044D02*
X2562080Y-312461D01*
X2561150Y-313502D01*
X2560530Y-314752D01*
X2560065Y-316419D01*
X2559910Y-318294D01*
X2560065Y-320169D01*
X2560530Y-321836D01*
X2561150Y-323086D01*
X2562080Y-324127D01*
X2563320Y-324544D01*
X2564560Y-324127D01*
X2565490Y-323086D01*
X2566110Y-321836D01*
X2566575Y-320169D01*
X2566730Y-318294D01*
X2566575Y-316419D01*
X2566110Y-314752D01*
X2565490Y-313502D01*
X2564560Y-312461D01*
X2563320Y-312044D01*
G01X2513720Y-265444D02*
Y-252944D01*
X2511860Y-255444D01*
G01Y-265444D02*
X2515580D01*
G01X2522710Y-263569D02*
X2523640Y-264611D01*
X2524725Y-265236D01*
X2526120Y-265444D01*
X2527515Y-265027D01*
X2528600Y-264194D01*
X2529375Y-262736D01*
X2529530Y-261069D01*
X2529220Y-259402D01*
X2528445Y-258361D01*
X2527360Y-257527D01*
X2526275Y-257319D01*
X2525190Y-257527D01*
X2523795Y-258361D01*
X2524260Y-252944D01*
X2528445D01*
G01X2538520Y-265444D02*
X2539605Y-265236D01*
X2540845Y-264611D01*
X2541620Y-263569D01*
X2541930Y-262111D01*
X2541620Y-260653D01*
X2540690Y-259402D01*
X2539295Y-258777D01*
X2537745D01*
X2536815Y-258361D01*
X2536040Y-257319D01*
X2535730Y-255861D01*
X2536195Y-254402D01*
X2537280Y-253361D01*
X2538520Y-252944D01*
X2539760Y-253361D01*
X2540845Y-254402D01*
X2541310Y-255861D01*
X2541000Y-257319D01*
X2540225Y-258361D01*
X2539295Y-258777D01*
X2537745D01*
X2536350Y-259402D01*
X2535420Y-260653D01*
X2535110Y-262111D01*
X2535420Y-263569D01*
X2536195Y-264611D01*
X2537435Y-265236D01*
X2538520Y-265444D01*
G01X2550920Y-265861D02*
X2550610Y-265652D01*
Y-265236D01*
X2550920Y-265027D01*
X2551230Y-265236D01*
Y-265652D01*
X2550920Y-265861D01*
G01X2563320Y-252944D02*
X2562080Y-253361D01*
X2561150Y-254402D01*
X2560530Y-255652D01*
X2560065Y-257319D01*
X2559910Y-259194D01*
X2560065Y-261069D01*
X2560530Y-262736D01*
X2561150Y-263986D01*
X2562080Y-265027D01*
X2563320Y-265444D01*
X2564560Y-265027D01*
X2565490Y-263986D01*
X2566110Y-262736D01*
X2566575Y-261069D01*
X2566730Y-259194D01*
X2566575Y-257319D01*
X2566110Y-255652D01*
X2565490Y-254402D01*
X2564560Y-253361D01*
X2563320Y-252944D01*
G01X2513720Y-206344D02*
Y-193844D01*
X2511860Y-196344D01*
G01Y-206344D02*
X2515580D01*
G01X2523175Y-195927D02*
X2524105Y-194678D01*
X2525190Y-194052D01*
X2526430Y-193844D01*
X2527980Y-194261D01*
X2529065Y-195302D01*
X2529375Y-196552D01*
X2529220Y-197803D01*
X2528600Y-198844D01*
X2525500Y-200927D01*
X2524105Y-202386D01*
X2523175Y-204469D01*
X2522865Y-206344D01*
X2529375D01*
G01X2535110Y-204469D02*
X2536040Y-205511D01*
X2537125Y-206136D01*
X2538520Y-206344D01*
X2539915Y-205927D01*
X2541000Y-205094D01*
X2541775Y-203636D01*
X2541930Y-201969D01*
X2541620Y-200302D01*
X2540845Y-199261D01*
X2539760Y-198427D01*
X2538675Y-198219D01*
X2537590Y-198427D01*
X2536195Y-199261D01*
X2536660Y-193844D01*
X2540845D01*
G01X2550920Y-206761D02*
X2550610Y-206552D01*
Y-206136D01*
X2550920Y-205927D01*
X2551230Y-206136D01*
Y-206552D01*
X2550920Y-206761D01*
G01X2563320Y-193844D02*
X2562080Y-194261D01*
X2561150Y-195302D01*
X2560530Y-196552D01*
X2560065Y-198219D01*
X2559910Y-200094D01*
X2560065Y-201969D01*
X2560530Y-203636D01*
X2561150Y-204886D01*
X2562080Y-205927D01*
X2563320Y-206344D01*
X2564560Y-205927D01*
X2565490Y-204886D01*
X2566110Y-203636D01*
X2566575Y-201969D01*
X2566730Y-200094D01*
X2566575Y-198219D01*
X2566110Y-196552D01*
X2565490Y-195302D01*
X2564560Y-194261D01*
X2563320Y-193844D01*
G01X2513720Y-147244D02*
Y-134744D01*
X2511860Y-137244D01*
G01Y-147244D02*
X2515580D01*
G01X2523175Y-136827D02*
X2524105Y-135578D01*
X2525190Y-134952D01*
X2526430Y-134744D01*
X2527980Y-135161D01*
X2529065Y-136202D01*
X2529375Y-137452D01*
X2529220Y-138703D01*
X2528600Y-139744D01*
X2525500Y-141827D01*
X2524105Y-143286D01*
X2523175Y-145369D01*
X2522865Y-147244D01*
X2529375D01*
G01X2535110Y-145369D02*
X2536040Y-146411D01*
X2537125Y-147036D01*
X2538520Y-147244D01*
X2539915Y-146827D01*
X2541000Y-145994D01*
X2541775Y-144536D01*
X2541930Y-142869D01*
X2541620Y-141202D01*
X2540845Y-140161D01*
X2539760Y-139327D01*
X2538675Y-139119D01*
X2537590Y-139327D01*
X2536195Y-140161D01*
X2536660Y-134744D01*
X2540845D01*
G01X2550920Y-147661D02*
X2550610Y-147452D01*
Y-147036D01*
X2550920Y-146827D01*
X2551230Y-147036D01*
Y-147452D01*
X2550920Y-147661D01*
G01X2563320Y-134744D02*
X2562080Y-135161D01*
X2561150Y-136202D01*
X2560530Y-137452D01*
X2560065Y-139119D01*
X2559910Y-140994D01*
X2560065Y-142869D01*
X2560530Y-144536D01*
X2561150Y-145786D01*
X2562080Y-146827D01*
X2563320Y-147244D01*
X2564560Y-146827D01*
X2565490Y-145786D01*
X2566110Y-144536D01*
X2566575Y-142869D01*
X2566730Y-140994D01*
X2566575Y-139119D01*
X2566110Y-137452D01*
X2565490Y-136202D01*
X2564560Y-135161D01*
X2563320Y-134744D01*
G01X2513720Y-88144D02*
Y-75644D01*
X2511860Y-78144D01*
G01Y-88144D02*
X2515580D01*
G01X2523175Y-77727D02*
X2524105Y-76478D01*
X2525190Y-75852D01*
X2526430Y-75644D01*
X2527980Y-76061D01*
X2529065Y-77102D01*
X2529375Y-78352D01*
X2529220Y-79603D01*
X2528600Y-80644D01*
X2525500Y-82727D01*
X2524105Y-84186D01*
X2523175Y-86269D01*
X2522865Y-88144D01*
X2529375D01*
G01X2535575Y-77727D02*
X2536505Y-76478D01*
X2537590Y-75852D01*
X2538830Y-75644D01*
X2540380Y-76061D01*
X2541465Y-77102D01*
X2541775Y-78352D01*
X2541620Y-79603D01*
X2541000Y-80644D01*
X2537900Y-82727D01*
X2536505Y-84186D01*
X2535575Y-86269D01*
X2535265Y-88144D01*
X2541775D01*
G01X2550920Y-88561D02*
X2550610Y-88352D01*
Y-87936D01*
X2550920Y-87727D01*
X2551230Y-87936D01*
Y-88352D01*
X2550920Y-88561D01*
G01X2563320Y-75644D02*
X2562080Y-76061D01*
X2561150Y-77102D01*
X2560530Y-78352D01*
X2560065Y-80019D01*
X2559910Y-81894D01*
X2560065Y-83769D01*
X2560530Y-85436D01*
X2561150Y-86686D01*
X2562080Y-87727D01*
X2563320Y-88144D01*
X2564560Y-87727D01*
X2565490Y-86686D01*
X2566110Y-85436D01*
X2566575Y-83769D01*
X2566730Y-81894D01*
X2566575Y-80019D01*
X2566110Y-78352D01*
X2565490Y-77102D01*
X2564560Y-76061D01*
X2563320Y-75644D01*
G01X2513720Y-29044D02*
Y-16544D01*
X2511860Y-19044D01*
G01Y-29044D02*
X2515580D01*
G01X2523175Y-18627D02*
X2524105Y-17378D01*
X2525190Y-16752D01*
X2526430Y-16544D01*
X2527980Y-16961D01*
X2529065Y-18002D01*
X2529375Y-19252D01*
X2529220Y-20503D01*
X2528600Y-21544D01*
X2525500Y-23627D01*
X2524105Y-25086D01*
X2523175Y-27169D01*
X2522865Y-29044D01*
X2529375D01*
G01X2538520Y-16544D02*
X2537280Y-16961D01*
X2536350Y-18002D01*
X2535730Y-19252D01*
X2535265Y-20919D01*
X2535110Y-22794D01*
X2535265Y-24669D01*
X2535730Y-26336D01*
X2536350Y-27586D01*
X2537280Y-28627D01*
X2538520Y-29044D01*
X2539760Y-28627D01*
X2540690Y-27586D01*
X2541310Y-26336D01*
X2541775Y-24669D01*
X2541930Y-22794D01*
X2541775Y-20919D01*
X2541310Y-19252D01*
X2540690Y-18002D01*
X2539760Y-16961D01*
X2538520Y-16544D01*
G01X2550920Y-29461D02*
X2550610Y-29252D01*
Y-28836D01*
X2550920Y-28627D01*
X2551230Y-28836D01*
Y-29252D01*
X2550920Y-29461D01*
G01X2563320Y-16544D02*
X2562080Y-16961D01*
X2561150Y-18002D01*
X2560530Y-19252D01*
X2560065Y-20919D01*
X2559910Y-22794D01*
X2560065Y-24669D01*
X2560530Y-26336D01*
X2561150Y-27586D01*
X2562080Y-28627D01*
X2563320Y-29044D01*
X2564560Y-28627D01*
X2565490Y-27586D01*
X2566110Y-26336D01*
X2566575Y-24669D01*
X2566730Y-22794D01*
X2566575Y-20919D01*
X2566110Y-19252D01*
X2565490Y-18002D01*
X2564560Y-16961D01*
X2563320Y-16544D01*
G01X2510775Y395073D02*
X2511705Y396322D01*
X2512790Y396948D01*
X2514030Y397156D01*
X2515580Y396739D01*
X2516665Y395698D01*
X2516975Y394448D01*
X2516820Y393197D01*
X2516200Y392156D01*
X2513100Y390073D01*
X2511705Y388614D01*
X2510775Y386531D01*
X2510465Y384656D01*
X2516975D01*
G01X2523175Y395073D02*
X2524105Y396322D01*
X2525190Y396948D01*
X2526430Y397156D01*
X2527980Y396739D01*
X2529065Y395698D01*
X2529375Y394448D01*
X2529220Y393197D01*
X2528600Y392156D01*
X2525500Y390073D01*
X2524105Y388614D01*
X2523175Y386531D01*
X2522865Y384656D01*
X2529375D01*
G01X2538520D02*
Y397156D01*
X2536660Y394656D01*
G01Y384656D02*
X2540380D01*
G01X2550920Y384239D02*
X2550610Y384448D01*
Y384864D01*
X2550920Y385073D01*
X2551230Y384864D01*
Y384448D01*
X2550920Y384239D01*
G01X2563320Y397156D02*
X2562080Y396739D01*
X2561150Y395698D01*
X2560530Y394448D01*
X2560065Y392781D01*
X2559910Y390906D01*
X2560065Y389031D01*
X2560530Y387364D01*
X2561150Y386114D01*
X2562080Y385073D01*
X2563320Y384656D01*
X2564560Y385073D01*
X2565490Y386114D01*
X2566110Y387364D01*
X2566575Y389031D01*
X2566730Y390906D01*
X2566575Y392781D01*
X2566110Y394448D01*
X2565490Y395698D01*
X2564560Y396739D01*
X2563320Y397156D01*
G01X2513720Y443756D02*
Y456256D01*
X2511860Y453756D01*
G01Y443756D02*
X2515580D01*
G01X2523175Y448964D02*
X2524260Y450423D01*
X2525190Y451256D01*
X2526430Y451673D01*
X2527515Y451256D01*
X2528290Y450423D01*
X2528910Y449173D01*
X2529065Y447714D01*
X2528910Y446464D01*
X2528290Y445214D01*
X2527360Y444173D01*
X2526275Y443756D01*
X2525035Y444173D01*
X2523950Y445422D01*
X2523330Y447298D01*
X2523175Y449381D01*
X2523485Y452089D01*
X2523950Y453548D01*
X2524725Y455006D01*
X2525810Y456048D01*
X2526895Y456256D01*
X2527980Y455839D01*
X2528755Y454798D01*
G01X2535575Y448964D02*
X2536660Y450423D01*
X2537590Y451256D01*
X2538830Y451673D01*
X2539915Y451256D01*
X2540690Y450423D01*
X2541310Y449173D01*
X2541465Y447714D01*
X2541310Y446464D01*
X2540690Y445214D01*
X2539760Y444173D01*
X2538675Y443756D01*
X2537435Y444173D01*
X2536350Y445422D01*
X2535730Y447298D01*
X2535575Y449381D01*
X2535885Y452089D01*
X2536350Y453548D01*
X2537125Y455006D01*
X2538210Y456048D01*
X2539295Y456256D01*
X2540380Y455839D01*
X2541155Y454798D01*
G01X2550920Y443339D02*
X2550610Y443548D01*
Y443964D01*
X2550920Y444173D01*
X2551230Y443964D01*
Y443548D01*
X2550920Y443339D01*
G01X2563320Y456256D02*
X2562080Y455839D01*
X2561150Y454798D01*
X2560530Y453548D01*
X2560065Y451881D01*
X2559910Y450006D01*
X2560065Y448131D01*
X2560530Y446464D01*
X2561150Y445214D01*
X2562080Y444173D01*
X2563320Y443756D01*
X2564560Y444173D01*
X2565490Y445214D01*
X2566110Y446464D01*
X2566575Y448131D01*
X2566730Y450006D01*
X2566575Y451881D01*
X2566110Y453548D01*
X2565490Y454798D01*
X2564560Y455839D01*
X2563320Y456256D01*
G01X2513720Y502856D02*
Y515356D01*
X2511860Y512856D01*
G01Y502856D02*
X2515580D01*
G01X2522710Y504731D02*
X2523640Y503689D01*
X2524725Y503064D01*
X2526120Y502856D01*
X2527515Y503273D01*
X2528600Y504106D01*
X2529375Y505564D01*
X2529530Y507231D01*
X2529220Y508898D01*
X2528445Y509939D01*
X2527360Y510773D01*
X2526275Y510981D01*
X2525190Y510773D01*
X2523795Y509939D01*
X2524260Y515356D01*
X2528445D01*
G01X2538520D02*
X2537280Y514939D01*
X2536350Y513898D01*
X2535730Y512648D01*
X2535265Y510981D01*
X2535110Y509106D01*
X2535265Y507231D01*
X2535730Y505564D01*
X2536350Y504314D01*
X2537280Y503273D01*
X2538520Y502856D01*
X2539760Y503273D01*
X2540690Y504314D01*
X2541310Y505564D01*
X2541775Y507231D01*
X2541930Y509106D01*
X2541775Y510981D01*
X2541310Y512648D01*
X2540690Y513898D01*
X2539760Y514939D01*
X2538520Y515356D01*
G01X2550920Y502439D02*
X2550610Y502648D01*
Y503064D01*
X2550920Y503273D01*
X2551230Y503064D01*
Y502648D01*
X2550920Y502439D01*
G01X2563320Y515356D02*
X2562080Y514939D01*
X2561150Y513898D01*
X2560530Y512648D01*
X2560065Y510981D01*
X2559910Y509106D01*
X2560065Y507231D01*
X2560530Y505564D01*
X2561150Y504314D01*
X2562080Y503273D01*
X2563320Y502856D01*
X2564560Y503273D01*
X2565490Y504314D01*
X2566110Y505564D01*
X2566575Y507231D01*
X2566730Y509106D01*
X2566575Y510981D01*
X2566110Y512648D01*
X2565490Y513898D01*
X2564560Y514939D01*
X2563320Y515356D01*
G01X2513720Y561956D02*
Y574456D01*
X2511860Y571956D01*
G01Y561956D02*
X2515580D01*
G01X2527980D02*
Y574456D01*
X2522245Y565498D01*
X2529995D01*
G01X2538210Y561956D02*
X2538520Y564664D01*
X2538985Y566956D01*
X2539605Y569039D01*
X2540380Y571331D01*
X2541620Y574456D01*
X2535420D01*
G01X2550920Y561539D02*
X2550610Y561748D01*
Y562164D01*
X2550920Y562373D01*
X2551230Y562164D01*
Y561748D01*
X2550920Y561539D01*
G01X2563320Y574456D02*
X2562080Y574039D01*
X2561150Y572998D01*
X2560530Y571748D01*
X2560065Y570081D01*
X2559910Y568206D01*
X2560065Y566331D01*
X2560530Y564664D01*
X2561150Y563414D01*
X2562080Y562373D01*
X2563320Y561956D01*
X2564560Y562373D01*
X2565490Y563414D01*
X2566110Y564664D01*
X2566575Y566331D01*
X2566730Y568206D01*
X2566575Y570081D01*
X2566110Y571748D01*
X2565490Y572998D01*
X2564560Y574039D01*
X2563320Y574456D01*
G01X2515580Y916556D02*
Y929056D01*
X2509845Y920098D01*
X2517595D01*
G01X2526120Y929056D02*
X2524880Y928639D01*
X2523950Y927598D01*
X2523330Y926348D01*
X2522865Y924681D01*
X2522710Y922806D01*
X2522865Y920931D01*
X2523330Y919264D01*
X2523950Y918014D01*
X2524880Y916973D01*
X2526120Y916556D01*
X2527360Y916973D01*
X2528290Y918014D01*
X2528910Y919264D01*
X2529375Y920931D01*
X2529530Y922806D01*
X2529375Y924681D01*
X2528910Y926348D01*
X2528290Y927598D01*
X2527360Y928639D01*
X2526120Y929056D01*
G01X2538520Y916139D02*
X2538210Y916348D01*
Y916764D01*
X2538520Y916973D01*
X2538830Y916764D01*
Y916348D01*
X2538520Y916139D01*
G01X2550920Y916556D02*
Y929056D01*
X2549060Y926556D01*
G01Y916556D02*
X2552780D01*
G01X2559910Y918431D02*
X2560840Y917389D01*
X2561925Y916764D01*
X2563320Y916556D01*
X2564715Y916973D01*
X2565800Y917806D01*
X2566575Y919264D01*
X2566730Y920931D01*
X2566420Y922598D01*
X2565645Y923639D01*
X2564560Y924473D01*
X2563475Y924681D01*
X2562390Y924473D01*
X2560995Y923639D01*
X2561460Y929056D01*
X2565645D01*
G01X2513720Y1212056D02*
Y1224556D01*
X2511860Y1222056D01*
G01Y1212056D02*
X2515580D01*
G01X2523485Y1213514D02*
X2524570Y1212473D01*
X2525810Y1212056D01*
X2527050Y1212473D01*
X2528135Y1213722D01*
X2528910Y1215598D01*
X2529220Y1217473D01*
Y1219764D01*
X2528910Y1221639D01*
X2528135Y1223306D01*
X2527205Y1224139D01*
X2526120Y1224556D01*
X2524880Y1224139D01*
X2523950Y1223306D01*
X2523330Y1222056D01*
X2523020Y1220389D01*
X2523330Y1218931D01*
X2524105Y1217473D01*
X2525035Y1216639D01*
X2526120Y1216431D01*
X2527360Y1216847D01*
X2528290Y1217889D01*
X2529220Y1219764D01*
G01X2538520Y1211639D02*
X2538210Y1211848D01*
Y1212264D01*
X2538520Y1212473D01*
X2538830Y1212264D01*
Y1211848D01*
X2538520Y1211639D01*
G01X2547975Y1217264D02*
X2549060Y1218723D01*
X2549990Y1219556D01*
X2551230Y1219973D01*
X2552315Y1219556D01*
X2553090Y1218723D01*
X2553710Y1217473D01*
X2553865Y1216014D01*
X2553710Y1214764D01*
X2553090Y1213514D01*
X2552160Y1212473D01*
X2551075Y1212056D01*
X2549835Y1212473D01*
X2548750Y1213722D01*
X2548130Y1215598D01*
X2547975Y1217681D01*
X2548285Y1220389D01*
X2548750Y1221848D01*
X2549525Y1223306D01*
X2550610Y1224348D01*
X2551695Y1224556D01*
X2552780Y1224139D01*
X2553555Y1223098D01*
G01X2563320Y1212056D02*
X2564405Y1212264D01*
X2565645Y1212889D01*
X2566420Y1213931D01*
X2566730Y1215389D01*
X2566420Y1216847D01*
X2565490Y1218098D01*
X2564095Y1218723D01*
X2562545D01*
X2561615Y1219139D01*
X2560840Y1220181D01*
X2560530Y1221639D01*
X2560995Y1223098D01*
X2562080Y1224139D01*
X2563320Y1224556D01*
X2564560Y1224139D01*
X2565645Y1223098D01*
X2566110Y1221639D01*
X2565800Y1220181D01*
X2565025Y1219139D01*
X2564095Y1218723D01*
X2562545D01*
X2561150Y1218098D01*
X2560220Y1216847D01*
X2559910Y1215389D01*
X2560220Y1213931D01*
X2560995Y1212889D01*
X2562235Y1212264D01*
X2563320Y1212056D01*
G01X2513720Y1271156D02*
Y1283656D01*
X2511860Y1281156D01*
G01Y1271156D02*
X2515580D01*
G01X2527980D02*
Y1283656D01*
X2522245Y1274698D01*
X2529995D01*
G01X2538520Y1270739D02*
X2538210Y1270948D01*
Y1271364D01*
X2538520Y1271573D01*
X2538830Y1271364D01*
Y1270948D01*
X2538520Y1270739D01*
G01X2550920Y1271156D02*
Y1283656D01*
X2549060Y1281156D01*
G01Y1271156D02*
X2552780D01*
G01X2563010D02*
X2563320Y1273864D01*
X2563785Y1276156D01*
X2564405Y1278239D01*
X2565180Y1280531D01*
X2566420Y1283656D01*
X2560220D01*
G01X2516975Y35264D02*
X2518060Y36723D01*
X2518990Y37556D01*
X2520230Y37973D01*
X2521315Y37556D01*
X2522090Y36723D01*
X2522710Y35473D01*
X2522865Y34014D01*
X2522710Y32764D01*
X2522090Y31514D01*
X2521160Y30473D01*
X2520075Y30056D01*
X2518835Y30473D01*
X2517750Y31722D01*
X2517130Y33598D01*
X2516975Y35681D01*
X2517285Y38389D01*
X2517750Y39848D01*
X2518525Y41306D01*
X2519610Y42348D01*
X2520695Y42556D01*
X2521780Y42139D01*
X2522555Y41098D01*
G01X2528910Y31931D02*
X2529840Y30889D01*
X2530925Y30264D01*
X2532320Y30056D01*
X2533715Y30473D01*
X2534800Y31306D01*
X2535575Y32764D01*
X2535730Y34431D01*
X2535420Y36098D01*
X2534645Y37139D01*
X2533560Y37973D01*
X2532475Y38181D01*
X2531390Y37973D01*
X2529995Y37139D01*
X2530460Y42556D01*
X2534645D01*
G01X2544720Y29639D02*
X2544410Y29848D01*
Y30264D01*
X2544720Y30473D01*
X2545030Y30264D01*
Y29848D01*
X2544720Y29639D01*
G01X2557120Y42556D02*
X2555880Y42139D01*
X2554950Y41098D01*
X2554330Y39848D01*
X2553865Y38181D01*
X2553710Y36306D01*
X2553865Y34431D01*
X2554330Y32764D01*
X2554950Y31514D01*
X2555880Y30473D01*
X2557120Y30056D01*
X2558360Y30473D01*
X2559290Y31514D01*
X2559910Y32764D01*
X2560375Y34431D01*
X2560530Y36306D01*
X2560375Y38181D01*
X2559910Y39848D01*
X2559290Y41098D01*
X2558360Y42139D01*
X2557120Y42556D01*
G01X2521780Y89156D02*
Y101656D01*
X2516045Y92698D01*
X2523795D01*
G01X2529375Y94364D02*
X2530460Y95823D01*
X2531390Y96656D01*
X2532630Y97073D01*
X2533715Y96656D01*
X2534490Y95823D01*
X2535110Y94573D01*
X2535265Y93114D01*
X2535110Y91864D01*
X2534490Y90614D01*
X2533560Y89573D01*
X2532475Y89156D01*
X2531235Y89573D01*
X2530150Y90822D01*
X2529530Y92698D01*
X2529375Y94781D01*
X2529685Y97489D01*
X2530150Y98948D01*
X2530925Y100406D01*
X2532010Y101448D01*
X2533095Y101656D01*
X2534180Y101239D01*
X2534955Y100198D01*
G01X2544720Y88739D02*
X2544410Y88948D01*
Y89364D01*
X2544720Y89573D01*
X2545030Y89364D01*
Y88948D01*
X2544720Y88739D01*
G01X2557120Y101656D02*
X2555880Y101239D01*
X2554950Y100198D01*
X2554330Y98948D01*
X2553865Y97281D01*
X2553710Y95406D01*
X2553865Y93531D01*
X2554330Y91864D01*
X2554950Y90614D01*
X2555880Y89573D01*
X2557120Y89156D01*
X2558360Y89573D01*
X2559290Y90614D01*
X2559910Y91864D01*
X2560375Y93531D01*
X2560530Y95406D01*
X2560375Y97281D01*
X2559910Y98948D01*
X2559290Y100198D01*
X2558360Y101239D01*
X2557120Y101656D01*
G01X2521780Y148256D02*
Y160756D01*
X2516045Y151798D01*
X2523795D01*
G01X2528910Y150131D02*
X2529840Y149089D01*
X2530925Y148464D01*
X2532320Y148256D01*
X2533715Y148673D01*
X2534800Y149506D01*
X2535575Y150964D01*
X2535730Y152631D01*
X2535420Y154298D01*
X2534645Y155339D01*
X2533560Y156173D01*
X2532475Y156381D01*
X2531390Y156173D01*
X2529995Y155339D01*
X2530460Y160756D01*
X2534645D01*
G01X2544720Y147839D02*
X2544410Y148048D01*
Y148464D01*
X2544720Y148673D01*
X2545030Y148464D01*
Y148048D01*
X2544720Y147839D01*
G01X2557120Y160756D02*
X2555880Y160339D01*
X2554950Y159298D01*
X2554330Y158048D01*
X2553865Y156381D01*
X2553710Y154506D01*
X2553865Y152631D01*
X2554330Y150964D01*
X2554950Y149714D01*
X2555880Y148673D01*
X2557120Y148256D01*
X2558360Y148673D01*
X2559290Y149714D01*
X2559910Y150964D01*
X2560375Y152631D01*
X2560530Y154506D01*
X2560375Y156381D01*
X2559910Y158048D01*
X2559290Y159298D01*
X2558360Y160339D01*
X2557120Y160756D01*
G01X2521780Y207356D02*
Y219856D01*
X2516045Y210898D01*
X2523795D01*
G01X2534180Y207356D02*
Y219856D01*
X2528445Y210898D01*
X2536195D01*
G01X2544720Y206939D02*
X2544410Y207148D01*
Y207564D01*
X2544720Y207773D01*
X2545030Y207564D01*
Y207148D01*
X2544720Y206939D01*
G01X2557120Y219856D02*
X2555880Y219439D01*
X2554950Y218398D01*
X2554330Y217148D01*
X2553865Y215481D01*
X2553710Y213606D01*
X2553865Y211731D01*
X2554330Y210064D01*
X2554950Y208814D01*
X2555880Y207773D01*
X2557120Y207356D01*
X2558360Y207773D01*
X2559290Y208814D01*
X2559910Y210064D01*
X2560375Y211731D01*
X2560530Y213606D01*
X2560375Y215481D01*
X2559910Y217148D01*
X2559290Y218398D01*
X2558360Y219439D01*
X2557120Y219856D01*
G01X2521780Y266456D02*
Y278956D01*
X2516045Y269998D01*
X2523795D01*
G01X2532320Y266456D02*
Y278956D01*
X2530460Y276456D01*
G01Y266456D02*
X2534180D01*
G01X2544720Y266039D02*
X2544410Y266248D01*
Y266664D01*
X2544720Y266873D01*
X2545030Y266664D01*
Y266248D01*
X2544720Y266039D01*
G01X2557120Y278956D02*
X2555880Y278539D01*
X2554950Y277498D01*
X2554330Y276248D01*
X2553865Y274581D01*
X2553710Y272706D01*
X2553865Y270831D01*
X2554330Y269164D01*
X2554950Y267914D01*
X2555880Y266873D01*
X2557120Y266456D01*
X2558360Y266873D01*
X2559290Y267914D01*
X2559910Y269164D01*
X2560375Y270831D01*
X2560530Y272706D01*
X2560375Y274581D01*
X2559910Y276248D01*
X2559290Y277498D01*
X2558360Y278539D01*
X2557120Y278956D01*
G01X2516510Y328056D02*
X2517440Y326597D01*
X2518680Y325764D01*
X2520075Y325556D01*
X2521315Y325764D01*
X2522555Y326806D01*
X2523330Y328056D01*
X2523485Y329306D01*
X2523175Y330764D01*
X2522090Y331806D01*
X2521005Y332223D01*
X2519610D01*
G01X2521005D02*
X2521935Y332848D01*
X2522710Y333889D01*
X2523020Y335139D01*
X2522710Y336389D01*
X2521935Y337431D01*
X2520540Y338056D01*
X2519145Y337848D01*
X2517750Y337014D01*
G01X2532320Y338056D02*
X2531080Y337639D01*
X2530150Y336598D01*
X2529530Y335348D01*
X2529065Y333681D01*
X2528910Y331806D01*
X2529065Y329931D01*
X2529530Y328264D01*
X2530150Y327014D01*
X2531080Y325973D01*
X2532320Y325556D01*
X2533560Y325973D01*
X2534490Y327014D01*
X2535110Y328264D01*
X2535575Y329931D01*
X2535730Y331806D01*
X2535575Y333681D01*
X2535110Y335348D01*
X2534490Y336598D01*
X2533560Y337639D01*
X2532320Y338056D01*
G01X2544720Y325139D02*
X2544410Y325348D01*
Y325764D01*
X2544720Y325973D01*
X2545030Y325764D01*
Y325348D01*
X2544720Y325139D01*
G01X2557120Y338056D02*
X2555880Y337639D01*
X2554950Y336598D01*
X2554330Y335348D01*
X2553865Y333681D01*
X2553710Y331806D01*
X2553865Y329931D01*
X2554330Y328264D01*
X2554950Y327014D01*
X2555880Y325973D01*
X2557120Y325556D01*
X2558360Y325973D01*
X2559290Y327014D01*
X2559910Y328264D01*
X2560375Y329931D01*
X2560530Y331806D01*
X2560375Y333681D01*
X2559910Y335348D01*
X2559290Y336598D01*
X2558360Y337639D01*
X2557120Y338056D01*
G01X2519610Y621056D02*
X2519920Y623764D01*
X2520385Y626056D01*
X2521005Y628139D01*
X2521780Y630431D01*
X2523020Y633556D01*
X2516820D01*
G01X2529685Y622514D02*
X2530770Y621473D01*
X2532010Y621056D01*
X2533250Y621473D01*
X2534335Y622722D01*
X2535110Y624598D01*
X2535420Y626473D01*
Y628764D01*
X2535110Y630639D01*
X2534335Y632306D01*
X2533405Y633139D01*
X2532320Y633556D01*
X2531080Y633139D01*
X2530150Y632306D01*
X2529530Y631056D01*
X2529220Y629389D01*
X2529530Y627931D01*
X2530305Y626473D01*
X2531235Y625639D01*
X2532320Y625431D01*
X2533560Y625847D01*
X2534490Y626889D01*
X2535420Y628764D01*
G01X2544720Y620639D02*
X2544410Y620848D01*
Y621264D01*
X2544720Y621473D01*
X2545030Y621264D01*
Y620848D01*
X2544720Y620639D01*
G01X2557120Y633556D02*
X2555880Y633139D01*
X2554950Y632098D01*
X2554330Y630848D01*
X2553865Y629181D01*
X2553710Y627306D01*
X2553865Y625431D01*
X2554330Y623764D01*
X2554950Y622514D01*
X2555880Y621473D01*
X2557120Y621056D01*
X2558360Y621473D01*
X2559290Y622514D01*
X2559910Y623764D01*
X2560375Y625431D01*
X2560530Y627306D01*
X2560375Y629181D01*
X2559910Y630848D01*
X2559290Y632098D01*
X2558360Y633139D01*
X2557120Y633556D01*
G01X2516975Y685364D02*
X2518060Y686823D01*
X2518990Y687656D01*
X2520230Y688073D01*
X2521315Y687656D01*
X2522090Y686823D01*
X2522710Y685573D01*
X2522865Y684114D01*
X2522710Y682864D01*
X2522090Y681614D01*
X2521160Y680573D01*
X2520075Y680156D01*
X2518835Y680573D01*
X2517750Y681822D01*
X2517130Y683698D01*
X2516975Y685781D01*
X2517285Y688489D01*
X2517750Y689948D01*
X2518525Y691406D01*
X2519610Y692448D01*
X2520695Y692656D01*
X2521780Y692239D01*
X2522555Y691198D01*
G01X2532010Y680156D02*
X2532320Y682864D01*
X2532785Y685156D01*
X2533405Y687239D01*
X2534180Y689531D01*
X2535420Y692656D01*
X2529220D01*
G01X2544720Y679739D02*
X2544410Y679948D01*
Y680364D01*
X2544720Y680573D01*
X2545030Y680364D01*
Y679948D01*
X2544720Y679739D01*
G01X2557120Y692656D02*
X2555880Y692239D01*
X2554950Y691198D01*
X2554330Y689948D01*
X2553865Y688281D01*
X2553710Y686406D01*
X2553865Y684531D01*
X2554330Y682864D01*
X2554950Y681614D01*
X2555880Y680573D01*
X2557120Y680156D01*
X2558360Y680573D01*
X2559290Y681614D01*
X2559910Y682864D01*
X2560375Y684531D01*
X2560530Y686406D01*
X2560375Y688281D01*
X2559910Y689948D01*
X2559290Y691198D01*
X2558360Y692239D01*
X2557120Y692656D01*
G01X2521780Y739256D02*
Y751756D01*
X2516045Y742798D01*
X2523795D01*
G01X2529375Y744464D02*
X2530460Y745923D01*
X2531390Y746756D01*
X2532630Y747173D01*
X2533715Y746756D01*
X2534490Y745923D01*
X2535110Y744673D01*
X2535265Y743214D01*
X2535110Y741964D01*
X2534490Y740714D01*
X2533560Y739673D01*
X2532475Y739256D01*
X2531235Y739673D01*
X2530150Y740922D01*
X2529530Y742798D01*
X2529375Y744881D01*
X2529685Y747589D01*
X2530150Y749048D01*
X2530925Y750506D01*
X2532010Y751548D01*
X2533095Y751756D01*
X2534180Y751339D01*
X2534955Y750298D01*
G01X2544720Y738839D02*
X2544410Y739048D01*
Y739464D01*
X2544720Y739673D01*
X2545030Y739464D01*
Y739048D01*
X2544720Y738839D01*
G01X2557120Y751756D02*
X2555880Y751339D01*
X2554950Y750298D01*
X2554330Y749048D01*
X2553865Y747381D01*
X2553710Y745506D01*
X2553865Y743631D01*
X2554330Y741964D01*
X2554950Y740714D01*
X2555880Y739673D01*
X2557120Y739256D01*
X2558360Y739673D01*
X2559290Y740714D01*
X2559910Y741964D01*
X2560375Y743631D01*
X2560530Y745506D01*
X2560375Y747381D01*
X2559910Y749048D01*
X2559290Y750298D01*
X2558360Y751339D01*
X2557120Y751756D01*
G01X2521780Y798356D02*
Y810856D01*
X2516045Y801898D01*
X2523795D01*
G01X2534180Y798356D02*
Y810856D01*
X2528445Y801898D01*
X2536195D01*
G01X2544720Y797939D02*
X2544410Y798148D01*
Y798564D01*
X2544720Y798773D01*
X2545030Y798564D01*
Y798148D01*
X2544720Y797939D01*
G01X2557120Y810856D02*
X2555880Y810439D01*
X2554950Y809398D01*
X2554330Y808148D01*
X2553865Y806481D01*
X2553710Y804606D01*
X2553865Y802731D01*
X2554330Y801064D01*
X2554950Y799814D01*
X2555880Y798773D01*
X2557120Y798356D01*
X2558360Y798773D01*
X2559290Y799814D01*
X2559910Y801064D01*
X2560375Y802731D01*
X2560530Y804606D01*
X2560375Y806481D01*
X2559910Y808148D01*
X2559290Y809398D01*
X2558360Y810439D01*
X2557120Y810856D01*
G01X2521780Y857456D02*
Y869956D01*
X2516045Y860998D01*
X2523795D01*
G01X2532320Y857456D02*
Y869956D01*
X2530460Y867456D01*
G01Y857456D02*
X2534180D01*
G01X2544720Y857039D02*
X2544410Y857248D01*
Y857664D01*
X2544720Y857873D01*
X2545030Y857664D01*
Y857248D01*
X2544720Y857039D01*
G01X2557120Y869956D02*
X2555880Y869539D01*
X2554950Y868498D01*
X2554330Y867248D01*
X2553865Y865581D01*
X2553710Y863706D01*
X2553865Y861831D01*
X2554330Y860164D01*
X2554950Y858914D01*
X2555880Y857873D01*
X2557120Y857456D01*
X2558360Y857873D01*
X2559290Y858914D01*
X2559910Y860164D01*
X2560375Y861831D01*
X2560530Y863706D01*
X2560375Y865581D01*
X2559910Y867248D01*
X2559290Y868498D01*
X2558360Y869539D01*
X2557120Y869956D01*
G01X2521780Y975656D02*
Y988156D01*
X2516045Y979198D01*
X2523795D01*
G01X2532320Y988156D02*
X2531080Y987739D01*
X2530150Y986698D01*
X2529530Y985448D01*
X2529065Y983781D01*
X2528910Y981906D01*
X2529065Y980031D01*
X2529530Y978364D01*
X2530150Y977114D01*
X2531080Y976073D01*
X2532320Y975656D01*
X2533560Y976073D01*
X2534490Y977114D01*
X2535110Y978364D01*
X2535575Y980031D01*
X2535730Y981906D01*
X2535575Y983781D01*
X2535110Y985448D01*
X2534490Y986698D01*
X2533560Y987739D01*
X2532320Y988156D01*
G01X2544720Y975239D02*
X2544410Y975448D01*
Y975864D01*
X2544720Y976073D01*
X2545030Y975864D01*
Y975448D01*
X2544720Y975239D01*
G01X2557120Y988156D02*
X2555880Y987739D01*
X2554950Y986698D01*
X2554330Y985448D01*
X2553865Y983781D01*
X2553710Y981906D01*
X2553865Y980031D01*
X2554330Y978364D01*
X2554950Y977114D01*
X2555880Y976073D01*
X2557120Y975656D01*
X2558360Y976073D01*
X2559290Y977114D01*
X2559910Y978364D01*
X2560375Y980031D01*
X2560530Y981906D01*
X2560375Y983781D01*
X2559910Y985448D01*
X2559290Y986698D01*
X2558360Y987739D01*
X2557120Y988156D01*
G01X2521780Y1034756D02*
Y1047256D01*
X2516045Y1038298D01*
X2523795D01*
G01X2532320Y1047256D02*
X2531080Y1046839D01*
X2530150Y1045798D01*
X2529530Y1044548D01*
X2529065Y1042881D01*
X2528910Y1041006D01*
X2529065Y1039131D01*
X2529530Y1037464D01*
X2530150Y1036214D01*
X2531080Y1035173D01*
X2532320Y1034756D01*
X2533560Y1035173D01*
X2534490Y1036214D01*
X2535110Y1037464D01*
X2535575Y1039131D01*
X2535730Y1041006D01*
X2535575Y1042881D01*
X2535110Y1044548D01*
X2534490Y1045798D01*
X2533560Y1046839D01*
X2532320Y1047256D01*
G01X2544720Y1034339D02*
X2544410Y1034548D01*
Y1034964D01*
X2544720Y1035173D01*
X2545030Y1034964D01*
Y1034548D01*
X2544720Y1034339D01*
G01X2557120Y1047256D02*
X2555880Y1046839D01*
X2554950Y1045798D01*
X2554330Y1044548D01*
X2553865Y1042881D01*
X2553710Y1041006D01*
X2553865Y1039131D01*
X2554330Y1037464D01*
X2554950Y1036214D01*
X2555880Y1035173D01*
X2557120Y1034756D01*
X2558360Y1035173D01*
X2559290Y1036214D01*
X2559910Y1037464D01*
X2560375Y1039131D01*
X2560530Y1041006D01*
X2560375Y1042881D01*
X2559910Y1044548D01*
X2559290Y1045798D01*
X2558360Y1046839D01*
X2557120Y1047256D01*
G01X2516510Y1096356D02*
X2517440Y1094897D01*
X2518680Y1094064D01*
X2520075Y1093856D01*
X2521315Y1094064D01*
X2522555Y1095106D01*
X2523330Y1096356D01*
X2523485Y1097606D01*
X2523175Y1099064D01*
X2522090Y1100106D01*
X2521005Y1100523D01*
X2519610D01*
G01X2521005D02*
X2521935Y1101148D01*
X2522710Y1102189D01*
X2523020Y1103439D01*
X2522710Y1104689D01*
X2521935Y1105731D01*
X2520540Y1106356D01*
X2519145Y1106148D01*
X2517750Y1105314D01*
G01X2529375Y1104273D02*
X2530305Y1105522D01*
X2531390Y1106148D01*
X2532630Y1106356D01*
X2534180Y1105939D01*
X2535265Y1104898D01*
X2535575Y1103648D01*
X2535420Y1102397D01*
X2534800Y1101356D01*
X2531700Y1099273D01*
X2530305Y1097814D01*
X2529375Y1095731D01*
X2529065Y1093856D01*
X2535575D01*
G01X2544720Y1093439D02*
X2544410Y1093648D01*
Y1094064D01*
X2544720Y1094273D01*
X2545030Y1094064D01*
Y1093648D01*
X2544720Y1093439D01*
G01X2557120Y1106356D02*
X2555880Y1105939D01*
X2554950Y1104898D01*
X2554330Y1103648D01*
X2553865Y1101981D01*
X2553710Y1100106D01*
X2553865Y1098231D01*
X2554330Y1096564D01*
X2554950Y1095314D01*
X2555880Y1094273D01*
X2557120Y1093856D01*
X2558360Y1094273D01*
X2559290Y1095314D01*
X2559910Y1096564D01*
X2560375Y1098231D01*
X2560530Y1100106D01*
X2560375Y1101981D01*
X2559910Y1103648D01*
X2559290Y1104898D01*
X2558360Y1105939D01*
X2557120Y1106356D01*
G01X2516975Y1163373D02*
X2517905Y1164622D01*
X2518990Y1165248D01*
X2520230Y1165456D01*
X2521780Y1165039D01*
X2522865Y1163998D01*
X2523175Y1162748D01*
X2523020Y1161497D01*
X2522400Y1160456D01*
X2519300Y1158373D01*
X2517905Y1156914D01*
X2516975Y1154831D01*
X2516665Y1152956D01*
X2523175D01*
G01X2529375Y1163373D02*
X2530305Y1164622D01*
X2531390Y1165248D01*
X2532630Y1165456D01*
X2534180Y1165039D01*
X2535265Y1163998D01*
X2535575Y1162748D01*
X2535420Y1161497D01*
X2534800Y1160456D01*
X2531700Y1158373D01*
X2530305Y1156914D01*
X2529375Y1154831D01*
X2529065Y1152956D01*
X2535575D01*
G01X2544720Y1152539D02*
X2544410Y1152748D01*
Y1153164D01*
X2544720Y1153373D01*
X2545030Y1153164D01*
Y1152748D01*
X2544720Y1152539D01*
G01X2557120Y1165456D02*
X2555880Y1165039D01*
X2554950Y1163998D01*
X2554330Y1162748D01*
X2553865Y1161081D01*
X2553710Y1159206D01*
X2553865Y1157331D01*
X2554330Y1155664D01*
X2554950Y1154414D01*
X2555880Y1153373D01*
X2557120Y1152956D01*
X2558360Y1153373D01*
X2559290Y1154414D01*
X2559910Y1155664D01*
X2560375Y1157331D01*
X2560530Y1159206D01*
X2560375Y1161081D01*
X2559910Y1162748D01*
X2559290Y1163998D01*
X2558360Y1165039D01*
X2557120Y1165456D01*
G01X2519920Y1330256D02*
Y1342756D01*
X2518060Y1340256D01*
G01Y1330256D02*
X2521780D01*
G01X2532320Y1342756D02*
X2531080Y1342339D01*
X2530150Y1341298D01*
X2529530Y1340048D01*
X2529065Y1338381D01*
X2528910Y1336506D01*
X2529065Y1334631D01*
X2529530Y1332964D01*
X2530150Y1331714D01*
X2531080Y1330673D01*
X2532320Y1330256D01*
X2533560Y1330673D01*
X2534490Y1331714D01*
X2535110Y1332964D01*
X2535575Y1334631D01*
X2535730Y1336506D01*
X2535575Y1338381D01*
X2535110Y1340048D01*
X2534490Y1341298D01*
X2533560Y1342339D01*
X2532320Y1342756D01*
G01X2544720Y1329839D02*
X2544410Y1330048D01*
Y1330464D01*
X2544720Y1330673D01*
X2545030Y1330464D01*
Y1330048D01*
X2544720Y1329839D01*
G01X2557120Y1342756D02*
X2555880Y1342339D01*
X2554950Y1341298D01*
X2554330Y1340048D01*
X2553865Y1338381D01*
X2553710Y1336506D01*
X2553865Y1334631D01*
X2554330Y1332964D01*
X2554950Y1331714D01*
X2555880Y1330673D01*
X2557120Y1330256D01*
X2558360Y1330673D01*
X2559290Y1331714D01*
X2559910Y1332964D01*
X2560375Y1334631D01*
X2560530Y1336506D01*
X2560375Y1338381D01*
X2559910Y1340048D01*
X2559290Y1341298D01*
X2558360Y1342339D01*
X2557120Y1342756D01*
G01X2519920Y1389356D02*
Y1401856D01*
X2518060Y1399356D01*
G01Y1389356D02*
X2521780D01*
G01X2532320Y1401856D02*
X2531080Y1401439D01*
X2530150Y1400398D01*
X2529530Y1399148D01*
X2529065Y1397481D01*
X2528910Y1395606D01*
X2529065Y1393731D01*
X2529530Y1392064D01*
X2530150Y1390814D01*
X2531080Y1389773D01*
X2532320Y1389356D01*
X2533560Y1389773D01*
X2534490Y1390814D01*
X2535110Y1392064D01*
X2535575Y1393731D01*
X2535730Y1395606D01*
X2535575Y1397481D01*
X2535110Y1399148D01*
X2534490Y1400398D01*
X2533560Y1401439D01*
X2532320Y1401856D01*
G01X2544720Y1388939D02*
X2544410Y1389148D01*
Y1389564D01*
X2544720Y1389773D01*
X2545030Y1389564D01*
Y1389148D01*
X2544720Y1388939D01*
G01X2557120Y1401856D02*
X2555880Y1401439D01*
X2554950Y1400398D01*
X2554330Y1399148D01*
X2553865Y1397481D01*
X2553710Y1395606D01*
X2553865Y1393731D01*
X2554330Y1392064D01*
X2554950Y1390814D01*
X2555880Y1389773D01*
X2557120Y1389356D01*
X2558360Y1389773D01*
X2559290Y1390814D01*
X2559910Y1392064D01*
X2560375Y1393731D01*
X2560530Y1395606D01*
X2560375Y1397481D01*
X2559910Y1399148D01*
X2559290Y1400398D01*
X2558360Y1401439D01*
X2557120Y1401856D01*
G01X2517285Y1449914D02*
X2518370Y1448873D01*
X2519610Y1448456D01*
X2520850Y1448873D01*
X2521935Y1450122D01*
X2522710Y1451998D01*
X2523020Y1453873D01*
Y1456164D01*
X2522710Y1458039D01*
X2521935Y1459706D01*
X2521005Y1460539D01*
X2519920Y1460956D01*
X2518680Y1460539D01*
X2517750Y1459706D01*
X2517130Y1458456D01*
X2516820Y1456789D01*
X2517130Y1455331D01*
X2517905Y1453873D01*
X2518835Y1453039D01*
X2519920Y1452831D01*
X2521160Y1453247D01*
X2522090Y1454289D01*
X2523020Y1456164D01*
G01X2532320Y1448039D02*
X2532010Y1448248D01*
Y1448664D01*
X2532320Y1448873D01*
X2532630Y1448664D01*
Y1448248D01*
X2532320Y1448039D01*
G01X2544720Y1448456D02*
X2545805Y1448664D01*
X2547045Y1449289D01*
X2547820Y1450331D01*
X2548130Y1451789D01*
X2547820Y1453247D01*
X2546890Y1454498D01*
X2545495Y1455123D01*
X2543945D01*
X2543015Y1455539D01*
X2542240Y1456581D01*
X2541930Y1458039D01*
X2542395Y1459498D01*
X2543480Y1460539D01*
X2544720Y1460956D01*
X2545960Y1460539D01*
X2547045Y1459498D01*
X2547510Y1458039D01*
X2547200Y1456581D01*
X2546425Y1455539D01*
X2545495Y1455123D01*
X2543945D01*
X2542550Y1454498D01*
X2541620Y1453247D01*
X2541310Y1451789D01*
X2541620Y1450331D01*
X2542395Y1449289D01*
X2543635Y1448664D01*
X2544720Y1448456D01*
G01X2558980D02*
Y1460956D01*
X2553245Y1451998D01*
X2560995D01*
G01X2526120Y1507556D02*
X2527205Y1507764D01*
X2528445Y1508389D01*
X2529220Y1509431D01*
X2529530Y1510889D01*
X2529220Y1512347D01*
X2528290Y1513598D01*
X2526895Y1514223D01*
X2525345D01*
X2524415Y1514639D01*
X2523640Y1515681D01*
X2523330Y1517139D01*
X2523795Y1518598D01*
X2524880Y1519639D01*
X2526120Y1520056D01*
X2527360Y1519639D01*
X2528445Y1518598D01*
X2528910Y1517139D01*
X2528600Y1515681D01*
X2527825Y1514639D01*
X2526895Y1514223D01*
X2525345D01*
X2523950Y1513598D01*
X2523020Y1512347D01*
X2522710Y1510889D01*
X2523020Y1509431D01*
X2523795Y1508389D01*
X2525035Y1507764D01*
X2526120Y1507556D01*
G01X2538520Y1507139D02*
X2538210Y1507348D01*
Y1507764D01*
X2538520Y1507973D01*
X2538830Y1507764D01*
Y1507348D01*
X2538520Y1507139D01*
G01X2550920Y1520056D02*
X2549680Y1519639D01*
X2548750Y1518598D01*
X2548130Y1517348D01*
X2547665Y1515681D01*
X2547510Y1513806D01*
X2547665Y1511931D01*
X2548130Y1510264D01*
X2548750Y1509014D01*
X2549680Y1507973D01*
X2550920Y1507556D01*
X2552160Y1507973D01*
X2553090Y1509014D01*
X2553710Y1510264D01*
X2554175Y1511931D01*
X2554330Y1513806D01*
X2554175Y1515681D01*
X2553710Y1517348D01*
X2553090Y1518598D01*
X2552160Y1519639D01*
X2550920Y1520056D01*
G01X2638960Y1599606D02*
Y1612106D01*
X2642060D01*
X2643300Y1611481D01*
X2644230Y1610648D01*
X2645005Y1609398D01*
X2645625Y1607939D01*
X2645780Y1605856D01*
X2645625Y1603773D01*
X2645005Y1602314D01*
X2644230Y1601064D01*
X2643300Y1600231D01*
X2642060Y1599606D01*
X2638960D01*
G01X2651670D02*
Y1612106D01*
X2655545D01*
X2656785Y1611481D01*
X2657560Y1610648D01*
X2657870Y1608981D01*
X2657560Y1607314D01*
X2656630Y1606273D01*
X2655545Y1605648D01*
X2651670D01*
G01X2655545D02*
X2657870Y1599606D01*
G01X2665310Y1612106D02*
X2669030D01*
G01X2667170D02*
Y1599606D01*
G01X2665310D02*
X2669030D01*
G01X2676470Y1612106D02*
Y1599606D01*
X2682670D01*
G01X2688870Y1612106D02*
Y1599606D01*
X2695070D01*
G01X2720180Y1611064D02*
X2719250Y1611689D01*
X2718165Y1612106D01*
X2716925D01*
X2715530Y1611481D01*
X2714445Y1610439D01*
X2713670Y1609189D01*
X2713050Y1607106D01*
X2712895Y1605231D01*
X2713205Y1603356D01*
X2713670Y1602106D01*
X2714600Y1600856D01*
X2715685Y1600023D01*
X2716770Y1599606D01*
X2717855D01*
X2718940Y1600023D01*
X2719870Y1600647D01*
X2720645Y1601481D01*
G01X2725915Y1599606D02*
Y1612106D01*
G01X2732425D02*
Y1599606D01*
G01Y1605856D02*
X2725915D01*
G01X2737695Y1599606D02*
X2741570Y1612106D01*
X2745445Y1599606D01*
G01X2744050Y1603981D02*
X2739090D01*
G01X2750870Y1599606D02*
Y1612106D01*
X2754745D01*
X2755985Y1611481D01*
X2756760Y1610648D01*
X2757070Y1608981D01*
X2756760Y1607314D01*
X2755830Y1606273D01*
X2754745Y1605648D01*
X2750870D01*
G01X2754745D02*
X2757070Y1599606D01*
G01X2766370Y1612106D02*
Y1599606D01*
G01X2762805Y1612106D02*
X2769935D01*
G01X2778770Y1599189D02*
X2778460Y1599398D01*
Y1599814D01*
X2778770Y1600023D01*
X2779080Y1599814D01*
Y1599398D01*
X2778770Y1599189D01*
G01Y1604814D02*
X2778460Y1605023D01*
Y1605439D01*
X2778770Y1605648D01*
X2779080Y1605439D01*
Y1605023D01*
X2778770Y1604814D01*
G01X2803570Y1612106D02*
Y1599606D01*
G01X2800005Y1612106D02*
X2807135D01*
G01X2815970Y1599606D02*
X2814730Y1599814D01*
X2813645Y1600647D01*
X2812715Y1601898D01*
X2812095Y1603356D01*
X2811785Y1605023D01*
Y1606689D01*
X2812095Y1608356D01*
X2812715Y1609814D01*
X2813645Y1611064D01*
X2814730Y1611898D01*
X2815970Y1612106D01*
X2817210Y1611898D01*
X2818295Y1611064D01*
X2819225Y1609814D01*
X2819845Y1608356D01*
X2820155Y1606689D01*
Y1605023D01*
X2819845Y1603356D01*
X2819225Y1601898D01*
X2818295Y1600647D01*
X2817210Y1599814D01*
X2815970Y1599606D01*
G01X2825270D02*
Y1612106D01*
X2828990D01*
X2830230Y1611481D01*
X2831160Y1610023D01*
X2831470Y1608356D01*
X2831160Y1606689D01*
X2830385Y1605439D01*
X2828990Y1604814D01*
X2825270D01*
G01X2853170Y1612106D02*
Y1599606D01*
G01X2851000Y1607939D02*
X2855340D01*
G01X2865570Y1599606D02*
X2864640Y1599814D01*
X2863710Y1600647D01*
X2863090Y1602106D01*
X2862780Y1603773D01*
X2863090Y1605439D01*
X2863710Y1606898D01*
X2864640Y1607731D01*
X2865570Y1607939D01*
X2866500Y1607731D01*
X2867430Y1606898D01*
X2868050Y1605439D01*
X2868205Y1603773D01*
X2868050Y1602106D01*
X2867430Y1600647D01*
X2866500Y1599814D01*
X2865570Y1599606D01*
G01X2891610Y1606273D02*
X2892230Y1606898D01*
X2892695Y1607939D01*
X2893005Y1609398D01*
X2892695Y1610648D01*
X2892075Y1611481D01*
X2890990Y1612106D01*
X2886805D01*
Y1599606D01*
X2891920D01*
X2893005Y1600439D01*
X2893625Y1601689D01*
X2893935Y1603148D01*
X2893625Y1604606D01*
X2892695Y1605856D01*
X2891610Y1606273D01*
X2886805D01*
G01X2902770Y1599606D02*
X2901530Y1599814D01*
X2900445Y1600647D01*
X2899515Y1601898D01*
X2898895Y1603356D01*
X2898585Y1605023D01*
Y1606689D01*
X2898895Y1608356D01*
X2899515Y1609814D01*
X2900445Y1611064D01*
X2901530Y1611898D01*
X2902770Y1612106D01*
X2904010Y1611898D01*
X2905095Y1611064D01*
X2906025Y1609814D01*
X2906645Y1608356D01*
X2906955Y1606689D01*
Y1605023D01*
X2906645Y1603356D01*
X2906025Y1601898D01*
X2905095Y1600647D01*
X2904010Y1599814D01*
X2902770Y1599606D01*
G01X2915170Y1612106D02*
Y1599606D01*
G01X2911605Y1612106D02*
X2918735D01*
G01X2927570D02*
Y1599606D01*
G01X2924005Y1612106D02*
X2931135D01*
G01X2939970Y1599606D02*
X2938730Y1599814D01*
X2937645Y1600647D01*
X2936715Y1601898D01*
X2936095Y1603356D01*
X2935785Y1605023D01*
Y1606689D01*
X2936095Y1608356D01*
X2936715Y1609814D01*
X2937645Y1611064D01*
X2938730Y1611898D01*
X2939970Y1612106D01*
X2941210Y1611898D01*
X2942295Y1611064D01*
X2943225Y1609814D01*
X2943845Y1608356D01*
X2944155Y1606689D01*
Y1605023D01*
X2943845Y1603356D01*
X2943225Y1601898D01*
X2942295Y1600647D01*
X2941210Y1599814D01*
X2939970Y1599606D01*
G01X2948340D02*
Y1612106D01*
X2952370Y1601689D01*
X2956400Y1612106D01*
Y1599606D01*
G01X2653220Y1562106D02*
Y1549606D01*
G01X2649655Y1562106D02*
X2656785D01*
G01X2665620Y1549606D02*
X2664380Y1549814D01*
X2663295Y1550647D01*
X2662365Y1551898D01*
X2661745Y1553356D01*
X2661435Y1555023D01*
Y1556689D01*
X2661745Y1558356D01*
X2662365Y1559814D01*
X2663295Y1561064D01*
X2664380Y1561898D01*
X2665620Y1562106D01*
X2666860Y1561898D01*
X2667945Y1561064D01*
X2668875Y1559814D01*
X2669495Y1558356D01*
X2669805Y1556689D01*
Y1555023D01*
X2669495Y1553356D01*
X2668875Y1551898D01*
X2667945Y1550647D01*
X2666860Y1549814D01*
X2665620Y1549606D01*
G01X2674920Y1562106D02*
Y1549606D01*
X2681120D01*
G01X2693520D02*
X2687320D01*
Y1562106D01*
X2693520D01*
G01X2691040Y1556064D02*
X2687320D01*
G01X2699720Y1549606D02*
Y1562106D01*
X2703595D01*
X2704835Y1561481D01*
X2705610Y1560648D01*
X2705920Y1558981D01*
X2705610Y1557314D01*
X2704680Y1556273D01*
X2703595Y1555648D01*
X2699720D01*
G01X2703595D02*
X2705920Y1549606D01*
G01X2711345D02*
X2715220Y1562106D01*
X2719095Y1549606D01*
G01X2717700Y1553981D02*
X2712740D01*
G01X2724055Y1549606D02*
Y1562106D01*
X2731185Y1549606D01*
Y1562106D01*
G01X2743430Y1561064D02*
X2742500Y1561689D01*
X2741415Y1562106D01*
X2740175D01*
X2738780Y1561481D01*
X2737695Y1560439D01*
X2736920Y1559189D01*
X2736300Y1557106D01*
X2736145Y1555231D01*
X2736455Y1553356D01*
X2736920Y1552106D01*
X2737850Y1550856D01*
X2738935Y1550023D01*
X2740020Y1549606D01*
X2741105D01*
X2742190Y1550023D01*
X2743120Y1550647D01*
X2743895Y1551481D01*
G01X2755520Y1549606D02*
X2749320D01*
Y1562106D01*
X2755520D01*
G01X2753040Y1556064D02*
X2749320D01*
G01X2760170Y1545439D02*
X2769470D01*
G01X2773810Y1549606D02*
Y1562106D01*
X2776910D01*
X2778150Y1561481D01*
X2779080Y1560648D01*
X2779855Y1559398D01*
X2780475Y1557939D01*
X2780630Y1555856D01*
X2780475Y1553773D01*
X2779855Y1552314D01*
X2779080Y1551064D01*
X2778150Y1550231D01*
X2776910Y1549606D01*
X2773810D01*
G01X2786520D02*
Y1562106D01*
X2790395D01*
X2791635Y1561481D01*
X2792410Y1560648D01*
X2792720Y1558981D01*
X2792410Y1557314D01*
X2791480Y1556273D01*
X2790395Y1555648D01*
X2786520D01*
G01X2790395D02*
X2792720Y1549606D01*
G01X2800160Y1562106D02*
X2803880D01*
G01X2802020D02*
Y1549606D01*
G01X2800160D02*
X2803880D01*
G01X2811320Y1562106D02*
Y1549606D01*
X2817520D01*
G01X2823720Y1562106D02*
Y1549606D01*
X2829920D01*
G01X2676315Y-438577D02*
X2680035D01*
G01X2678020Y-435869D02*
Y-441286D01*
G01X2690420Y-442744D02*
Y-430244D01*
X2688560Y-432744D01*
G01Y-442744D02*
X2692280D01*
G01X2702820Y-443161D02*
X2702510Y-442952D01*
Y-442536D01*
X2702820Y-442327D01*
X2703130Y-442536D01*
Y-442952D01*
X2702820Y-443161D01*
G01X2712585Y-441286D02*
X2713670Y-442327D01*
X2714910Y-442744D01*
X2716150Y-442327D01*
X2717235Y-441078D01*
X2718010Y-439202D01*
X2718320Y-437327D01*
Y-435036D01*
X2718010Y-433161D01*
X2717235Y-431494D01*
X2716305Y-430661D01*
X2715220Y-430244D01*
X2713980Y-430661D01*
X2713050Y-431494D01*
X2712430Y-432744D01*
X2712120Y-434411D01*
X2712430Y-435869D01*
X2713205Y-437327D01*
X2714135Y-438161D01*
X2715220Y-438369D01*
X2716460Y-437953D01*
X2717390Y-436911D01*
X2718320Y-435036D01*
G01X2724675Y-437536D02*
X2725760Y-436077D01*
X2726690Y-435244D01*
X2727930Y-434827D01*
X2729015Y-435244D01*
X2729790Y-436077D01*
X2730410Y-437327D01*
X2730565Y-438786D01*
X2730410Y-440036D01*
X2729790Y-441286D01*
X2728860Y-442327D01*
X2727775Y-442744D01*
X2726535Y-442327D01*
X2725450Y-441078D01*
X2724830Y-439202D01*
X2724675Y-437119D01*
X2724985Y-434411D01*
X2725450Y-432952D01*
X2726225Y-431494D01*
X2727310Y-430452D01*
X2728395Y-430244D01*
X2729480Y-430661D01*
X2730255Y-431702D01*
G01X2737230Y-443161D02*
X2742810Y-430244D01*
G01X2750405Y-438577D02*
X2754435D01*
G01X2764820Y-442744D02*
Y-430244D01*
X2762960Y-432744D01*
G01Y-442744D02*
X2766680D01*
G01X2777220Y-443161D02*
X2776910Y-442952D01*
Y-442536D01*
X2777220Y-442327D01*
X2777530Y-442536D01*
Y-442952D01*
X2777220Y-443161D01*
G01X2786985Y-441286D02*
X2788070Y-442327D01*
X2789310Y-442744D01*
X2790550Y-442327D01*
X2791635Y-441078D01*
X2792410Y-439202D01*
X2792720Y-437327D01*
Y-435036D01*
X2792410Y-433161D01*
X2791635Y-431494D01*
X2790705Y-430661D01*
X2789620Y-430244D01*
X2788380Y-430661D01*
X2787450Y-431494D01*
X2786830Y-432744D01*
X2786520Y-434411D01*
X2786830Y-435869D01*
X2787605Y-437327D01*
X2788535Y-438161D01*
X2789620Y-438369D01*
X2790860Y-437953D01*
X2791790Y-436911D01*
X2792720Y-435036D01*
G01X2799075Y-437536D02*
X2800160Y-436077D01*
X2801090Y-435244D01*
X2802330Y-434827D01*
X2803415Y-435244D01*
X2804190Y-436077D01*
X2804810Y-437327D01*
X2804965Y-438786D01*
X2804810Y-440036D01*
X2804190Y-441286D01*
X2803260Y-442327D01*
X2802175Y-442744D01*
X2800935Y-442327D01*
X2799850Y-441078D01*
X2799230Y-439202D01*
X2799075Y-437119D01*
X2799385Y-434411D01*
X2799850Y-432952D01*
X2800625Y-431494D01*
X2801710Y-430452D01*
X2802795Y-430244D01*
X2803880Y-430661D01*
X2804655Y-431702D01*
G01X2676315Y152423D02*
X2680035D01*
G01X2678020Y155131D02*
Y149714D01*
G01X2690420Y148256D02*
Y160756D01*
X2688560Y158256D01*
G01Y148256D02*
X2692280D01*
G01X2702820Y147839D02*
X2702510Y148048D01*
Y148464D01*
X2702820Y148673D01*
X2703130Y148464D01*
Y148048D01*
X2702820Y147839D01*
G01X2712585Y149714D02*
X2713670Y148673D01*
X2714910Y148256D01*
X2716150Y148673D01*
X2717235Y149922D01*
X2718010Y151798D01*
X2718320Y153673D01*
Y155964D01*
X2718010Y157839D01*
X2717235Y159506D01*
X2716305Y160339D01*
X2715220Y160756D01*
X2713980Y160339D01*
X2713050Y159506D01*
X2712430Y158256D01*
X2712120Y156589D01*
X2712430Y155131D01*
X2713205Y153673D01*
X2714135Y152839D01*
X2715220Y152631D01*
X2716460Y153047D01*
X2717390Y154089D01*
X2718320Y155964D01*
G01X2724675Y153464D02*
X2725760Y154923D01*
X2726690Y155756D01*
X2727930Y156173D01*
X2729015Y155756D01*
X2729790Y154923D01*
X2730410Y153673D01*
X2730565Y152214D01*
X2730410Y150964D01*
X2729790Y149714D01*
X2728860Y148673D01*
X2727775Y148256D01*
X2726535Y148673D01*
X2725450Y149922D01*
X2724830Y151798D01*
X2724675Y153881D01*
X2724985Y156589D01*
X2725450Y158048D01*
X2726225Y159506D01*
X2727310Y160548D01*
X2728395Y160756D01*
X2729480Y160339D01*
X2730255Y159298D01*
G01X2737230Y147839D02*
X2742810Y160756D01*
G01X2750405Y152423D02*
X2754435D01*
G01X2764820Y148256D02*
Y160756D01*
X2762960Y158256D01*
G01Y148256D02*
X2766680D01*
G01X2777220Y147839D02*
X2776910Y148048D01*
Y148464D01*
X2777220Y148673D01*
X2777530Y148464D01*
Y148048D01*
X2777220Y147839D01*
G01X2786985Y149714D02*
X2788070Y148673D01*
X2789310Y148256D01*
X2790550Y148673D01*
X2791635Y149922D01*
X2792410Y151798D01*
X2792720Y153673D01*
Y155964D01*
X2792410Y157839D01*
X2791635Y159506D01*
X2790705Y160339D01*
X2789620Y160756D01*
X2788380Y160339D01*
X2787450Y159506D01*
X2786830Y158256D01*
X2786520Y156589D01*
X2786830Y155131D01*
X2787605Y153673D01*
X2788535Y152839D01*
X2789620Y152631D01*
X2790860Y153047D01*
X2791790Y154089D01*
X2792720Y155964D01*
G01X2799075Y153464D02*
X2800160Y154923D01*
X2801090Y155756D01*
X2802330Y156173D01*
X2803415Y155756D01*
X2804190Y154923D01*
X2804810Y153673D01*
X2804965Y152214D01*
X2804810Y150964D01*
X2804190Y149714D01*
X2803260Y148673D01*
X2802175Y148256D01*
X2800935Y148673D01*
X2799850Y149922D01*
X2799230Y151798D01*
X2799075Y153881D01*
X2799385Y156589D01*
X2799850Y158048D01*
X2800625Y159506D01*
X2801710Y160548D01*
X2802795Y160756D01*
X2803880Y160339D01*
X2804655Y159298D01*
G01X2676315Y211523D02*
X2680035D01*
G01X2678020Y214231D02*
Y208814D01*
G01X2690420Y207356D02*
Y219856D01*
X2688560Y217356D01*
G01Y207356D02*
X2692280D01*
G01X2702820Y206939D02*
X2702510Y207148D01*
Y207564D01*
X2702820Y207773D01*
X2703130Y207564D01*
Y207148D01*
X2702820Y206939D01*
G01X2712585Y208814D02*
X2713670Y207773D01*
X2714910Y207356D01*
X2716150Y207773D01*
X2717235Y209022D01*
X2718010Y210898D01*
X2718320Y212773D01*
Y215064D01*
X2718010Y216939D01*
X2717235Y218606D01*
X2716305Y219439D01*
X2715220Y219856D01*
X2713980Y219439D01*
X2713050Y218606D01*
X2712430Y217356D01*
X2712120Y215689D01*
X2712430Y214231D01*
X2713205Y212773D01*
X2714135Y211939D01*
X2715220Y211731D01*
X2716460Y212147D01*
X2717390Y213189D01*
X2718320Y215064D01*
G01X2724675Y212564D02*
X2725760Y214023D01*
X2726690Y214856D01*
X2727930Y215273D01*
X2729015Y214856D01*
X2729790Y214023D01*
X2730410Y212773D01*
X2730565Y211314D01*
X2730410Y210064D01*
X2729790Y208814D01*
X2728860Y207773D01*
X2727775Y207356D01*
X2726535Y207773D01*
X2725450Y209022D01*
X2724830Y210898D01*
X2724675Y212981D01*
X2724985Y215689D01*
X2725450Y217148D01*
X2726225Y218606D01*
X2727310Y219648D01*
X2728395Y219856D01*
X2729480Y219439D01*
X2730255Y218398D01*
G01X2737230Y206939D02*
X2742810Y219856D01*
G01X2750405Y211523D02*
X2754435D01*
G01X2764820Y207356D02*
Y219856D01*
X2762960Y217356D01*
G01Y207356D02*
X2766680D01*
G01X2777220Y206939D02*
X2776910Y207148D01*
Y207564D01*
X2777220Y207773D01*
X2777530Y207564D01*
Y207148D01*
X2777220Y206939D01*
G01X2786985Y208814D02*
X2788070Y207773D01*
X2789310Y207356D01*
X2790550Y207773D01*
X2791635Y209022D01*
X2792410Y210898D01*
X2792720Y212773D01*
Y215064D01*
X2792410Y216939D01*
X2791635Y218606D01*
X2790705Y219439D01*
X2789620Y219856D01*
X2788380Y219439D01*
X2787450Y218606D01*
X2786830Y217356D01*
X2786520Y215689D01*
X2786830Y214231D01*
X2787605Y212773D01*
X2788535Y211939D01*
X2789620Y211731D01*
X2790860Y212147D01*
X2791790Y213189D01*
X2792720Y215064D01*
G01X2799075Y212564D02*
X2800160Y214023D01*
X2801090Y214856D01*
X2802330Y215273D01*
X2803415Y214856D01*
X2804190Y214023D01*
X2804810Y212773D01*
X2804965Y211314D01*
X2804810Y210064D01*
X2804190Y208814D01*
X2803260Y207773D01*
X2802175Y207356D01*
X2800935Y207773D01*
X2799850Y209022D01*
X2799230Y210898D01*
X2799075Y212981D01*
X2799385Y215689D01*
X2799850Y217148D01*
X2800625Y218606D01*
X2801710Y219648D01*
X2802795Y219856D01*
X2803880Y219439D01*
X2804655Y218398D01*
G01X2676315Y802523D02*
X2680035D01*
G01X2678020Y805231D02*
Y799814D01*
G01X2690420Y798356D02*
Y810856D01*
X2688560Y808356D01*
G01Y798356D02*
X2692280D01*
G01X2702820Y797939D02*
X2702510Y798148D01*
Y798564D01*
X2702820Y798773D01*
X2703130Y798564D01*
Y798148D01*
X2702820Y797939D01*
G01X2712585Y799814D02*
X2713670Y798773D01*
X2714910Y798356D01*
X2716150Y798773D01*
X2717235Y800022D01*
X2718010Y801898D01*
X2718320Y803773D01*
Y806064D01*
X2718010Y807939D01*
X2717235Y809606D01*
X2716305Y810439D01*
X2715220Y810856D01*
X2713980Y810439D01*
X2713050Y809606D01*
X2712430Y808356D01*
X2712120Y806689D01*
X2712430Y805231D01*
X2713205Y803773D01*
X2714135Y802939D01*
X2715220Y802731D01*
X2716460Y803147D01*
X2717390Y804189D01*
X2718320Y806064D01*
G01X2724675Y803564D02*
X2725760Y805023D01*
X2726690Y805856D01*
X2727930Y806273D01*
X2729015Y805856D01*
X2729790Y805023D01*
X2730410Y803773D01*
X2730565Y802314D01*
X2730410Y801064D01*
X2729790Y799814D01*
X2728860Y798773D01*
X2727775Y798356D01*
X2726535Y798773D01*
X2725450Y800022D01*
X2724830Y801898D01*
X2724675Y803981D01*
X2724985Y806689D01*
X2725450Y808148D01*
X2726225Y809606D01*
X2727310Y810648D01*
X2728395Y810856D01*
X2729480Y810439D01*
X2730255Y809398D01*
G01X2737230Y797939D02*
X2742810Y810856D01*
G01X2750405Y802523D02*
X2754435D01*
G01X2764820Y798356D02*
Y810856D01*
X2762960Y808356D01*
G01Y798356D02*
X2766680D01*
G01X2777220Y797939D02*
X2776910Y798148D01*
Y798564D01*
X2777220Y798773D01*
X2777530Y798564D01*
Y798148D01*
X2777220Y797939D01*
G01X2786985Y799814D02*
X2788070Y798773D01*
X2789310Y798356D01*
X2790550Y798773D01*
X2791635Y800022D01*
X2792410Y801898D01*
X2792720Y803773D01*
Y806064D01*
X2792410Y807939D01*
X2791635Y809606D01*
X2790705Y810439D01*
X2789620Y810856D01*
X2788380Y810439D01*
X2787450Y809606D01*
X2786830Y808356D01*
X2786520Y806689D01*
X2786830Y805231D01*
X2787605Y803773D01*
X2788535Y802939D01*
X2789620Y802731D01*
X2790860Y803147D01*
X2791790Y804189D01*
X2792720Y806064D01*
G01X2799075Y803564D02*
X2800160Y805023D01*
X2801090Y805856D01*
X2802330Y806273D01*
X2803415Y805856D01*
X2804190Y805023D01*
X2804810Y803773D01*
X2804965Y802314D01*
X2804810Y801064D01*
X2804190Y799814D01*
X2803260Y798773D01*
X2802175Y798356D01*
X2800935Y798773D01*
X2799850Y800022D01*
X2799230Y801898D01*
X2799075Y803981D01*
X2799385Y806689D01*
X2799850Y808148D01*
X2800625Y809606D01*
X2801710Y810648D01*
X2802795Y810856D01*
X2803880Y810439D01*
X2804655Y809398D01*
G01X2676315Y1038923D02*
X2680035D01*
G01X2678020Y1041631D02*
Y1036214D01*
G01X2690420Y1034756D02*
Y1047256D01*
X2688560Y1044756D01*
G01Y1034756D02*
X2692280D01*
G01X2702820Y1034339D02*
X2702510Y1034548D01*
Y1034964D01*
X2702820Y1035173D01*
X2703130Y1034964D01*
Y1034548D01*
X2702820Y1034339D01*
G01X2712585Y1036214D02*
X2713670Y1035173D01*
X2714910Y1034756D01*
X2716150Y1035173D01*
X2717235Y1036422D01*
X2718010Y1038298D01*
X2718320Y1040173D01*
Y1042464D01*
X2718010Y1044339D01*
X2717235Y1046006D01*
X2716305Y1046839D01*
X2715220Y1047256D01*
X2713980Y1046839D01*
X2713050Y1046006D01*
X2712430Y1044756D01*
X2712120Y1043089D01*
X2712430Y1041631D01*
X2713205Y1040173D01*
X2714135Y1039339D01*
X2715220Y1039131D01*
X2716460Y1039547D01*
X2717390Y1040589D01*
X2718320Y1042464D01*
G01X2724675Y1039964D02*
X2725760Y1041423D01*
X2726690Y1042256D01*
X2727930Y1042673D01*
X2729015Y1042256D01*
X2729790Y1041423D01*
X2730410Y1040173D01*
X2730565Y1038714D01*
X2730410Y1037464D01*
X2729790Y1036214D01*
X2728860Y1035173D01*
X2727775Y1034756D01*
X2726535Y1035173D01*
X2725450Y1036422D01*
X2724830Y1038298D01*
X2724675Y1040381D01*
X2724985Y1043089D01*
X2725450Y1044548D01*
X2726225Y1046006D01*
X2727310Y1047048D01*
X2728395Y1047256D01*
X2729480Y1046839D01*
X2730255Y1045798D01*
G01X2737230Y1034339D02*
X2742810Y1047256D01*
G01X2750405Y1038923D02*
X2754435D01*
G01X2764820Y1034756D02*
Y1047256D01*
X2762960Y1044756D01*
G01Y1034756D02*
X2766680D01*
G01X2777220Y1034339D02*
X2776910Y1034548D01*
Y1034964D01*
X2777220Y1035173D01*
X2777530Y1034964D01*
Y1034548D01*
X2777220Y1034339D01*
G01X2786985Y1036214D02*
X2788070Y1035173D01*
X2789310Y1034756D01*
X2790550Y1035173D01*
X2791635Y1036422D01*
X2792410Y1038298D01*
X2792720Y1040173D01*
Y1042464D01*
X2792410Y1044339D01*
X2791635Y1046006D01*
X2790705Y1046839D01*
X2789620Y1047256D01*
X2788380Y1046839D01*
X2787450Y1046006D01*
X2786830Y1044756D01*
X2786520Y1043089D01*
X2786830Y1041631D01*
X2787605Y1040173D01*
X2788535Y1039339D01*
X2789620Y1039131D01*
X2790860Y1039547D01*
X2791790Y1040589D01*
X2792720Y1042464D01*
G01X2799075Y1039964D02*
X2800160Y1041423D01*
X2801090Y1042256D01*
X2802330Y1042673D01*
X2803415Y1042256D01*
X2804190Y1041423D01*
X2804810Y1040173D01*
X2804965Y1038714D01*
X2804810Y1037464D01*
X2804190Y1036214D01*
X2803260Y1035173D01*
X2802175Y1034756D01*
X2800935Y1035173D01*
X2799850Y1036422D01*
X2799230Y1038298D01*
X2799075Y1040381D01*
X2799385Y1043089D01*
X2799850Y1044548D01*
X2800625Y1046006D01*
X2801710Y1047048D01*
X2802795Y1047256D01*
X2803880Y1046839D01*
X2804655Y1045798D01*
G01X2676315Y1216223D02*
X2680035D01*
G01X2678020Y1218931D02*
Y1213514D01*
G01X2690420Y1212056D02*
Y1224556D01*
X2688560Y1222056D01*
G01Y1212056D02*
X2692280D01*
G01X2702820Y1211639D02*
X2702510Y1211848D01*
Y1212264D01*
X2702820Y1212473D01*
X2703130Y1212264D01*
Y1211848D01*
X2702820Y1211639D01*
G01X2712585Y1213514D02*
X2713670Y1212473D01*
X2714910Y1212056D01*
X2716150Y1212473D01*
X2717235Y1213722D01*
X2718010Y1215598D01*
X2718320Y1217473D01*
Y1219764D01*
X2718010Y1221639D01*
X2717235Y1223306D01*
X2716305Y1224139D01*
X2715220Y1224556D01*
X2713980Y1224139D01*
X2713050Y1223306D01*
X2712430Y1222056D01*
X2712120Y1220389D01*
X2712430Y1218931D01*
X2713205Y1217473D01*
X2714135Y1216639D01*
X2715220Y1216431D01*
X2716460Y1216847D01*
X2717390Y1217889D01*
X2718320Y1219764D01*
G01X2724675Y1217264D02*
X2725760Y1218723D01*
X2726690Y1219556D01*
X2727930Y1219973D01*
X2729015Y1219556D01*
X2729790Y1218723D01*
X2730410Y1217473D01*
X2730565Y1216014D01*
X2730410Y1214764D01*
X2729790Y1213514D01*
X2728860Y1212473D01*
X2727775Y1212056D01*
X2726535Y1212473D01*
X2725450Y1213722D01*
X2724830Y1215598D01*
X2724675Y1217681D01*
X2724985Y1220389D01*
X2725450Y1221848D01*
X2726225Y1223306D01*
X2727310Y1224348D01*
X2728395Y1224556D01*
X2729480Y1224139D01*
X2730255Y1223098D01*
G01X2737230Y1211639D02*
X2742810Y1224556D01*
G01X2750405Y1216223D02*
X2754435D01*
G01X2764820Y1212056D02*
Y1224556D01*
X2762960Y1222056D01*
G01Y1212056D02*
X2766680D01*
G01X2777220Y1211639D02*
X2776910Y1211848D01*
Y1212264D01*
X2777220Y1212473D01*
X2777530Y1212264D01*
Y1211848D01*
X2777220Y1211639D01*
G01X2786985Y1213514D02*
X2788070Y1212473D01*
X2789310Y1212056D01*
X2790550Y1212473D01*
X2791635Y1213722D01*
X2792410Y1215598D01*
X2792720Y1217473D01*
Y1219764D01*
X2792410Y1221639D01*
X2791635Y1223306D01*
X2790705Y1224139D01*
X2789620Y1224556D01*
X2788380Y1224139D01*
X2787450Y1223306D01*
X2786830Y1222056D01*
X2786520Y1220389D01*
X2786830Y1218931D01*
X2787605Y1217473D01*
X2788535Y1216639D01*
X2789620Y1216431D01*
X2790860Y1216847D01*
X2791790Y1217889D01*
X2792720Y1219764D01*
G01X2799075Y1217264D02*
X2800160Y1218723D01*
X2801090Y1219556D01*
X2802330Y1219973D01*
X2803415Y1219556D01*
X2804190Y1218723D01*
X2804810Y1217473D01*
X2804965Y1216014D01*
X2804810Y1214764D01*
X2804190Y1213514D01*
X2803260Y1212473D01*
X2802175Y1212056D01*
X2800935Y1212473D01*
X2799850Y1213722D01*
X2799230Y1215598D01*
X2799075Y1217681D01*
X2799385Y1220389D01*
X2799850Y1221848D01*
X2800625Y1223306D01*
X2801710Y1224348D01*
X2802795Y1224556D01*
X2803880Y1224139D01*
X2804655Y1223098D01*
G01X2676315Y1275323D02*
X2680035D01*
G01X2678020Y1278031D02*
Y1272614D01*
G01X2690420Y1271156D02*
Y1283656D01*
X2688560Y1281156D01*
G01Y1271156D02*
X2692280D01*
G01X2702820Y1270739D02*
X2702510Y1270948D01*
Y1271364D01*
X2702820Y1271573D01*
X2703130Y1271364D01*
Y1270948D01*
X2702820Y1270739D01*
G01X2712585Y1272614D02*
X2713670Y1271573D01*
X2714910Y1271156D01*
X2716150Y1271573D01*
X2717235Y1272822D01*
X2718010Y1274698D01*
X2718320Y1276573D01*
Y1278864D01*
X2718010Y1280739D01*
X2717235Y1282406D01*
X2716305Y1283239D01*
X2715220Y1283656D01*
X2713980Y1283239D01*
X2713050Y1282406D01*
X2712430Y1281156D01*
X2712120Y1279489D01*
X2712430Y1278031D01*
X2713205Y1276573D01*
X2714135Y1275739D01*
X2715220Y1275531D01*
X2716460Y1275947D01*
X2717390Y1276989D01*
X2718320Y1278864D01*
G01X2724675Y1276364D02*
X2725760Y1277823D01*
X2726690Y1278656D01*
X2727930Y1279073D01*
X2729015Y1278656D01*
X2729790Y1277823D01*
X2730410Y1276573D01*
X2730565Y1275114D01*
X2730410Y1273864D01*
X2729790Y1272614D01*
X2728860Y1271573D01*
X2727775Y1271156D01*
X2726535Y1271573D01*
X2725450Y1272822D01*
X2724830Y1274698D01*
X2724675Y1276781D01*
X2724985Y1279489D01*
X2725450Y1280948D01*
X2726225Y1282406D01*
X2727310Y1283448D01*
X2728395Y1283656D01*
X2729480Y1283239D01*
X2730255Y1282198D01*
G01X2737230Y1270739D02*
X2742810Y1283656D01*
G01X2750405Y1275323D02*
X2754435D01*
G01X2764820Y1271156D02*
Y1283656D01*
X2762960Y1281156D01*
G01Y1271156D02*
X2766680D01*
G01X2777220Y1270739D02*
X2776910Y1270948D01*
Y1271364D01*
X2777220Y1271573D01*
X2777530Y1271364D01*
Y1270948D01*
X2777220Y1270739D01*
G01X2786985Y1272614D02*
X2788070Y1271573D01*
X2789310Y1271156D01*
X2790550Y1271573D01*
X2791635Y1272822D01*
X2792410Y1274698D01*
X2792720Y1276573D01*
Y1278864D01*
X2792410Y1280739D01*
X2791635Y1282406D01*
X2790705Y1283239D01*
X2789620Y1283656D01*
X2788380Y1283239D01*
X2787450Y1282406D01*
X2786830Y1281156D01*
X2786520Y1279489D01*
X2786830Y1278031D01*
X2787605Y1276573D01*
X2788535Y1275739D01*
X2789620Y1275531D01*
X2790860Y1275947D01*
X2791790Y1276989D01*
X2792720Y1278864D01*
G01X2799075Y1276364D02*
X2800160Y1277823D01*
X2801090Y1278656D01*
X2802330Y1279073D01*
X2803415Y1278656D01*
X2804190Y1277823D01*
X2804810Y1276573D01*
X2804965Y1275114D01*
X2804810Y1273864D01*
X2804190Y1272614D01*
X2803260Y1271573D01*
X2802175Y1271156D01*
X2800935Y1271573D01*
X2799850Y1272822D01*
X2799230Y1274698D01*
X2799075Y1276781D01*
X2799385Y1279489D01*
X2799850Y1280948D01*
X2800625Y1282406D01*
X2801710Y1283448D01*
X2802795Y1283656D01*
X2803880Y1283239D01*
X2804655Y1282198D01*
G01X2669495Y1574606D02*
X2673370Y1587106D01*
X2677245Y1574606D01*
G01X2675850Y1578981D02*
X2670890D01*
G01X2682670Y1587106D02*
Y1574606D01*
X2688870D01*
G01X2695070Y1587106D02*
Y1574606D01*
X2701270D01*
G01X2719560Y1587106D02*
Y1578148D01*
X2720180Y1576272D01*
X2721420Y1575023D01*
X2722970Y1574606D01*
X2724520Y1575023D01*
X2725760Y1576272D01*
X2726380Y1578148D01*
Y1587106D01*
G01X2731805Y1574606D02*
Y1587106D01*
X2738935Y1574606D01*
Y1587106D01*
G01X2745910D02*
X2749630D01*
G01X2747770D02*
Y1574606D01*
G01X2745910D02*
X2749630D01*
G01X2760170Y1587106D02*
Y1574606D01*
G01X2756605Y1587106D02*
X2763735D01*
G01X2769315Y1576272D02*
X2770555Y1575231D01*
X2771950Y1574606D01*
X2773190D01*
X2774430Y1575231D01*
X2775360Y1576272D01*
X2775825Y1577731D01*
X2775515Y1579189D01*
X2774740Y1580439D01*
X2773345Y1581273D01*
X2771485Y1581689D01*
X2770400Y1582523D01*
X2769935Y1583981D01*
X2770245Y1585439D01*
X2771020Y1586481D01*
X2772105Y1587106D01*
X2773190D01*
X2774275Y1586689D01*
X2775205Y1585648D01*
G01X2793495Y1574606D02*
X2797370Y1587106D01*
X2801245Y1574606D01*
G01X2799850Y1578981D02*
X2794890D01*
G01X2806670Y1574606D02*
Y1587106D01*
X2810545D01*
X2811785Y1586481D01*
X2812560Y1585648D01*
X2812870Y1583981D01*
X2812560Y1582314D01*
X2811630Y1581273D01*
X2810545Y1580648D01*
X2806670D01*
G01X2810545D02*
X2812870Y1574606D01*
G01X2825270D02*
X2819070D01*
Y1587106D01*
X2825270D01*
G01X2822790Y1581064D02*
X2819070D01*
G01X2845110Y1587106D02*
X2848830D01*
G01X2846970D02*
Y1574606D01*
G01X2845110D02*
X2848830D01*
G01X2855805D02*
Y1587106D01*
X2862935Y1574606D01*
Y1587106D01*
G01X2880140Y1574606D02*
Y1587106D01*
X2884170Y1576689D01*
X2888200Y1587106D01*
Y1574606D01*
G01X2894710Y1587106D02*
X2898430D01*
G01X2896570D02*
Y1574606D01*
G01X2894710D02*
X2898430D01*
G01X2905870Y1587106D02*
Y1574606D01*
X2912070D01*
G01X2918115Y1576272D02*
X2919355Y1575231D01*
X2920750Y1574606D01*
X2921990D01*
X2923230Y1575231D01*
X2924160Y1576272D01*
X2924625Y1577731D01*
X2924315Y1579189D01*
X2923540Y1580439D01*
X2922145Y1581273D01*
X2920285Y1581689D01*
X2919200Y1582523D01*
X2918735Y1583981D01*
X2919045Y1585439D01*
X2919820Y1586481D01*
X2920905Y1587106D01*
X2921990D01*
X2923075Y1586689D01*
X2924005Y1585648D01*
G01X2688715Y-615877D02*
X2692435D01*
G01X2690420Y-613169D02*
Y-618586D01*
G01X2704680Y-620044D02*
Y-607544D01*
X2698945Y-616502D01*
X2706695D01*
G01X2715220Y-620461D02*
X2714910Y-620252D01*
Y-619836D01*
X2715220Y-619627D01*
X2715530Y-619836D01*
Y-620252D01*
X2715220Y-620461D01*
G01X2727620Y-607544D02*
X2726380Y-607961D01*
X2725450Y-609002D01*
X2724830Y-610252D01*
X2724365Y-611919D01*
X2724210Y-613794D01*
X2724365Y-615669D01*
X2724830Y-617336D01*
X2725450Y-618586D01*
X2726380Y-619627D01*
X2727620Y-620044D01*
X2728860Y-619627D01*
X2729790Y-618586D01*
X2730410Y-617336D01*
X2730875Y-615669D01*
X2731030Y-613794D01*
X2730875Y-611919D01*
X2730410Y-610252D01*
X2729790Y-609002D01*
X2728860Y-607961D01*
X2727620Y-607544D01*
G01X2737230Y-620461D02*
X2742810Y-607544D01*
G01X2750405Y-615877D02*
X2754435D01*
G01X2766680Y-620044D02*
Y-607544D01*
X2760945Y-616502D01*
X2768695D01*
G01X2777220Y-620461D02*
X2776910Y-620252D01*
Y-619836D01*
X2777220Y-619627D01*
X2777530Y-619836D01*
Y-620252D01*
X2777220Y-620461D01*
G01X2789620Y-607544D02*
X2788380Y-607961D01*
X2787450Y-609002D01*
X2786830Y-610252D01*
X2786365Y-611919D01*
X2786210Y-613794D01*
X2786365Y-615669D01*
X2786830Y-617336D01*
X2787450Y-618586D01*
X2788380Y-619627D01*
X2789620Y-620044D01*
X2790860Y-619627D01*
X2791790Y-618586D01*
X2792410Y-617336D01*
X2792875Y-615669D01*
X2793030Y-613794D01*
X2792875Y-611919D01*
X2792410Y-610252D01*
X2791790Y-609002D01*
X2790860Y-607961D01*
X2789620Y-607544D01*
G01X2688715Y-556777D02*
X2692435D01*
G01X2690420Y-554069D02*
Y-559486D01*
G01X2704680Y-560944D02*
Y-548444D01*
X2698945Y-557402D01*
X2706695D01*
G01X2715220Y-561361D02*
X2714910Y-561152D01*
Y-560736D01*
X2715220Y-560527D01*
X2715530Y-560736D01*
Y-561152D01*
X2715220Y-561361D01*
G01X2727620Y-548444D02*
X2726380Y-548861D01*
X2725450Y-549902D01*
X2724830Y-551152D01*
X2724365Y-552819D01*
X2724210Y-554694D01*
X2724365Y-556569D01*
X2724830Y-558236D01*
X2725450Y-559486D01*
X2726380Y-560527D01*
X2727620Y-560944D01*
X2728860Y-560527D01*
X2729790Y-559486D01*
X2730410Y-558236D01*
X2730875Y-556569D01*
X2731030Y-554694D01*
X2730875Y-552819D01*
X2730410Y-551152D01*
X2729790Y-549902D01*
X2728860Y-548861D01*
X2727620Y-548444D01*
G01X2737230Y-561361D02*
X2742810Y-548444D01*
G01X2750405Y-556777D02*
X2754435D01*
G01X2766680Y-560944D02*
Y-548444D01*
X2760945Y-557402D01*
X2768695D01*
G01X2777220Y-561361D02*
X2776910Y-561152D01*
Y-560736D01*
X2777220Y-560527D01*
X2777530Y-560736D01*
Y-561152D01*
X2777220Y-561361D01*
G01X2789620Y-548444D02*
X2788380Y-548861D01*
X2787450Y-549902D01*
X2786830Y-551152D01*
X2786365Y-552819D01*
X2786210Y-554694D01*
X2786365Y-556569D01*
X2786830Y-558236D01*
X2787450Y-559486D01*
X2788380Y-560527D01*
X2789620Y-560944D01*
X2790860Y-560527D01*
X2791790Y-559486D01*
X2792410Y-558236D01*
X2792875Y-556569D01*
X2793030Y-554694D01*
X2792875Y-552819D01*
X2792410Y-551152D01*
X2791790Y-549902D01*
X2790860Y-548861D01*
X2789620Y-548444D01*
G01X2688715Y-497677D02*
X2692435D01*
G01X2690420Y-494969D02*
Y-500386D01*
G01X2699875Y-491427D02*
X2700805Y-490178D01*
X2701890Y-489552D01*
X2703130Y-489344D01*
X2704680Y-489761D01*
X2705765Y-490802D01*
X2706075Y-492052D01*
X2705920Y-493303D01*
X2705300Y-494344D01*
X2702200Y-496427D01*
X2700805Y-497886D01*
X2699875Y-499969D01*
X2699565Y-501844D01*
X2706075D01*
G01X2715220Y-502261D02*
X2714910Y-502052D01*
Y-501636D01*
X2715220Y-501427D01*
X2715530Y-501636D01*
Y-502052D01*
X2715220Y-502261D01*
G01X2727620Y-489344D02*
X2726380Y-489761D01*
X2725450Y-490802D01*
X2724830Y-492052D01*
X2724365Y-493719D01*
X2724210Y-495594D01*
X2724365Y-497469D01*
X2724830Y-499136D01*
X2725450Y-500386D01*
X2726380Y-501427D01*
X2727620Y-501844D01*
X2728860Y-501427D01*
X2729790Y-500386D01*
X2730410Y-499136D01*
X2730875Y-497469D01*
X2731030Y-495594D01*
X2730875Y-493719D01*
X2730410Y-492052D01*
X2729790Y-490802D01*
X2728860Y-489761D01*
X2727620Y-489344D01*
G01X2737230Y-502261D02*
X2742810Y-489344D01*
G01X2750405Y-497677D02*
X2754435D01*
G01X2761875Y-491427D02*
X2762805Y-490178D01*
X2763890Y-489552D01*
X2765130Y-489344D01*
X2766680Y-489761D01*
X2767765Y-490802D01*
X2768075Y-492052D01*
X2767920Y-493303D01*
X2767300Y-494344D01*
X2764200Y-496427D01*
X2762805Y-497886D01*
X2761875Y-499969D01*
X2761565Y-501844D01*
X2768075D01*
G01X2777220Y-502261D02*
X2776910Y-502052D01*
Y-501636D01*
X2777220Y-501427D01*
X2777530Y-501636D01*
Y-502052D01*
X2777220Y-502261D01*
G01X2789620Y-489344D02*
X2788380Y-489761D01*
X2787450Y-490802D01*
X2786830Y-492052D01*
X2786365Y-493719D01*
X2786210Y-495594D01*
X2786365Y-497469D01*
X2786830Y-499136D01*
X2787450Y-500386D01*
X2788380Y-501427D01*
X2789620Y-501844D01*
X2790860Y-501427D01*
X2791790Y-500386D01*
X2792410Y-499136D01*
X2792875Y-497469D01*
X2793030Y-495594D01*
X2792875Y-493719D01*
X2792410Y-492052D01*
X2791790Y-490802D01*
X2790860Y-489761D01*
X2789620Y-489344D01*
G01X2688715Y-379477D02*
X2692435D01*
G01X2690420Y-376769D02*
Y-382186D01*
G01X2704680Y-383644D02*
Y-371144D01*
X2698945Y-380102D01*
X2706695D01*
G01X2715220Y-384061D02*
X2714910Y-383852D01*
Y-383436D01*
X2715220Y-383227D01*
X2715530Y-383436D01*
Y-383852D01*
X2715220Y-384061D01*
G01X2727620Y-371144D02*
X2726380Y-371561D01*
X2725450Y-372602D01*
X2724830Y-373852D01*
X2724365Y-375519D01*
X2724210Y-377394D01*
X2724365Y-379269D01*
X2724830Y-380936D01*
X2725450Y-382186D01*
X2726380Y-383227D01*
X2727620Y-383644D01*
X2728860Y-383227D01*
X2729790Y-382186D01*
X2730410Y-380936D01*
X2730875Y-379269D01*
X2731030Y-377394D01*
X2730875Y-375519D01*
X2730410Y-373852D01*
X2729790Y-372602D01*
X2728860Y-371561D01*
X2727620Y-371144D01*
G01X2737230Y-384061D02*
X2742810Y-371144D01*
G01X2750405Y-379477D02*
X2754435D01*
G01X2766680Y-383644D02*
Y-371144D01*
X2760945Y-380102D01*
X2768695D01*
G01X2777220Y-384061D02*
X2776910Y-383852D01*
Y-383436D01*
X2777220Y-383227D01*
X2777530Y-383436D01*
Y-383852D01*
X2777220Y-384061D01*
G01X2789620Y-371144D02*
X2788380Y-371561D01*
X2787450Y-372602D01*
X2786830Y-373852D01*
X2786365Y-375519D01*
X2786210Y-377394D01*
X2786365Y-379269D01*
X2786830Y-380936D01*
X2787450Y-382186D01*
X2788380Y-383227D01*
X2789620Y-383644D01*
X2790860Y-383227D01*
X2791790Y-382186D01*
X2792410Y-380936D01*
X2792875Y-379269D01*
X2793030Y-377394D01*
X2792875Y-375519D01*
X2792410Y-373852D01*
X2791790Y-372602D01*
X2790860Y-371561D01*
X2789620Y-371144D01*
G01X2688715Y-320377D02*
X2692435D01*
G01X2690420Y-317669D02*
Y-323086D01*
G01X2699875Y-314127D02*
X2700805Y-312878D01*
X2701890Y-312252D01*
X2703130Y-312044D01*
X2704680Y-312461D01*
X2705765Y-313502D01*
X2706075Y-314752D01*
X2705920Y-316003D01*
X2705300Y-317044D01*
X2702200Y-319127D01*
X2700805Y-320586D01*
X2699875Y-322669D01*
X2699565Y-324544D01*
X2706075D01*
G01X2715220Y-324961D02*
X2714910Y-324752D01*
Y-324336D01*
X2715220Y-324127D01*
X2715530Y-324336D01*
Y-324752D01*
X2715220Y-324961D01*
G01X2727620Y-312044D02*
X2726380Y-312461D01*
X2725450Y-313502D01*
X2724830Y-314752D01*
X2724365Y-316419D01*
X2724210Y-318294D01*
X2724365Y-320169D01*
X2724830Y-321836D01*
X2725450Y-323086D01*
X2726380Y-324127D01*
X2727620Y-324544D01*
X2728860Y-324127D01*
X2729790Y-323086D01*
X2730410Y-321836D01*
X2730875Y-320169D01*
X2731030Y-318294D01*
X2730875Y-316419D01*
X2730410Y-314752D01*
X2729790Y-313502D01*
X2728860Y-312461D01*
X2727620Y-312044D01*
G01X2737230Y-324961D02*
X2742810Y-312044D01*
G01X2750405Y-320377D02*
X2754435D01*
G01X2761875Y-314127D02*
X2762805Y-312878D01*
X2763890Y-312252D01*
X2765130Y-312044D01*
X2766680Y-312461D01*
X2767765Y-313502D01*
X2768075Y-314752D01*
X2767920Y-316003D01*
X2767300Y-317044D01*
X2764200Y-319127D01*
X2762805Y-320586D01*
X2761875Y-322669D01*
X2761565Y-324544D01*
X2768075D01*
G01X2777220Y-324961D02*
X2776910Y-324752D01*
Y-324336D01*
X2777220Y-324127D01*
X2777530Y-324336D01*
Y-324752D01*
X2777220Y-324961D01*
G01X2789620Y-312044D02*
X2788380Y-312461D01*
X2787450Y-313502D01*
X2786830Y-314752D01*
X2786365Y-316419D01*
X2786210Y-318294D01*
X2786365Y-320169D01*
X2786830Y-321836D01*
X2787450Y-323086D01*
X2788380Y-324127D01*
X2789620Y-324544D01*
X2790860Y-324127D01*
X2791790Y-323086D01*
X2792410Y-321836D01*
X2792875Y-320169D01*
X2793030Y-318294D01*
X2792875Y-316419D01*
X2792410Y-314752D01*
X2791790Y-313502D01*
X2790860Y-312461D01*
X2789620Y-312044D01*
G01X2688715Y-261277D02*
X2692435D01*
G01X2690420Y-258569D02*
Y-263986D01*
G01X2699875Y-255027D02*
X2700805Y-253778D01*
X2701890Y-253152D01*
X2703130Y-252944D01*
X2704680Y-253361D01*
X2705765Y-254402D01*
X2706075Y-255652D01*
X2705920Y-256903D01*
X2705300Y-257944D01*
X2702200Y-260027D01*
X2700805Y-261486D01*
X2699875Y-263569D01*
X2699565Y-265444D01*
X2706075D01*
G01X2715220Y-265861D02*
X2714910Y-265652D01*
Y-265236D01*
X2715220Y-265027D01*
X2715530Y-265236D01*
Y-265652D01*
X2715220Y-265861D01*
G01X2727620Y-252944D02*
X2726380Y-253361D01*
X2725450Y-254402D01*
X2724830Y-255652D01*
X2724365Y-257319D01*
X2724210Y-259194D01*
X2724365Y-261069D01*
X2724830Y-262736D01*
X2725450Y-263986D01*
X2726380Y-265027D01*
X2727620Y-265444D01*
X2728860Y-265027D01*
X2729790Y-263986D01*
X2730410Y-262736D01*
X2730875Y-261069D01*
X2731030Y-259194D01*
X2730875Y-257319D01*
X2730410Y-255652D01*
X2729790Y-254402D01*
X2728860Y-253361D01*
X2727620Y-252944D01*
G01X2737230Y-265861D02*
X2742810Y-252944D01*
G01X2750405Y-261277D02*
X2754435D01*
G01X2761875Y-255027D02*
X2762805Y-253778D01*
X2763890Y-253152D01*
X2765130Y-252944D01*
X2766680Y-253361D01*
X2767765Y-254402D01*
X2768075Y-255652D01*
X2767920Y-256903D01*
X2767300Y-257944D01*
X2764200Y-260027D01*
X2762805Y-261486D01*
X2761875Y-263569D01*
X2761565Y-265444D01*
X2768075D01*
G01X2777220Y-265861D02*
X2776910Y-265652D01*
Y-265236D01*
X2777220Y-265027D01*
X2777530Y-265236D01*
Y-265652D01*
X2777220Y-265861D01*
G01X2789620Y-252944D02*
X2788380Y-253361D01*
X2787450Y-254402D01*
X2786830Y-255652D01*
X2786365Y-257319D01*
X2786210Y-259194D01*
X2786365Y-261069D01*
X2786830Y-262736D01*
X2787450Y-263986D01*
X2788380Y-265027D01*
X2789620Y-265444D01*
X2790860Y-265027D01*
X2791790Y-263986D01*
X2792410Y-262736D01*
X2792875Y-261069D01*
X2793030Y-259194D01*
X2792875Y-257319D01*
X2792410Y-255652D01*
X2791790Y-254402D01*
X2790860Y-253361D01*
X2789620Y-252944D01*
G01X2688715Y-202177D02*
X2692435D01*
G01X2690420Y-199469D02*
Y-204886D01*
G01X2699875Y-195927D02*
X2700805Y-194678D01*
X2701890Y-194052D01*
X2703130Y-193844D01*
X2704680Y-194261D01*
X2705765Y-195302D01*
X2706075Y-196552D01*
X2705920Y-197803D01*
X2705300Y-198844D01*
X2702200Y-200927D01*
X2700805Y-202386D01*
X2699875Y-204469D01*
X2699565Y-206344D01*
X2706075D01*
G01X2715220Y-206761D02*
X2714910Y-206552D01*
Y-206136D01*
X2715220Y-205927D01*
X2715530Y-206136D01*
Y-206552D01*
X2715220Y-206761D01*
G01X2727620Y-193844D02*
X2726380Y-194261D01*
X2725450Y-195302D01*
X2724830Y-196552D01*
X2724365Y-198219D01*
X2724210Y-200094D01*
X2724365Y-201969D01*
X2724830Y-203636D01*
X2725450Y-204886D01*
X2726380Y-205927D01*
X2727620Y-206344D01*
X2728860Y-205927D01*
X2729790Y-204886D01*
X2730410Y-203636D01*
X2730875Y-201969D01*
X2731030Y-200094D01*
X2730875Y-198219D01*
X2730410Y-196552D01*
X2729790Y-195302D01*
X2728860Y-194261D01*
X2727620Y-193844D01*
G01X2737230Y-206761D02*
X2742810Y-193844D01*
G01X2750405Y-202177D02*
X2754435D01*
G01X2761875Y-195927D02*
X2762805Y-194678D01*
X2763890Y-194052D01*
X2765130Y-193844D01*
X2766680Y-194261D01*
X2767765Y-195302D01*
X2768075Y-196552D01*
X2767920Y-197803D01*
X2767300Y-198844D01*
X2764200Y-200927D01*
X2762805Y-202386D01*
X2761875Y-204469D01*
X2761565Y-206344D01*
X2768075D01*
G01X2777220Y-206761D02*
X2776910Y-206552D01*
Y-206136D01*
X2777220Y-205927D01*
X2777530Y-206136D01*
Y-206552D01*
X2777220Y-206761D01*
G01X2789620Y-193844D02*
X2788380Y-194261D01*
X2787450Y-195302D01*
X2786830Y-196552D01*
X2786365Y-198219D01*
X2786210Y-200094D01*
X2786365Y-201969D01*
X2786830Y-203636D01*
X2787450Y-204886D01*
X2788380Y-205927D01*
X2789620Y-206344D01*
X2790860Y-205927D01*
X2791790Y-204886D01*
X2792410Y-203636D01*
X2792875Y-201969D01*
X2793030Y-200094D01*
X2792875Y-198219D01*
X2792410Y-196552D01*
X2791790Y-195302D01*
X2790860Y-194261D01*
X2789620Y-193844D01*
G01X2688715Y-143077D02*
X2692435D01*
G01X2690420Y-140369D02*
Y-145786D01*
G01X2699875Y-136827D02*
X2700805Y-135578D01*
X2701890Y-134952D01*
X2703130Y-134744D01*
X2704680Y-135161D01*
X2705765Y-136202D01*
X2706075Y-137452D01*
X2705920Y-138703D01*
X2705300Y-139744D01*
X2702200Y-141827D01*
X2700805Y-143286D01*
X2699875Y-145369D01*
X2699565Y-147244D01*
X2706075D01*
G01X2715220Y-147661D02*
X2714910Y-147452D01*
Y-147036D01*
X2715220Y-146827D01*
X2715530Y-147036D01*
Y-147452D01*
X2715220Y-147661D01*
G01X2727620Y-134744D02*
X2726380Y-135161D01*
X2725450Y-136202D01*
X2724830Y-137452D01*
X2724365Y-139119D01*
X2724210Y-140994D01*
X2724365Y-142869D01*
X2724830Y-144536D01*
X2725450Y-145786D01*
X2726380Y-146827D01*
X2727620Y-147244D01*
X2728860Y-146827D01*
X2729790Y-145786D01*
X2730410Y-144536D01*
X2730875Y-142869D01*
X2731030Y-140994D01*
X2730875Y-139119D01*
X2730410Y-137452D01*
X2729790Y-136202D01*
X2728860Y-135161D01*
X2727620Y-134744D01*
G01X2737230Y-147661D02*
X2742810Y-134744D01*
G01X2750405Y-143077D02*
X2754435D01*
G01X2764820Y-134744D02*
X2763580Y-135161D01*
X2762650Y-136202D01*
X2762030Y-137452D01*
X2761565Y-139119D01*
X2761410Y-140994D01*
X2761565Y-142869D01*
X2762030Y-144536D01*
X2762650Y-145786D01*
X2763580Y-146827D01*
X2764820Y-147244D01*
X2766060Y-146827D01*
X2766990Y-145786D01*
X2767610Y-144536D01*
X2768075Y-142869D01*
X2768230Y-140994D01*
X2768075Y-139119D01*
X2767610Y-137452D01*
X2766990Y-136202D01*
X2766060Y-135161D01*
X2764820Y-134744D01*
G01X2777220Y-147661D02*
X2776910Y-147452D01*
Y-147036D01*
X2777220Y-146827D01*
X2777530Y-147036D01*
Y-147452D01*
X2777220Y-147661D01*
G01X2789620Y-134744D02*
X2788380Y-135161D01*
X2787450Y-136202D01*
X2786830Y-137452D01*
X2786365Y-139119D01*
X2786210Y-140994D01*
X2786365Y-142869D01*
X2786830Y-144536D01*
X2787450Y-145786D01*
X2788380Y-146827D01*
X2789620Y-147244D01*
X2790860Y-146827D01*
X2791790Y-145786D01*
X2792410Y-144536D01*
X2792875Y-142869D01*
X2793030Y-140994D01*
X2792875Y-139119D01*
X2792410Y-137452D01*
X2791790Y-136202D01*
X2790860Y-135161D01*
X2789620Y-134744D01*
G01X2688715Y-83977D02*
X2692435D01*
G01X2690420Y-81269D02*
Y-86686D01*
G01X2699875Y-77727D02*
X2700805Y-76478D01*
X2701890Y-75852D01*
X2703130Y-75644D01*
X2704680Y-76061D01*
X2705765Y-77102D01*
X2706075Y-78352D01*
X2705920Y-79603D01*
X2705300Y-80644D01*
X2702200Y-82727D01*
X2700805Y-84186D01*
X2699875Y-86269D01*
X2699565Y-88144D01*
X2706075D01*
G01X2715220Y-88561D02*
X2714910Y-88352D01*
Y-87936D01*
X2715220Y-87727D01*
X2715530Y-87936D01*
Y-88352D01*
X2715220Y-88561D01*
G01X2727620Y-75644D02*
X2726380Y-76061D01*
X2725450Y-77102D01*
X2724830Y-78352D01*
X2724365Y-80019D01*
X2724210Y-81894D01*
X2724365Y-83769D01*
X2724830Y-85436D01*
X2725450Y-86686D01*
X2726380Y-87727D01*
X2727620Y-88144D01*
X2728860Y-87727D01*
X2729790Y-86686D01*
X2730410Y-85436D01*
X2730875Y-83769D01*
X2731030Y-81894D01*
X2730875Y-80019D01*
X2730410Y-78352D01*
X2729790Y-77102D01*
X2728860Y-76061D01*
X2727620Y-75644D01*
G01X2737230Y-88561D02*
X2742810Y-75644D01*
G01X2750405Y-83977D02*
X2754435D01*
G01X2761875Y-77727D02*
X2762805Y-76478D01*
X2763890Y-75852D01*
X2765130Y-75644D01*
X2766680Y-76061D01*
X2767765Y-77102D01*
X2768075Y-78352D01*
X2767920Y-79603D01*
X2767300Y-80644D01*
X2764200Y-82727D01*
X2762805Y-84186D01*
X2761875Y-86269D01*
X2761565Y-88144D01*
X2768075D01*
G01X2777220Y-88561D02*
X2776910Y-88352D01*
Y-87936D01*
X2777220Y-87727D01*
X2777530Y-87936D01*
Y-88352D01*
X2777220Y-88561D01*
G01X2789620Y-75644D02*
X2788380Y-76061D01*
X2787450Y-77102D01*
X2786830Y-78352D01*
X2786365Y-80019D01*
X2786210Y-81894D01*
X2786365Y-83769D01*
X2786830Y-85436D01*
X2787450Y-86686D01*
X2788380Y-87727D01*
X2789620Y-88144D01*
X2790860Y-87727D01*
X2791790Y-86686D01*
X2792410Y-85436D01*
X2792875Y-83769D01*
X2793030Y-81894D01*
X2792875Y-80019D01*
X2792410Y-78352D01*
X2791790Y-77102D01*
X2790860Y-76061D01*
X2789620Y-75644D01*
G01X2688715Y-24877D02*
X2692435D01*
G01X2690420Y-22169D02*
Y-27586D01*
G01X2699875Y-18627D02*
X2700805Y-17378D01*
X2701890Y-16752D01*
X2703130Y-16544D01*
X2704680Y-16961D01*
X2705765Y-18002D01*
X2706075Y-19252D01*
X2705920Y-20503D01*
X2705300Y-21544D01*
X2702200Y-23627D01*
X2700805Y-25086D01*
X2699875Y-27169D01*
X2699565Y-29044D01*
X2706075D01*
G01X2715220Y-29461D02*
X2714910Y-29252D01*
Y-28836D01*
X2715220Y-28627D01*
X2715530Y-28836D01*
Y-29252D01*
X2715220Y-29461D01*
G01X2727620Y-16544D02*
X2726380Y-16961D01*
X2725450Y-18002D01*
X2724830Y-19252D01*
X2724365Y-20919D01*
X2724210Y-22794D01*
X2724365Y-24669D01*
X2724830Y-26336D01*
X2725450Y-27586D01*
X2726380Y-28627D01*
X2727620Y-29044D01*
X2728860Y-28627D01*
X2729790Y-27586D01*
X2730410Y-26336D01*
X2730875Y-24669D01*
X2731030Y-22794D01*
X2730875Y-20919D01*
X2730410Y-19252D01*
X2729790Y-18002D01*
X2728860Y-16961D01*
X2727620Y-16544D01*
G01X2737230Y-29461D02*
X2742810Y-16544D01*
G01X2750405Y-24877D02*
X2754435D01*
G01X2761875Y-18627D02*
X2762805Y-17378D01*
X2763890Y-16752D01*
X2765130Y-16544D01*
X2766680Y-16961D01*
X2767765Y-18002D01*
X2768075Y-19252D01*
X2767920Y-20503D01*
X2767300Y-21544D01*
X2764200Y-23627D01*
X2762805Y-25086D01*
X2761875Y-27169D01*
X2761565Y-29044D01*
X2768075D01*
G01X2777220Y-29461D02*
X2776910Y-29252D01*
Y-28836D01*
X2777220Y-28627D01*
X2777530Y-28836D01*
Y-29252D01*
X2777220Y-29461D01*
G01X2789620Y-16544D02*
X2788380Y-16961D01*
X2787450Y-18002D01*
X2786830Y-19252D01*
X2786365Y-20919D01*
X2786210Y-22794D01*
X2786365Y-24669D01*
X2786830Y-26336D01*
X2787450Y-27586D01*
X2788380Y-28627D01*
X2789620Y-29044D01*
X2790860Y-28627D01*
X2791790Y-27586D01*
X2792410Y-26336D01*
X2792875Y-24669D01*
X2793030Y-22794D01*
X2792875Y-20919D01*
X2792410Y-19252D01*
X2791790Y-18002D01*
X2790860Y-16961D01*
X2789620Y-16544D01*
G01X2688715Y34223D02*
X2692435D01*
G01X2690420Y36931D02*
Y31514D01*
G01X2699875Y40473D02*
X2700805Y41722D01*
X2701890Y42348D01*
X2703130Y42556D01*
X2704680Y42139D01*
X2705765Y41098D01*
X2706075Y39848D01*
X2705920Y38597D01*
X2705300Y37556D01*
X2702200Y35473D01*
X2700805Y34014D01*
X2699875Y31931D01*
X2699565Y30056D01*
X2706075D01*
G01X2715220Y29639D02*
X2714910Y29848D01*
Y30264D01*
X2715220Y30473D01*
X2715530Y30264D01*
Y29848D01*
X2715220Y29639D01*
G01X2727620Y42556D02*
X2726380Y42139D01*
X2725450Y41098D01*
X2724830Y39848D01*
X2724365Y38181D01*
X2724210Y36306D01*
X2724365Y34431D01*
X2724830Y32764D01*
X2725450Y31514D01*
X2726380Y30473D01*
X2727620Y30056D01*
X2728860Y30473D01*
X2729790Y31514D01*
X2730410Y32764D01*
X2730875Y34431D01*
X2731030Y36306D01*
X2730875Y38181D01*
X2730410Y39848D01*
X2729790Y41098D01*
X2728860Y42139D01*
X2727620Y42556D01*
G01X2737230Y29639D02*
X2742810Y42556D01*
G01X2750405Y34223D02*
X2754435D01*
G01X2761875Y40473D02*
X2762805Y41722D01*
X2763890Y42348D01*
X2765130Y42556D01*
X2766680Y42139D01*
X2767765Y41098D01*
X2768075Y39848D01*
X2767920Y38597D01*
X2767300Y37556D01*
X2764200Y35473D01*
X2762805Y34014D01*
X2761875Y31931D01*
X2761565Y30056D01*
X2768075D01*
G01X2777220Y29639D02*
X2776910Y29848D01*
Y30264D01*
X2777220Y30473D01*
X2777530Y30264D01*
Y29848D01*
X2777220Y29639D01*
G01X2789620Y42556D02*
X2788380Y42139D01*
X2787450Y41098D01*
X2786830Y39848D01*
X2786365Y38181D01*
X2786210Y36306D01*
X2786365Y34431D01*
X2786830Y32764D01*
X2787450Y31514D01*
X2788380Y30473D01*
X2789620Y30056D01*
X2790860Y30473D01*
X2791790Y31514D01*
X2792410Y32764D01*
X2792875Y34431D01*
X2793030Y36306D01*
X2792875Y38181D01*
X2792410Y39848D01*
X2791790Y41098D01*
X2790860Y42139D01*
X2789620Y42556D01*
G01X2688715Y93323D02*
X2692435D01*
G01X2690420Y96031D02*
Y90614D01*
G01X2699875Y99573D02*
X2700805Y100822D01*
X2701890Y101448D01*
X2703130Y101656D01*
X2704680Y101239D01*
X2705765Y100198D01*
X2706075Y98948D01*
X2705920Y97697D01*
X2705300Y96656D01*
X2702200Y94573D01*
X2700805Y93114D01*
X2699875Y91031D01*
X2699565Y89156D01*
X2706075D01*
G01X2715220Y88739D02*
X2714910Y88948D01*
Y89364D01*
X2715220Y89573D01*
X2715530Y89364D01*
Y88948D01*
X2715220Y88739D01*
G01X2727620Y101656D02*
X2726380Y101239D01*
X2725450Y100198D01*
X2724830Y98948D01*
X2724365Y97281D01*
X2724210Y95406D01*
X2724365Y93531D01*
X2724830Y91864D01*
X2725450Y90614D01*
X2726380Y89573D01*
X2727620Y89156D01*
X2728860Y89573D01*
X2729790Y90614D01*
X2730410Y91864D01*
X2730875Y93531D01*
X2731030Y95406D01*
X2730875Y97281D01*
X2730410Y98948D01*
X2729790Y100198D01*
X2728860Y101239D01*
X2727620Y101656D01*
G01X2737230Y88739D02*
X2742810Y101656D01*
G01X2750405Y93323D02*
X2754435D01*
G01X2761875Y99573D02*
X2762805Y100822D01*
X2763890Y101448D01*
X2765130Y101656D01*
X2766680Y101239D01*
X2767765Y100198D01*
X2768075Y98948D01*
X2767920Y97697D01*
X2767300Y96656D01*
X2764200Y94573D01*
X2762805Y93114D01*
X2761875Y91031D01*
X2761565Y89156D01*
X2768075D01*
G01X2777220Y88739D02*
X2776910Y88948D01*
Y89364D01*
X2777220Y89573D01*
X2777530Y89364D01*
Y88948D01*
X2777220Y88739D01*
G01X2789620Y101656D02*
X2788380Y101239D01*
X2787450Y100198D01*
X2786830Y98948D01*
X2786365Y97281D01*
X2786210Y95406D01*
X2786365Y93531D01*
X2786830Y91864D01*
X2787450Y90614D01*
X2788380Y89573D01*
X2789620Y89156D01*
X2790860Y89573D01*
X2791790Y90614D01*
X2792410Y91864D01*
X2792875Y93531D01*
X2793030Y95406D01*
X2792875Y97281D01*
X2792410Y98948D01*
X2791790Y100198D01*
X2790860Y101239D01*
X2789620Y101656D01*
G01X2688715Y270623D02*
X2692435D01*
G01X2690420Y273331D02*
Y267914D01*
G01X2699875Y276873D02*
X2700805Y278122D01*
X2701890Y278748D01*
X2703130Y278956D01*
X2704680Y278539D01*
X2705765Y277498D01*
X2706075Y276248D01*
X2705920Y274997D01*
X2705300Y273956D01*
X2702200Y271873D01*
X2700805Y270414D01*
X2699875Y268331D01*
X2699565Y266456D01*
X2706075D01*
G01X2715220Y266039D02*
X2714910Y266248D01*
Y266664D01*
X2715220Y266873D01*
X2715530Y266664D01*
Y266248D01*
X2715220Y266039D01*
G01X2727620Y278956D02*
X2726380Y278539D01*
X2725450Y277498D01*
X2724830Y276248D01*
X2724365Y274581D01*
X2724210Y272706D01*
X2724365Y270831D01*
X2724830Y269164D01*
X2725450Y267914D01*
X2726380Y266873D01*
X2727620Y266456D01*
X2728860Y266873D01*
X2729790Y267914D01*
X2730410Y269164D01*
X2730875Y270831D01*
X2731030Y272706D01*
X2730875Y274581D01*
X2730410Y276248D01*
X2729790Y277498D01*
X2728860Y278539D01*
X2727620Y278956D01*
G01X2737230Y266039D02*
X2742810Y278956D01*
G01X2750405Y270623D02*
X2754435D01*
G01X2761875Y276873D02*
X2762805Y278122D01*
X2763890Y278748D01*
X2765130Y278956D01*
X2766680Y278539D01*
X2767765Y277498D01*
X2768075Y276248D01*
X2767920Y274997D01*
X2767300Y273956D01*
X2764200Y271873D01*
X2762805Y270414D01*
X2761875Y268331D01*
X2761565Y266456D01*
X2768075D01*
G01X2777220Y266039D02*
X2776910Y266248D01*
Y266664D01*
X2777220Y266873D01*
X2777530Y266664D01*
Y266248D01*
X2777220Y266039D01*
G01X2789620Y278956D02*
X2788380Y278539D01*
X2787450Y277498D01*
X2786830Y276248D01*
X2786365Y274581D01*
X2786210Y272706D01*
X2786365Y270831D01*
X2786830Y269164D01*
X2787450Y267914D01*
X2788380Y266873D01*
X2789620Y266456D01*
X2790860Y266873D01*
X2791790Y267914D01*
X2792410Y269164D01*
X2792875Y270831D01*
X2793030Y272706D01*
X2792875Y274581D01*
X2792410Y276248D01*
X2791790Y277498D01*
X2790860Y278539D01*
X2789620Y278956D01*
G01X2682515Y329723D02*
X2686235D01*
G01X2684220Y332431D02*
Y327014D01*
G01X2693210Y328056D02*
X2694140Y326597D01*
X2695380Y325764D01*
X2696775Y325556D01*
X2698015Y325764D01*
X2699255Y326806D01*
X2700030Y328056D01*
X2700185Y329306D01*
X2699875Y330764D01*
X2698790Y331806D01*
X2697705Y332223D01*
X2696310D01*
G01X2697705D02*
X2698635Y332848D01*
X2699410Y333889D01*
X2699720Y335139D01*
X2699410Y336389D01*
X2698635Y337431D01*
X2697240Y338056D01*
X2695845Y337848D01*
X2694450Y337014D01*
G01X2709020Y325139D02*
X2708710Y325348D01*
Y325764D01*
X2709020Y325973D01*
X2709330Y325764D01*
Y325348D01*
X2709020Y325139D01*
G01X2721420Y325556D02*
Y338056D01*
X2719560Y335556D01*
G01Y325556D02*
X2723280D01*
G01X2735680D02*
Y338056D01*
X2729945Y329098D01*
X2737695D01*
G01X2743430Y325139D02*
X2749010Y338056D01*
G01X2756605Y329723D02*
X2760635D01*
G01X2771020Y338056D02*
X2769780Y337639D01*
X2768850Y336598D01*
X2768230Y335348D01*
X2767765Y333681D01*
X2767610Y331806D01*
X2767765Y329931D01*
X2768230Y328264D01*
X2768850Y327014D01*
X2769780Y325973D01*
X2771020Y325556D01*
X2772260Y325973D01*
X2773190Y327014D01*
X2773810Y328264D01*
X2774275Y329931D01*
X2774430Y331806D01*
X2774275Y333681D01*
X2773810Y335348D01*
X2773190Y336598D01*
X2772260Y337639D01*
X2771020Y338056D01*
G01X2783420Y325139D02*
X2783110Y325348D01*
Y325764D01*
X2783420Y325973D01*
X2783730Y325764D01*
Y325348D01*
X2783420Y325139D01*
G01X2795820Y338056D02*
X2794580Y337639D01*
X2793650Y336598D01*
X2793030Y335348D01*
X2792565Y333681D01*
X2792410Y331806D01*
X2792565Y329931D01*
X2793030Y328264D01*
X2793650Y327014D01*
X2794580Y325973D01*
X2795820Y325556D01*
X2797060Y325973D01*
X2797990Y327014D01*
X2798610Y328264D01*
X2799075Y329931D01*
X2799230Y331806D01*
X2799075Y333681D01*
X2798610Y335348D01*
X2797990Y336598D01*
X2797060Y337639D01*
X2795820Y338056D01*
G01X2688715Y388823D02*
X2692435D01*
G01X2690420Y391531D02*
Y386114D01*
G01X2699410Y387156D02*
X2700340Y385697D01*
X2701580Y384864D01*
X2702975Y384656D01*
X2704215Y384864D01*
X2705455Y385906D01*
X2706230Y387156D01*
X2706385Y388406D01*
X2706075Y389864D01*
X2704990Y390906D01*
X2703905Y391323D01*
X2702510D01*
G01X2703905D02*
X2704835Y391948D01*
X2705610Y392989D01*
X2705920Y394239D01*
X2705610Y395489D01*
X2704835Y396531D01*
X2703440Y397156D01*
X2702045Y396948D01*
X2700650Y396114D01*
G01X2715220Y384239D02*
X2714910Y384448D01*
Y384864D01*
X2715220Y385073D01*
X2715530Y384864D01*
Y384448D01*
X2715220Y384239D01*
G01X2727620Y397156D02*
X2726380Y396739D01*
X2725450Y395698D01*
X2724830Y394448D01*
X2724365Y392781D01*
X2724210Y390906D01*
X2724365Y389031D01*
X2724830Y387364D01*
X2725450Y386114D01*
X2726380Y385073D01*
X2727620Y384656D01*
X2728860Y385073D01*
X2729790Y386114D01*
X2730410Y387364D01*
X2730875Y389031D01*
X2731030Y390906D01*
X2730875Y392781D01*
X2730410Y394448D01*
X2729790Y395698D01*
X2728860Y396739D01*
X2727620Y397156D01*
G01X2737230Y384239D02*
X2742810Y397156D01*
G01X2750405Y388823D02*
X2754435D01*
G01X2761410Y387156D02*
X2762340Y385697D01*
X2763580Y384864D01*
X2764975Y384656D01*
X2766215Y384864D01*
X2767455Y385906D01*
X2768230Y387156D01*
X2768385Y388406D01*
X2768075Y389864D01*
X2766990Y390906D01*
X2765905Y391323D01*
X2764510D01*
G01X2765905D02*
X2766835Y391948D01*
X2767610Y392989D01*
X2767920Y394239D01*
X2767610Y395489D01*
X2766835Y396531D01*
X2765440Y397156D01*
X2764045Y396948D01*
X2762650Y396114D01*
G01X2777220Y384239D02*
X2776910Y384448D01*
Y384864D01*
X2777220Y385073D01*
X2777530Y384864D01*
Y384448D01*
X2777220Y384239D01*
G01X2789620Y397156D02*
X2788380Y396739D01*
X2787450Y395698D01*
X2786830Y394448D01*
X2786365Y392781D01*
X2786210Y390906D01*
X2786365Y389031D01*
X2786830Y387364D01*
X2787450Y386114D01*
X2788380Y385073D01*
X2789620Y384656D01*
X2790860Y385073D01*
X2791790Y386114D01*
X2792410Y387364D01*
X2792875Y389031D01*
X2793030Y390906D01*
X2792875Y392781D01*
X2792410Y394448D01*
X2791790Y395698D01*
X2790860Y396739D01*
X2789620Y397156D01*
G01X2688715Y447923D02*
X2692435D01*
G01X2690420Y450631D02*
Y445214D01*
G01X2699410Y446256D02*
X2700340Y444797D01*
X2701580Y443964D01*
X2702975Y443756D01*
X2704215Y443964D01*
X2705455Y445006D01*
X2706230Y446256D01*
X2706385Y447506D01*
X2706075Y448964D01*
X2704990Y450006D01*
X2703905Y450423D01*
X2702510D01*
G01X2703905D02*
X2704835Y451048D01*
X2705610Y452089D01*
X2705920Y453339D01*
X2705610Y454589D01*
X2704835Y455631D01*
X2703440Y456256D01*
X2702045Y456048D01*
X2700650Y455214D01*
G01X2715220Y443339D02*
X2714910Y443548D01*
Y443964D01*
X2715220Y444173D01*
X2715530Y443964D01*
Y443548D01*
X2715220Y443339D01*
G01X2727620Y456256D02*
X2726380Y455839D01*
X2725450Y454798D01*
X2724830Y453548D01*
X2724365Y451881D01*
X2724210Y450006D01*
X2724365Y448131D01*
X2724830Y446464D01*
X2725450Y445214D01*
X2726380Y444173D01*
X2727620Y443756D01*
X2728860Y444173D01*
X2729790Y445214D01*
X2730410Y446464D01*
X2730875Y448131D01*
X2731030Y450006D01*
X2730875Y451881D01*
X2730410Y453548D01*
X2729790Y454798D01*
X2728860Y455839D01*
X2727620Y456256D01*
G01X2737230Y443339D02*
X2742810Y456256D01*
G01X2750405Y447923D02*
X2754435D01*
G01X2761410Y446256D02*
X2762340Y444797D01*
X2763580Y443964D01*
X2764975Y443756D01*
X2766215Y443964D01*
X2767455Y445006D01*
X2768230Y446256D01*
X2768385Y447506D01*
X2768075Y448964D01*
X2766990Y450006D01*
X2765905Y450423D01*
X2764510D01*
G01X2765905D02*
X2766835Y451048D01*
X2767610Y452089D01*
X2767920Y453339D01*
X2767610Y454589D01*
X2766835Y455631D01*
X2765440Y456256D01*
X2764045Y456048D01*
X2762650Y455214D01*
G01X2777220Y443339D02*
X2776910Y443548D01*
Y443964D01*
X2777220Y444173D01*
X2777530Y443964D01*
Y443548D01*
X2777220Y443339D01*
G01X2789620Y456256D02*
X2788380Y455839D01*
X2787450Y454798D01*
X2786830Y453548D01*
X2786365Y451881D01*
X2786210Y450006D01*
X2786365Y448131D01*
X2786830Y446464D01*
X2787450Y445214D01*
X2788380Y444173D01*
X2789620Y443756D01*
X2790860Y444173D01*
X2791790Y445214D01*
X2792410Y446464D01*
X2792875Y448131D01*
X2793030Y450006D01*
X2792875Y451881D01*
X2792410Y453548D01*
X2791790Y454798D01*
X2790860Y455839D01*
X2789620Y456256D01*
G01X2688715Y507023D02*
X2692435D01*
G01X2690420Y509731D02*
Y504314D01*
G01X2699410Y505356D02*
X2700340Y503897D01*
X2701580Y503064D01*
X2702975Y502856D01*
X2704215Y503064D01*
X2705455Y504106D01*
X2706230Y505356D01*
X2706385Y506606D01*
X2706075Y508064D01*
X2704990Y509106D01*
X2703905Y509523D01*
X2702510D01*
G01X2703905D02*
X2704835Y510148D01*
X2705610Y511189D01*
X2705920Y512439D01*
X2705610Y513689D01*
X2704835Y514731D01*
X2703440Y515356D01*
X2702045Y515148D01*
X2700650Y514314D01*
G01X2715220Y502439D02*
X2714910Y502648D01*
Y503064D01*
X2715220Y503273D01*
X2715530Y503064D01*
Y502648D01*
X2715220Y502439D01*
G01X2727620Y515356D02*
X2726380Y514939D01*
X2725450Y513898D01*
X2724830Y512648D01*
X2724365Y510981D01*
X2724210Y509106D01*
X2724365Y507231D01*
X2724830Y505564D01*
X2725450Y504314D01*
X2726380Y503273D01*
X2727620Y502856D01*
X2728860Y503273D01*
X2729790Y504314D01*
X2730410Y505564D01*
X2730875Y507231D01*
X2731030Y509106D01*
X2730875Y510981D01*
X2730410Y512648D01*
X2729790Y513898D01*
X2728860Y514939D01*
X2727620Y515356D01*
G01X2737230Y502439D02*
X2742810Y515356D01*
G01X2750405Y507023D02*
X2754435D01*
G01X2761410Y505356D02*
X2762340Y503897D01*
X2763580Y503064D01*
X2764975Y502856D01*
X2766215Y503064D01*
X2767455Y504106D01*
X2768230Y505356D01*
X2768385Y506606D01*
X2768075Y508064D01*
X2766990Y509106D01*
X2765905Y509523D01*
X2764510D01*
G01X2765905D02*
X2766835Y510148D01*
X2767610Y511189D01*
X2767920Y512439D01*
X2767610Y513689D01*
X2766835Y514731D01*
X2765440Y515356D01*
X2764045Y515148D01*
X2762650Y514314D01*
G01X2777220Y502439D02*
X2776910Y502648D01*
Y503064D01*
X2777220Y503273D01*
X2777530Y503064D01*
Y502648D01*
X2777220Y502439D01*
G01X2789620Y515356D02*
X2788380Y514939D01*
X2787450Y513898D01*
X2786830Y512648D01*
X2786365Y510981D01*
X2786210Y509106D01*
X2786365Y507231D01*
X2786830Y505564D01*
X2787450Y504314D01*
X2788380Y503273D01*
X2789620Y502856D01*
X2790860Y503273D01*
X2791790Y504314D01*
X2792410Y505564D01*
X2792875Y507231D01*
X2793030Y509106D01*
X2792875Y510981D01*
X2792410Y512648D01*
X2791790Y513898D01*
X2790860Y514939D01*
X2789620Y515356D01*
G01X2688715Y566123D02*
X2692435D01*
G01X2690420Y568831D02*
Y563414D01*
G01X2699410Y564456D02*
X2700340Y562997D01*
X2701580Y562164D01*
X2702975Y561956D01*
X2704215Y562164D01*
X2705455Y563206D01*
X2706230Y564456D01*
X2706385Y565706D01*
X2706075Y567164D01*
X2704990Y568206D01*
X2703905Y568623D01*
X2702510D01*
G01X2703905D02*
X2704835Y569248D01*
X2705610Y570289D01*
X2705920Y571539D01*
X2705610Y572789D01*
X2704835Y573831D01*
X2703440Y574456D01*
X2702045Y574248D01*
X2700650Y573414D01*
G01X2715220Y561539D02*
X2714910Y561748D01*
Y562164D01*
X2715220Y562373D01*
X2715530Y562164D01*
Y561748D01*
X2715220Y561539D01*
G01X2727620Y574456D02*
X2726380Y574039D01*
X2725450Y572998D01*
X2724830Y571748D01*
X2724365Y570081D01*
X2724210Y568206D01*
X2724365Y566331D01*
X2724830Y564664D01*
X2725450Y563414D01*
X2726380Y562373D01*
X2727620Y561956D01*
X2728860Y562373D01*
X2729790Y563414D01*
X2730410Y564664D01*
X2730875Y566331D01*
X2731030Y568206D01*
X2730875Y570081D01*
X2730410Y571748D01*
X2729790Y572998D01*
X2728860Y574039D01*
X2727620Y574456D01*
G01X2737230Y561539D02*
X2742810Y574456D01*
G01X2750405Y566123D02*
X2754435D01*
G01X2761410Y564456D02*
X2762340Y562997D01*
X2763580Y562164D01*
X2764975Y561956D01*
X2766215Y562164D01*
X2767455Y563206D01*
X2768230Y564456D01*
X2768385Y565706D01*
X2768075Y567164D01*
X2766990Y568206D01*
X2765905Y568623D01*
X2764510D01*
G01X2765905D02*
X2766835Y569248D01*
X2767610Y570289D01*
X2767920Y571539D01*
X2767610Y572789D01*
X2766835Y573831D01*
X2765440Y574456D01*
X2764045Y574248D01*
X2762650Y573414D01*
G01X2777220Y561539D02*
X2776910Y561748D01*
Y562164D01*
X2777220Y562373D01*
X2777530Y562164D01*
Y561748D01*
X2777220Y561539D01*
G01X2789620Y574456D02*
X2788380Y574039D01*
X2787450Y572998D01*
X2786830Y571748D01*
X2786365Y570081D01*
X2786210Y568206D01*
X2786365Y566331D01*
X2786830Y564664D01*
X2787450Y563414D01*
X2788380Y562373D01*
X2789620Y561956D01*
X2790860Y562373D01*
X2791790Y563414D01*
X2792410Y564664D01*
X2792875Y566331D01*
X2793030Y568206D01*
X2792875Y570081D01*
X2792410Y571748D01*
X2791790Y572998D01*
X2790860Y574039D01*
X2789620Y574456D01*
G01X2688715Y625223D02*
X2692435D01*
G01X2690420Y627931D02*
Y622514D01*
G01X2699410Y623556D02*
X2700340Y622097D01*
X2701580Y621264D01*
X2702975Y621056D01*
X2704215Y621264D01*
X2705455Y622306D01*
X2706230Y623556D01*
X2706385Y624806D01*
X2706075Y626264D01*
X2704990Y627306D01*
X2703905Y627723D01*
X2702510D01*
G01X2703905D02*
X2704835Y628348D01*
X2705610Y629389D01*
X2705920Y630639D01*
X2705610Y631889D01*
X2704835Y632931D01*
X2703440Y633556D01*
X2702045Y633348D01*
X2700650Y632514D01*
G01X2715220Y620639D02*
X2714910Y620848D01*
Y621264D01*
X2715220Y621473D01*
X2715530Y621264D01*
Y620848D01*
X2715220Y620639D01*
G01X2727620Y633556D02*
X2726380Y633139D01*
X2725450Y632098D01*
X2724830Y630848D01*
X2724365Y629181D01*
X2724210Y627306D01*
X2724365Y625431D01*
X2724830Y623764D01*
X2725450Y622514D01*
X2726380Y621473D01*
X2727620Y621056D01*
X2728860Y621473D01*
X2729790Y622514D01*
X2730410Y623764D01*
X2730875Y625431D01*
X2731030Y627306D01*
X2730875Y629181D01*
X2730410Y630848D01*
X2729790Y632098D01*
X2728860Y633139D01*
X2727620Y633556D01*
G01X2737230Y620639D02*
X2742810Y633556D01*
G01X2750405Y625223D02*
X2754435D01*
G01X2761410Y623556D02*
X2762340Y622097D01*
X2763580Y621264D01*
X2764975Y621056D01*
X2766215Y621264D01*
X2767455Y622306D01*
X2768230Y623556D01*
X2768385Y624806D01*
X2768075Y626264D01*
X2766990Y627306D01*
X2765905Y627723D01*
X2764510D01*
G01X2765905D02*
X2766835Y628348D01*
X2767610Y629389D01*
X2767920Y630639D01*
X2767610Y631889D01*
X2766835Y632931D01*
X2765440Y633556D01*
X2764045Y633348D01*
X2762650Y632514D01*
G01X2777220Y620639D02*
X2776910Y620848D01*
Y621264D01*
X2777220Y621473D01*
X2777530Y621264D01*
Y620848D01*
X2777220Y620639D01*
G01X2789620Y633556D02*
X2788380Y633139D01*
X2787450Y632098D01*
X2786830Y630848D01*
X2786365Y629181D01*
X2786210Y627306D01*
X2786365Y625431D01*
X2786830Y623764D01*
X2787450Y622514D01*
X2788380Y621473D01*
X2789620Y621056D01*
X2790860Y621473D01*
X2791790Y622514D01*
X2792410Y623764D01*
X2792875Y625431D01*
X2793030Y627306D01*
X2792875Y629181D01*
X2792410Y630848D01*
X2791790Y632098D01*
X2790860Y633139D01*
X2789620Y633556D01*
G01X2688715Y684323D02*
X2692435D01*
G01X2690420Y687031D02*
Y681614D01*
G01X2699410Y682656D02*
X2700340Y681197D01*
X2701580Y680364D01*
X2702975Y680156D01*
X2704215Y680364D01*
X2705455Y681406D01*
X2706230Y682656D01*
X2706385Y683906D01*
X2706075Y685364D01*
X2704990Y686406D01*
X2703905Y686823D01*
X2702510D01*
G01X2703905D02*
X2704835Y687448D01*
X2705610Y688489D01*
X2705920Y689739D01*
X2705610Y690989D01*
X2704835Y692031D01*
X2703440Y692656D01*
X2702045Y692448D01*
X2700650Y691614D01*
G01X2715220Y679739D02*
X2714910Y679948D01*
Y680364D01*
X2715220Y680573D01*
X2715530Y680364D01*
Y679948D01*
X2715220Y679739D01*
G01X2727620Y692656D02*
X2726380Y692239D01*
X2725450Y691198D01*
X2724830Y689948D01*
X2724365Y688281D01*
X2724210Y686406D01*
X2724365Y684531D01*
X2724830Y682864D01*
X2725450Y681614D01*
X2726380Y680573D01*
X2727620Y680156D01*
X2728860Y680573D01*
X2729790Y681614D01*
X2730410Y682864D01*
X2730875Y684531D01*
X2731030Y686406D01*
X2730875Y688281D01*
X2730410Y689948D01*
X2729790Y691198D01*
X2728860Y692239D01*
X2727620Y692656D01*
G01X2737230Y679739D02*
X2742810Y692656D01*
G01X2750405Y684323D02*
X2754435D01*
G01X2761410Y682656D02*
X2762340Y681197D01*
X2763580Y680364D01*
X2764975Y680156D01*
X2766215Y680364D01*
X2767455Y681406D01*
X2768230Y682656D01*
X2768385Y683906D01*
X2768075Y685364D01*
X2766990Y686406D01*
X2765905Y686823D01*
X2764510D01*
G01X2765905D02*
X2766835Y687448D01*
X2767610Y688489D01*
X2767920Y689739D01*
X2767610Y690989D01*
X2766835Y692031D01*
X2765440Y692656D01*
X2764045Y692448D01*
X2762650Y691614D01*
G01X2777220Y679739D02*
X2776910Y679948D01*
Y680364D01*
X2777220Y680573D01*
X2777530Y680364D01*
Y679948D01*
X2777220Y679739D01*
G01X2789620Y692656D02*
X2788380Y692239D01*
X2787450Y691198D01*
X2786830Y689948D01*
X2786365Y688281D01*
X2786210Y686406D01*
X2786365Y684531D01*
X2786830Y682864D01*
X2787450Y681614D01*
X2788380Y680573D01*
X2789620Y680156D01*
X2790860Y680573D01*
X2791790Y681614D01*
X2792410Y682864D01*
X2792875Y684531D01*
X2793030Y686406D01*
X2792875Y688281D01*
X2792410Y689948D01*
X2791790Y691198D01*
X2790860Y692239D01*
X2789620Y692656D01*
G01X2688715Y743423D02*
X2692435D01*
G01X2690420Y746131D02*
Y740714D01*
G01X2699410Y741756D02*
X2700340Y740297D01*
X2701580Y739464D01*
X2702975Y739256D01*
X2704215Y739464D01*
X2705455Y740506D01*
X2706230Y741756D01*
X2706385Y743006D01*
X2706075Y744464D01*
X2704990Y745506D01*
X2703905Y745923D01*
X2702510D01*
G01X2703905D02*
X2704835Y746548D01*
X2705610Y747589D01*
X2705920Y748839D01*
X2705610Y750089D01*
X2704835Y751131D01*
X2703440Y751756D01*
X2702045Y751548D01*
X2700650Y750714D01*
G01X2715220Y738839D02*
X2714910Y739048D01*
Y739464D01*
X2715220Y739673D01*
X2715530Y739464D01*
Y739048D01*
X2715220Y738839D01*
G01X2727620Y751756D02*
X2726380Y751339D01*
X2725450Y750298D01*
X2724830Y749048D01*
X2724365Y747381D01*
X2724210Y745506D01*
X2724365Y743631D01*
X2724830Y741964D01*
X2725450Y740714D01*
X2726380Y739673D01*
X2727620Y739256D01*
X2728860Y739673D01*
X2729790Y740714D01*
X2730410Y741964D01*
X2730875Y743631D01*
X2731030Y745506D01*
X2730875Y747381D01*
X2730410Y749048D01*
X2729790Y750298D01*
X2728860Y751339D01*
X2727620Y751756D01*
G01X2737230Y738839D02*
X2742810Y751756D01*
G01X2750405Y743423D02*
X2754435D01*
G01X2761410Y741756D02*
X2762340Y740297D01*
X2763580Y739464D01*
X2764975Y739256D01*
X2766215Y739464D01*
X2767455Y740506D01*
X2768230Y741756D01*
X2768385Y743006D01*
X2768075Y744464D01*
X2766990Y745506D01*
X2765905Y745923D01*
X2764510D01*
G01X2765905D02*
X2766835Y746548D01*
X2767610Y747589D01*
X2767920Y748839D01*
X2767610Y750089D01*
X2766835Y751131D01*
X2765440Y751756D01*
X2764045Y751548D01*
X2762650Y750714D01*
G01X2777220Y738839D02*
X2776910Y739048D01*
Y739464D01*
X2777220Y739673D01*
X2777530Y739464D01*
Y739048D01*
X2777220Y738839D01*
G01X2789620Y751756D02*
X2788380Y751339D01*
X2787450Y750298D01*
X2786830Y749048D01*
X2786365Y747381D01*
X2786210Y745506D01*
X2786365Y743631D01*
X2786830Y741964D01*
X2787450Y740714D01*
X2788380Y739673D01*
X2789620Y739256D01*
X2790860Y739673D01*
X2791790Y740714D01*
X2792410Y741964D01*
X2792875Y743631D01*
X2793030Y745506D01*
X2792875Y747381D01*
X2792410Y749048D01*
X2791790Y750298D01*
X2790860Y751339D01*
X2789620Y751756D01*
G01X2688715Y861623D02*
X2692435D01*
G01X2690420Y864331D02*
Y858914D01*
G01X2699410Y859956D02*
X2700340Y858497D01*
X2701580Y857664D01*
X2702975Y857456D01*
X2704215Y857664D01*
X2705455Y858706D01*
X2706230Y859956D01*
X2706385Y861206D01*
X2706075Y862664D01*
X2704990Y863706D01*
X2703905Y864123D01*
X2702510D01*
G01X2703905D02*
X2704835Y864748D01*
X2705610Y865789D01*
X2705920Y867039D01*
X2705610Y868289D01*
X2704835Y869331D01*
X2703440Y869956D01*
X2702045Y869748D01*
X2700650Y868914D01*
G01X2715220Y857039D02*
X2714910Y857248D01*
Y857664D01*
X2715220Y857873D01*
X2715530Y857664D01*
Y857248D01*
X2715220Y857039D01*
G01X2727620Y869956D02*
X2726380Y869539D01*
X2725450Y868498D01*
X2724830Y867248D01*
X2724365Y865581D01*
X2724210Y863706D01*
X2724365Y861831D01*
X2724830Y860164D01*
X2725450Y858914D01*
X2726380Y857873D01*
X2727620Y857456D01*
X2728860Y857873D01*
X2729790Y858914D01*
X2730410Y860164D01*
X2730875Y861831D01*
X2731030Y863706D01*
X2730875Y865581D01*
X2730410Y867248D01*
X2729790Y868498D01*
X2728860Y869539D01*
X2727620Y869956D01*
G01X2737230Y857039D02*
X2742810Y869956D01*
G01X2750405Y861623D02*
X2754435D01*
G01X2761410Y859956D02*
X2762340Y858497D01*
X2763580Y857664D01*
X2764975Y857456D01*
X2766215Y857664D01*
X2767455Y858706D01*
X2768230Y859956D01*
X2768385Y861206D01*
X2768075Y862664D01*
X2766990Y863706D01*
X2765905Y864123D01*
X2764510D01*
G01X2765905D02*
X2766835Y864748D01*
X2767610Y865789D01*
X2767920Y867039D01*
X2767610Y868289D01*
X2766835Y869331D01*
X2765440Y869956D01*
X2764045Y869748D01*
X2762650Y868914D01*
G01X2777220Y857039D02*
X2776910Y857248D01*
Y857664D01*
X2777220Y857873D01*
X2777530Y857664D01*
Y857248D01*
X2777220Y857039D01*
G01X2789620Y869956D02*
X2788380Y869539D01*
X2787450Y868498D01*
X2786830Y867248D01*
X2786365Y865581D01*
X2786210Y863706D01*
X2786365Y861831D01*
X2786830Y860164D01*
X2787450Y858914D01*
X2788380Y857873D01*
X2789620Y857456D01*
X2790860Y857873D01*
X2791790Y858914D01*
X2792410Y860164D01*
X2792875Y861831D01*
X2793030Y863706D01*
X2792875Y865581D01*
X2792410Y867248D01*
X2791790Y868498D01*
X2790860Y869539D01*
X2789620Y869956D01*
G01X2688715Y920723D02*
X2692435D01*
G01X2690420Y923431D02*
Y918014D01*
G01X2699875Y926973D02*
X2700805Y928222D01*
X2701890Y928848D01*
X2703130Y929056D01*
X2704680Y928639D01*
X2705765Y927598D01*
X2706075Y926348D01*
X2705920Y925097D01*
X2705300Y924056D01*
X2702200Y921973D01*
X2700805Y920514D01*
X2699875Y918431D01*
X2699565Y916556D01*
X2706075D01*
G01X2715220Y916139D02*
X2714910Y916348D01*
Y916764D01*
X2715220Y916973D01*
X2715530Y916764D01*
Y916348D01*
X2715220Y916139D01*
G01X2727620Y929056D02*
X2726380Y928639D01*
X2725450Y927598D01*
X2724830Y926348D01*
X2724365Y924681D01*
X2724210Y922806D01*
X2724365Y920931D01*
X2724830Y919264D01*
X2725450Y918014D01*
X2726380Y916973D01*
X2727620Y916556D01*
X2728860Y916973D01*
X2729790Y918014D01*
X2730410Y919264D01*
X2730875Y920931D01*
X2731030Y922806D01*
X2730875Y924681D01*
X2730410Y926348D01*
X2729790Y927598D01*
X2728860Y928639D01*
X2727620Y929056D01*
G01X2737230Y916139D02*
X2742810Y929056D01*
G01X2750405Y920723D02*
X2754435D01*
G01X2761875Y926973D02*
X2762805Y928222D01*
X2763890Y928848D01*
X2765130Y929056D01*
X2766680Y928639D01*
X2767765Y927598D01*
X2768075Y926348D01*
X2767920Y925097D01*
X2767300Y924056D01*
X2764200Y921973D01*
X2762805Y920514D01*
X2761875Y918431D01*
X2761565Y916556D01*
X2768075D01*
G01X2777220Y916139D02*
X2776910Y916348D01*
Y916764D01*
X2777220Y916973D01*
X2777530Y916764D01*
Y916348D01*
X2777220Y916139D01*
G01X2789620Y929056D02*
X2788380Y928639D01*
X2787450Y927598D01*
X2786830Y926348D01*
X2786365Y924681D01*
X2786210Y922806D01*
X2786365Y920931D01*
X2786830Y919264D01*
X2787450Y918014D01*
X2788380Y916973D01*
X2789620Y916556D01*
X2790860Y916973D01*
X2791790Y918014D01*
X2792410Y919264D01*
X2792875Y920931D01*
X2793030Y922806D01*
X2792875Y924681D01*
X2792410Y926348D01*
X2791790Y927598D01*
X2790860Y928639D01*
X2789620Y929056D01*
G01X2688715Y979823D02*
X2692435D01*
G01X2690420Y982531D02*
Y977114D01*
G01X2699410Y978156D02*
X2700340Y976697D01*
X2701580Y975864D01*
X2702975Y975656D01*
X2704215Y975864D01*
X2705455Y976906D01*
X2706230Y978156D01*
X2706385Y979406D01*
X2706075Y980864D01*
X2704990Y981906D01*
X2703905Y982323D01*
X2702510D01*
G01X2703905D02*
X2704835Y982948D01*
X2705610Y983989D01*
X2705920Y985239D01*
X2705610Y986489D01*
X2704835Y987531D01*
X2703440Y988156D01*
X2702045Y987948D01*
X2700650Y987114D01*
G01X2715220Y975239D02*
X2714910Y975448D01*
Y975864D01*
X2715220Y976073D01*
X2715530Y975864D01*
Y975448D01*
X2715220Y975239D01*
G01X2727620Y988156D02*
X2726380Y987739D01*
X2725450Y986698D01*
X2724830Y985448D01*
X2724365Y983781D01*
X2724210Y981906D01*
X2724365Y980031D01*
X2724830Y978364D01*
X2725450Y977114D01*
X2726380Y976073D01*
X2727620Y975656D01*
X2728860Y976073D01*
X2729790Y977114D01*
X2730410Y978364D01*
X2730875Y980031D01*
X2731030Y981906D01*
X2730875Y983781D01*
X2730410Y985448D01*
X2729790Y986698D01*
X2728860Y987739D01*
X2727620Y988156D01*
G01X2737230Y975239D02*
X2742810Y988156D01*
G01X2750405Y979823D02*
X2754435D01*
G01X2761410Y978156D02*
X2762340Y976697D01*
X2763580Y975864D01*
X2764975Y975656D01*
X2766215Y975864D01*
X2767455Y976906D01*
X2768230Y978156D01*
X2768385Y979406D01*
X2768075Y980864D01*
X2766990Y981906D01*
X2765905Y982323D01*
X2764510D01*
G01X2765905D02*
X2766835Y982948D01*
X2767610Y983989D01*
X2767920Y985239D01*
X2767610Y986489D01*
X2766835Y987531D01*
X2765440Y988156D01*
X2764045Y987948D01*
X2762650Y987114D01*
G01X2777220Y975239D02*
X2776910Y975448D01*
Y975864D01*
X2777220Y976073D01*
X2777530Y975864D01*
Y975448D01*
X2777220Y975239D01*
G01X2789620Y988156D02*
X2788380Y987739D01*
X2787450Y986698D01*
X2786830Y985448D01*
X2786365Y983781D01*
X2786210Y981906D01*
X2786365Y980031D01*
X2786830Y978364D01*
X2787450Y977114D01*
X2788380Y976073D01*
X2789620Y975656D01*
X2790860Y976073D01*
X2791790Y977114D01*
X2792410Y978364D01*
X2792875Y980031D01*
X2793030Y981906D01*
X2792875Y983781D01*
X2792410Y985448D01*
X2791790Y986698D01*
X2790860Y987739D01*
X2789620Y988156D01*
G01X2682515Y1098023D02*
X2686235D01*
G01X2684220Y1100731D02*
Y1095314D01*
G01X2693210Y1096356D02*
X2694140Y1094897D01*
X2695380Y1094064D01*
X2696775Y1093856D01*
X2698015Y1094064D01*
X2699255Y1095106D01*
X2700030Y1096356D01*
X2700185Y1097606D01*
X2699875Y1099064D01*
X2698790Y1100106D01*
X2697705Y1100523D01*
X2696310D01*
G01X2697705D02*
X2698635Y1101148D01*
X2699410Y1102189D01*
X2699720Y1103439D01*
X2699410Y1104689D01*
X2698635Y1105731D01*
X2697240Y1106356D01*
X2695845Y1106148D01*
X2694450Y1105314D01*
G01X2709020Y1093439D02*
X2708710Y1093648D01*
Y1094064D01*
X2709020Y1094273D01*
X2709330Y1094064D01*
Y1093648D01*
X2709020Y1093439D01*
G01X2718785Y1095314D02*
X2719870Y1094273D01*
X2721110Y1093856D01*
X2722350Y1094273D01*
X2723435Y1095522D01*
X2724210Y1097398D01*
X2724520Y1099273D01*
Y1101564D01*
X2724210Y1103439D01*
X2723435Y1105106D01*
X2722505Y1105939D01*
X2721420Y1106356D01*
X2720180Y1105939D01*
X2719250Y1105106D01*
X2718630Y1103856D01*
X2718320Y1102189D01*
X2718630Y1100731D01*
X2719405Y1099273D01*
X2720335Y1098439D01*
X2721420Y1098231D01*
X2722660Y1098647D01*
X2723590Y1099689D01*
X2724520Y1101564D01*
G01X2730410Y1096356D02*
X2731340Y1094897D01*
X2732580Y1094064D01*
X2733975Y1093856D01*
X2735215Y1094064D01*
X2736455Y1095106D01*
X2737230Y1096356D01*
X2737385Y1097606D01*
X2737075Y1099064D01*
X2735990Y1100106D01*
X2734905Y1100523D01*
X2733510D01*
G01X2734905D02*
X2735835Y1101148D01*
X2736610Y1102189D01*
X2736920Y1103439D01*
X2736610Y1104689D01*
X2735835Y1105731D01*
X2734440Y1106356D01*
X2733045Y1106148D01*
X2731650Y1105314D01*
G01X2743430Y1093439D02*
X2749010Y1106356D01*
G01X2756605Y1098023D02*
X2760635D01*
G01X2771020Y1106356D02*
X2769780Y1105939D01*
X2768850Y1104898D01*
X2768230Y1103648D01*
X2767765Y1101981D01*
X2767610Y1100106D01*
X2767765Y1098231D01*
X2768230Y1096564D01*
X2768850Y1095314D01*
X2769780Y1094273D01*
X2771020Y1093856D01*
X2772260Y1094273D01*
X2773190Y1095314D01*
X2773810Y1096564D01*
X2774275Y1098231D01*
X2774430Y1100106D01*
X2774275Y1101981D01*
X2773810Y1103648D01*
X2773190Y1104898D01*
X2772260Y1105939D01*
X2771020Y1106356D01*
G01X2783420Y1093439D02*
X2783110Y1093648D01*
Y1094064D01*
X2783420Y1094273D01*
X2783730Y1094064D01*
Y1093648D01*
X2783420Y1093439D01*
G01X2795820Y1106356D02*
X2794580Y1105939D01*
X2793650Y1104898D01*
X2793030Y1103648D01*
X2792565Y1101981D01*
X2792410Y1100106D01*
X2792565Y1098231D01*
X2793030Y1096564D01*
X2793650Y1095314D01*
X2794580Y1094273D01*
X2795820Y1093856D01*
X2797060Y1094273D01*
X2797990Y1095314D01*
X2798610Y1096564D01*
X2799075Y1098231D01*
X2799230Y1100106D01*
X2799075Y1101981D01*
X2798610Y1103648D01*
X2797990Y1104898D01*
X2797060Y1105939D01*
X2795820Y1106356D01*
G01X2688715Y1157123D02*
X2692435D01*
G01X2690420Y1159831D02*
Y1154414D01*
G01X2699410Y1155456D02*
X2700340Y1153997D01*
X2701580Y1153164D01*
X2702975Y1152956D01*
X2704215Y1153164D01*
X2705455Y1154206D01*
X2706230Y1155456D01*
X2706385Y1156706D01*
X2706075Y1158164D01*
X2704990Y1159206D01*
X2703905Y1159623D01*
X2702510D01*
G01X2703905D02*
X2704835Y1160248D01*
X2705610Y1161289D01*
X2705920Y1162539D01*
X2705610Y1163789D01*
X2704835Y1164831D01*
X2703440Y1165456D01*
X2702045Y1165248D01*
X2700650Y1164414D01*
G01X2715220Y1152539D02*
X2714910Y1152748D01*
Y1153164D01*
X2715220Y1153373D01*
X2715530Y1153164D01*
Y1152748D01*
X2715220Y1152539D01*
G01X2727620Y1165456D02*
X2726380Y1165039D01*
X2725450Y1163998D01*
X2724830Y1162748D01*
X2724365Y1161081D01*
X2724210Y1159206D01*
X2724365Y1157331D01*
X2724830Y1155664D01*
X2725450Y1154414D01*
X2726380Y1153373D01*
X2727620Y1152956D01*
X2728860Y1153373D01*
X2729790Y1154414D01*
X2730410Y1155664D01*
X2730875Y1157331D01*
X2731030Y1159206D01*
X2730875Y1161081D01*
X2730410Y1162748D01*
X2729790Y1163998D01*
X2728860Y1165039D01*
X2727620Y1165456D01*
G01X2737230Y1152539D02*
X2742810Y1165456D01*
G01X2750405Y1157123D02*
X2754435D01*
G01X2761410Y1155456D02*
X2762340Y1153997D01*
X2763580Y1153164D01*
X2764975Y1152956D01*
X2766215Y1153164D01*
X2767455Y1154206D01*
X2768230Y1155456D01*
X2768385Y1156706D01*
X2768075Y1158164D01*
X2766990Y1159206D01*
X2765905Y1159623D01*
X2764510D01*
G01X2765905D02*
X2766835Y1160248D01*
X2767610Y1161289D01*
X2767920Y1162539D01*
X2767610Y1163789D01*
X2766835Y1164831D01*
X2765440Y1165456D01*
X2764045Y1165248D01*
X2762650Y1164414D01*
G01X2777220Y1152539D02*
X2776910Y1152748D01*
Y1153164D01*
X2777220Y1153373D01*
X2777530Y1153164D01*
Y1152748D01*
X2777220Y1152539D01*
G01X2789620Y1165456D02*
X2788380Y1165039D01*
X2787450Y1163998D01*
X2786830Y1162748D01*
X2786365Y1161081D01*
X2786210Y1159206D01*
X2786365Y1157331D01*
X2786830Y1155664D01*
X2787450Y1154414D01*
X2788380Y1153373D01*
X2789620Y1152956D01*
X2790860Y1153373D01*
X2791790Y1154414D01*
X2792410Y1155664D01*
X2792875Y1157331D01*
X2793030Y1159206D01*
X2792875Y1161081D01*
X2792410Y1162748D01*
X2791790Y1163998D01*
X2790860Y1165039D01*
X2789620Y1165456D01*
G01X2682515Y1334423D02*
X2686235D01*
G01X2684220Y1337131D02*
Y1331714D01*
G01X2696620Y1342756D02*
X2695380Y1342339D01*
X2694450Y1341298D01*
X2693830Y1340048D01*
X2693365Y1338381D01*
X2693210Y1336506D01*
X2693365Y1334631D01*
X2693830Y1332964D01*
X2694450Y1331714D01*
X2695380Y1330673D01*
X2696620Y1330256D01*
X2697860Y1330673D01*
X2698790Y1331714D01*
X2699410Y1332964D01*
X2699875Y1334631D01*
X2700030Y1336506D01*
X2699875Y1338381D01*
X2699410Y1340048D01*
X2698790Y1341298D01*
X2697860Y1342339D01*
X2696620Y1342756D01*
G01X2709020Y1329839D02*
X2708710Y1330048D01*
Y1330464D01*
X2709020Y1330673D01*
X2709330Y1330464D01*
Y1330048D01*
X2709020Y1329839D01*
G01X2721420Y1342756D02*
X2720180Y1342339D01*
X2719250Y1341298D01*
X2718630Y1340048D01*
X2718165Y1338381D01*
X2718010Y1336506D01*
X2718165Y1334631D01*
X2718630Y1332964D01*
X2719250Y1331714D01*
X2720180Y1330673D01*
X2721420Y1330256D01*
X2722660Y1330673D01*
X2723590Y1331714D01*
X2724210Y1332964D01*
X2724675Y1334631D01*
X2724830Y1336506D01*
X2724675Y1338381D01*
X2724210Y1340048D01*
X2723590Y1341298D01*
X2722660Y1342339D01*
X2721420Y1342756D01*
G01X2731030Y1329839D02*
X2736610Y1342756D01*
G01X2744205Y1334423D02*
X2748235D01*
G01X2758620Y1330256D02*
Y1342756D01*
X2756760Y1340256D01*
G01Y1330256D02*
X2760480D01*
G01X2771020Y1342756D02*
X2769780Y1342339D01*
X2768850Y1341298D01*
X2768230Y1340048D01*
X2767765Y1338381D01*
X2767610Y1336506D01*
X2767765Y1334631D01*
X2768230Y1332964D01*
X2768850Y1331714D01*
X2769780Y1330673D01*
X2771020Y1330256D01*
X2772260Y1330673D01*
X2773190Y1331714D01*
X2773810Y1332964D01*
X2774275Y1334631D01*
X2774430Y1336506D01*
X2774275Y1338381D01*
X2773810Y1340048D01*
X2773190Y1341298D01*
X2772260Y1342339D01*
X2771020Y1342756D01*
G01X2783420Y1329839D02*
X2783110Y1330048D01*
Y1330464D01*
X2783420Y1330673D01*
X2783730Y1330464D01*
Y1330048D01*
X2783420Y1329839D01*
G01X2795820Y1342756D02*
X2794580Y1342339D01*
X2793650Y1341298D01*
X2793030Y1340048D01*
X2792565Y1338381D01*
X2792410Y1336506D01*
X2792565Y1334631D01*
X2793030Y1332964D01*
X2793650Y1331714D01*
X2794580Y1330673D01*
X2795820Y1330256D01*
X2797060Y1330673D01*
X2797990Y1331714D01*
X2798610Y1332964D01*
X2799075Y1334631D01*
X2799230Y1336506D01*
X2799075Y1338381D01*
X2798610Y1340048D01*
X2797990Y1341298D01*
X2797060Y1342339D01*
X2795820Y1342756D01*
G01X2682515Y1393523D02*
X2686235D01*
G01X2684220Y1396231D02*
Y1390814D01*
G01X2696620Y1401856D02*
X2695380Y1401439D01*
X2694450Y1400398D01*
X2693830Y1399148D01*
X2693365Y1397481D01*
X2693210Y1395606D01*
X2693365Y1393731D01*
X2693830Y1392064D01*
X2694450Y1390814D01*
X2695380Y1389773D01*
X2696620Y1389356D01*
X2697860Y1389773D01*
X2698790Y1390814D01*
X2699410Y1392064D01*
X2699875Y1393731D01*
X2700030Y1395606D01*
X2699875Y1397481D01*
X2699410Y1399148D01*
X2698790Y1400398D01*
X2697860Y1401439D01*
X2696620Y1401856D01*
G01X2709020Y1388939D02*
X2708710Y1389148D01*
Y1389564D01*
X2709020Y1389773D01*
X2709330Y1389564D01*
Y1389148D01*
X2709020Y1388939D01*
G01X2721420Y1401856D02*
X2720180Y1401439D01*
X2719250Y1400398D01*
X2718630Y1399148D01*
X2718165Y1397481D01*
X2718010Y1395606D01*
X2718165Y1393731D01*
X2718630Y1392064D01*
X2719250Y1390814D01*
X2720180Y1389773D01*
X2721420Y1389356D01*
X2722660Y1389773D01*
X2723590Y1390814D01*
X2724210Y1392064D01*
X2724675Y1393731D01*
X2724830Y1395606D01*
X2724675Y1397481D01*
X2724210Y1399148D01*
X2723590Y1400398D01*
X2722660Y1401439D01*
X2721420Y1401856D01*
G01X2731030Y1388939D02*
X2736610Y1401856D01*
G01X2744205Y1393523D02*
X2748235D01*
G01X2758620Y1389356D02*
Y1401856D01*
X2756760Y1399356D01*
G01Y1389356D02*
X2760480D01*
G01X2771020Y1401856D02*
X2769780Y1401439D01*
X2768850Y1400398D01*
X2768230Y1399148D01*
X2767765Y1397481D01*
X2767610Y1395606D01*
X2767765Y1393731D01*
X2768230Y1392064D01*
X2768850Y1390814D01*
X2769780Y1389773D01*
X2771020Y1389356D01*
X2772260Y1389773D01*
X2773190Y1390814D01*
X2773810Y1392064D01*
X2774275Y1393731D01*
X2774430Y1395606D01*
X2774275Y1397481D01*
X2773810Y1399148D01*
X2773190Y1400398D01*
X2772260Y1401439D01*
X2771020Y1401856D01*
G01X2783420Y1388939D02*
X2783110Y1389148D01*
Y1389564D01*
X2783420Y1389773D01*
X2783730Y1389564D01*
Y1389148D01*
X2783420Y1388939D01*
G01X2795820Y1401856D02*
X2794580Y1401439D01*
X2793650Y1400398D01*
X2793030Y1399148D01*
X2792565Y1397481D01*
X2792410Y1395606D01*
X2792565Y1393731D01*
X2793030Y1392064D01*
X2793650Y1390814D01*
X2794580Y1389773D01*
X2795820Y1389356D01*
X2797060Y1389773D01*
X2797990Y1390814D01*
X2798610Y1392064D01*
X2799075Y1393731D01*
X2799230Y1395606D01*
X2799075Y1397481D01*
X2798610Y1399148D01*
X2797990Y1400398D01*
X2797060Y1401439D01*
X2795820Y1401856D01*
G01X2688715Y1452623D02*
X2692435D01*
G01X2690420Y1455331D02*
Y1449914D01*
G01X2699875Y1458873D02*
X2700805Y1460122D01*
X2701890Y1460748D01*
X2703130Y1460956D01*
X2704680Y1460539D01*
X2705765Y1459498D01*
X2706075Y1458248D01*
X2705920Y1456997D01*
X2705300Y1455956D01*
X2702200Y1453873D01*
X2700805Y1452414D01*
X2699875Y1450331D01*
X2699565Y1448456D01*
X2706075D01*
G01X2715220Y1448039D02*
X2714910Y1448248D01*
Y1448664D01*
X2715220Y1448873D01*
X2715530Y1448664D01*
Y1448248D01*
X2715220Y1448039D01*
G01X2727620Y1460956D02*
X2726380Y1460539D01*
X2725450Y1459498D01*
X2724830Y1458248D01*
X2724365Y1456581D01*
X2724210Y1454706D01*
X2724365Y1452831D01*
X2724830Y1451164D01*
X2725450Y1449914D01*
X2726380Y1448873D01*
X2727620Y1448456D01*
X2728860Y1448873D01*
X2729790Y1449914D01*
X2730410Y1451164D01*
X2730875Y1452831D01*
X2731030Y1454706D01*
X2730875Y1456581D01*
X2730410Y1458248D01*
X2729790Y1459498D01*
X2728860Y1460539D01*
X2727620Y1460956D01*
G01X2737230Y1448039D02*
X2742810Y1460956D01*
G01X2750405Y1452623D02*
X2754435D01*
G01X2761875Y1458873D02*
X2762805Y1460122D01*
X2763890Y1460748D01*
X2765130Y1460956D01*
X2766680Y1460539D01*
X2767765Y1459498D01*
X2768075Y1458248D01*
X2767920Y1456997D01*
X2767300Y1455956D01*
X2764200Y1453873D01*
X2762805Y1452414D01*
X2761875Y1450331D01*
X2761565Y1448456D01*
X2768075D01*
G01X2777220Y1448039D02*
X2776910Y1448248D01*
Y1448664D01*
X2777220Y1448873D01*
X2777530Y1448664D01*
Y1448248D01*
X2777220Y1448039D01*
G01X2789620Y1460956D02*
X2788380Y1460539D01*
X2787450Y1459498D01*
X2786830Y1458248D01*
X2786365Y1456581D01*
X2786210Y1454706D01*
X2786365Y1452831D01*
X2786830Y1451164D01*
X2787450Y1449914D01*
X2788380Y1448873D01*
X2789620Y1448456D01*
X2790860Y1448873D01*
X2791790Y1449914D01*
X2792410Y1451164D01*
X2792875Y1452831D01*
X2793030Y1454706D01*
X2792875Y1456581D01*
X2792410Y1458248D01*
X2791790Y1459498D01*
X2790860Y1460539D01*
X2789620Y1460956D01*
G01X2688715Y1511723D02*
X2692435D01*
G01X2690420Y1514431D02*
Y1509014D01*
G01X2702820Y1520056D02*
X2701580Y1519639D01*
X2700650Y1518598D01*
X2700030Y1517348D01*
X2699565Y1515681D01*
X2699410Y1513806D01*
X2699565Y1511931D01*
X2700030Y1510264D01*
X2700650Y1509014D01*
X2701580Y1507973D01*
X2702820Y1507556D01*
X2704060Y1507973D01*
X2704990Y1509014D01*
X2705610Y1510264D01*
X2706075Y1511931D01*
X2706230Y1513806D01*
X2706075Y1515681D01*
X2705610Y1517348D01*
X2704990Y1518598D01*
X2704060Y1519639D01*
X2702820Y1520056D01*
G01X2715220Y1507139D02*
X2714910Y1507348D01*
Y1507764D01*
X2715220Y1507973D01*
X2715530Y1507764D01*
Y1507348D01*
X2715220Y1507139D01*
G01X2727620Y1520056D02*
X2726380Y1519639D01*
X2725450Y1518598D01*
X2724830Y1517348D01*
X2724365Y1515681D01*
X2724210Y1513806D01*
X2724365Y1511931D01*
X2724830Y1510264D01*
X2725450Y1509014D01*
X2726380Y1507973D01*
X2727620Y1507556D01*
X2728860Y1507973D01*
X2729790Y1509014D01*
X2730410Y1510264D01*
X2730875Y1511931D01*
X2731030Y1513806D01*
X2730875Y1515681D01*
X2730410Y1517348D01*
X2729790Y1518598D01*
X2728860Y1519639D01*
X2727620Y1520056D01*
G01X2737230Y1507139D02*
X2742810Y1520056D01*
G01X2750405Y1511723D02*
X2754435D01*
G01X2764820Y1507556D02*
X2765905Y1507764D01*
X2767145Y1508389D01*
X2767920Y1509431D01*
X2768230Y1510889D01*
X2767920Y1512347D01*
X2766990Y1513598D01*
X2765595Y1514223D01*
X2764045D01*
X2763115Y1514639D01*
X2762340Y1515681D01*
X2762030Y1517139D01*
X2762495Y1518598D01*
X2763580Y1519639D01*
X2764820Y1520056D01*
X2766060Y1519639D01*
X2767145Y1518598D01*
X2767610Y1517139D01*
X2767300Y1515681D01*
X2766525Y1514639D01*
X2765595Y1514223D01*
X2764045D01*
X2762650Y1513598D01*
X2761720Y1512347D01*
X2761410Y1510889D01*
X2761720Y1509431D01*
X2762495Y1508389D01*
X2763735Y1507764D01*
X2764820Y1507556D01*
G01X2777220Y1507139D02*
X2776910Y1507348D01*
Y1507764D01*
X2777220Y1507973D01*
X2777530Y1507764D01*
Y1507348D01*
X2777220Y1507139D01*
G01X2789620Y1520056D02*
X2788380Y1519639D01*
X2787450Y1518598D01*
X2786830Y1517348D01*
X2786365Y1515681D01*
X2786210Y1513806D01*
X2786365Y1511931D01*
X2786830Y1510264D01*
X2787450Y1509014D01*
X2788380Y1507973D01*
X2789620Y1507556D01*
X2790860Y1507973D01*
X2791790Y1509014D01*
X2792410Y1510264D01*
X2792875Y1511931D01*
X2793030Y1513806D01*
X2792875Y1515681D01*
X2792410Y1517348D01*
X2791790Y1518598D01*
X2790860Y1519639D01*
X2789620Y1520056D01*
G01X2848520Y1562106D02*
Y1549606D01*
G01X2844955Y1562106D02*
X2852085D01*
G01X2860920Y1549606D02*
X2859680Y1549814D01*
X2858595Y1550647D01*
X2857665Y1551898D01*
X2857045Y1553356D01*
X2856735Y1555023D01*
Y1556689D01*
X2857045Y1558356D01*
X2857665Y1559814D01*
X2858595Y1561064D01*
X2859680Y1561898D01*
X2860920Y1562106D01*
X2862160Y1561898D01*
X2863245Y1561064D01*
X2864175Y1559814D01*
X2864795Y1558356D01*
X2865105Y1556689D01*
Y1555023D01*
X2864795Y1553356D01*
X2864175Y1551898D01*
X2863245Y1550647D01*
X2862160Y1549814D01*
X2860920Y1549606D01*
G01X2870220Y1562106D02*
Y1549606D01*
X2876420D01*
G01X2888820D02*
X2882620D01*
Y1562106D01*
X2888820D01*
G01X2886340Y1556064D02*
X2882620D01*
G01X2895020Y1549606D02*
Y1562106D01*
X2898895D01*
X2900135Y1561481D01*
X2900910Y1560648D01*
X2901220Y1558981D01*
X2900910Y1557314D01*
X2899980Y1556273D01*
X2898895Y1555648D01*
X2895020D01*
G01X2898895D02*
X2901220Y1549606D01*
G01X2906645D02*
X2910520Y1562106D01*
X2914395Y1549606D01*
G01X2913000Y1553981D02*
X2908040D01*
G01X2919355Y1549606D02*
Y1562106D01*
X2926485Y1549606D01*
Y1562106D01*
G01X2938730Y1561064D02*
X2937800Y1561689D01*
X2936715Y1562106D01*
X2935475D01*
X2934080Y1561481D01*
X2932995Y1560439D01*
X2932220Y1559189D01*
X2931600Y1557106D01*
X2931445Y1555231D01*
X2931755Y1553356D01*
X2932220Y1552106D01*
X2933150Y1550856D01*
X2934235Y1550023D01*
X2935320Y1549606D01*
X2936405D01*
X2937490Y1550023D01*
X2938420Y1550647D01*
X2939195Y1551481D01*
G01X2950820Y1549606D02*
X2944620D01*
Y1562106D01*
X2950820D01*
G01X2948340Y1556064D02*
X2944620D01*
G01X2955470Y1545439D02*
X2964770D01*
G01X2972520Y1562106D02*
Y1549606D01*
G01X2968955Y1562106D02*
X2976085D01*
G01X2981820Y1549606D02*
Y1562106D01*
X2985695D01*
X2986935Y1561481D01*
X2987710Y1560648D01*
X2988020Y1558981D01*
X2987710Y1557314D01*
X2986780Y1556273D01*
X2985695Y1555648D01*
X2981820D01*
G01X2985695D02*
X2988020Y1549606D01*
G01X2993445D02*
X2997320Y1562106D01*
X3001195Y1549606D01*
G01X2999800Y1553981D02*
X2994840D01*
G01X3005845Y1562106D02*
X3009720Y1549606D01*
X3013595Y1562106D01*
G01X3025220Y1549606D02*
X3019020D01*
Y1562106D01*
X3025220D01*
G01X3022740Y1556064D02*
X3019020D01*
G01X3031420Y1562106D02*
Y1549606D01*
X3037620D01*
G01X2877815Y-438577D02*
X2881535D01*
G01X2879520Y-435869D02*
Y-441286D01*
G01X2891920Y-442744D02*
Y-430244D01*
X2890060Y-432744D01*
G01Y-442744D02*
X2893780D01*
G01X2904320Y-443161D02*
X2904010Y-442952D01*
Y-442536D01*
X2904320Y-442327D01*
X2904630Y-442536D01*
Y-442952D01*
X2904320Y-443161D01*
G01X2914085Y-441286D02*
X2915170Y-442327D01*
X2916410Y-442744D01*
X2917650Y-442327D01*
X2918735Y-441078D01*
X2919510Y-439202D01*
X2919820Y-437327D01*
Y-435036D01*
X2919510Y-433161D01*
X2918735Y-431494D01*
X2917805Y-430661D01*
X2916720Y-430244D01*
X2915480Y-430661D01*
X2914550Y-431494D01*
X2913930Y-432744D01*
X2913620Y-434411D01*
X2913930Y-435869D01*
X2914705Y-437327D01*
X2915635Y-438161D01*
X2916720Y-438369D01*
X2917960Y-437953D01*
X2918890Y-436911D01*
X2919820Y-435036D01*
G01X2926175Y-437536D02*
X2927260Y-436077D01*
X2928190Y-435244D01*
X2929430Y-434827D01*
X2930515Y-435244D01*
X2931290Y-436077D01*
X2931910Y-437327D01*
X2932065Y-438786D01*
X2931910Y-440036D01*
X2931290Y-441286D01*
X2930360Y-442327D01*
X2929275Y-442744D01*
X2928035Y-442327D01*
X2926950Y-441078D01*
X2926330Y-439202D01*
X2926175Y-437119D01*
X2926485Y-434411D01*
X2926950Y-432952D01*
X2927725Y-431494D01*
X2928810Y-430452D01*
X2929895Y-430244D01*
X2930980Y-430661D01*
X2931755Y-431702D01*
G01X2938730Y-443161D02*
X2944310Y-430244D01*
G01X2951905Y-438577D02*
X2955935D01*
G01X2966320Y-442744D02*
Y-430244D01*
X2964460Y-432744D01*
G01Y-442744D02*
X2968180D01*
G01X2978720Y-443161D02*
X2978410Y-442952D01*
Y-442536D01*
X2978720Y-442327D01*
X2979030Y-442536D01*
Y-442952D01*
X2978720Y-443161D01*
G01X2988485Y-441286D02*
X2989570Y-442327D01*
X2990810Y-442744D01*
X2992050Y-442327D01*
X2993135Y-441078D01*
X2993910Y-439202D01*
X2994220Y-437327D01*
Y-435036D01*
X2993910Y-433161D01*
X2993135Y-431494D01*
X2992205Y-430661D01*
X2991120Y-430244D01*
X2989880Y-430661D01*
X2988950Y-431494D01*
X2988330Y-432744D01*
X2988020Y-434411D01*
X2988330Y-435869D01*
X2989105Y-437327D01*
X2990035Y-438161D01*
X2991120Y-438369D01*
X2992360Y-437953D01*
X2993290Y-436911D01*
X2994220Y-435036D01*
G01X3000575Y-437536D02*
X3001660Y-436077D01*
X3002590Y-435244D01*
X3003830Y-434827D01*
X3004915Y-435244D01*
X3005690Y-436077D01*
X3006310Y-437327D01*
X3006465Y-438786D01*
X3006310Y-440036D01*
X3005690Y-441286D01*
X3004760Y-442327D01*
X3003675Y-442744D01*
X3002435Y-442327D01*
X3001350Y-441078D01*
X3000730Y-439202D01*
X3000575Y-437119D01*
X3000885Y-434411D01*
X3001350Y-432952D01*
X3002125Y-431494D01*
X3003210Y-430452D01*
X3004295Y-430244D01*
X3005380Y-430661D01*
X3006155Y-431702D01*
G01X2890215Y-615877D02*
X2893935D01*
G01X2891920Y-613169D02*
Y-618586D01*
G01X2906180Y-620044D02*
Y-607544D01*
X2900445Y-616502D01*
X2908195D01*
G01X2916720Y-620461D02*
X2916410Y-620252D01*
Y-619836D01*
X2916720Y-619627D01*
X2917030Y-619836D01*
Y-620252D01*
X2916720Y-620461D01*
G01X2929120Y-607544D02*
X2927880Y-607961D01*
X2926950Y-609002D01*
X2926330Y-610252D01*
X2925865Y-611919D01*
X2925710Y-613794D01*
X2925865Y-615669D01*
X2926330Y-617336D01*
X2926950Y-618586D01*
X2927880Y-619627D01*
X2929120Y-620044D01*
X2930360Y-619627D01*
X2931290Y-618586D01*
X2931910Y-617336D01*
X2932375Y-615669D01*
X2932530Y-613794D01*
X2932375Y-611919D01*
X2931910Y-610252D01*
X2931290Y-609002D01*
X2930360Y-607961D01*
X2929120Y-607544D01*
G01X2938730Y-620461D02*
X2944310Y-607544D01*
G01X2951905Y-615877D02*
X2955935D01*
G01X2968180Y-620044D02*
Y-607544D01*
X2962445Y-616502D01*
X2970195D01*
G01X2978720Y-620461D02*
X2978410Y-620252D01*
Y-619836D01*
X2978720Y-619627D01*
X2979030Y-619836D01*
Y-620252D01*
X2978720Y-620461D01*
G01X2991120Y-607544D02*
X2989880Y-607961D01*
X2988950Y-609002D01*
X2988330Y-610252D01*
X2987865Y-611919D01*
X2987710Y-613794D01*
X2987865Y-615669D01*
X2988330Y-617336D01*
X2988950Y-618586D01*
X2989880Y-619627D01*
X2991120Y-620044D01*
X2992360Y-619627D01*
X2993290Y-618586D01*
X2993910Y-617336D01*
X2994375Y-615669D01*
X2994530Y-613794D01*
X2994375Y-611919D01*
X2993910Y-610252D01*
X2993290Y-609002D01*
X2992360Y-607961D01*
X2991120Y-607544D01*
G01X2890215Y-556777D02*
X2893935D01*
G01X2891920Y-554069D02*
Y-559486D01*
G01X2906180Y-560944D02*
Y-548444D01*
X2900445Y-557402D01*
X2908195D01*
G01X2916720Y-561361D02*
X2916410Y-561152D01*
Y-560736D01*
X2916720Y-560527D01*
X2917030Y-560736D01*
Y-561152D01*
X2916720Y-561361D01*
G01X2929120Y-548444D02*
X2927880Y-548861D01*
X2926950Y-549902D01*
X2926330Y-551152D01*
X2925865Y-552819D01*
X2925710Y-554694D01*
X2925865Y-556569D01*
X2926330Y-558236D01*
X2926950Y-559486D01*
X2927880Y-560527D01*
X2929120Y-560944D01*
X2930360Y-560527D01*
X2931290Y-559486D01*
X2931910Y-558236D01*
X2932375Y-556569D01*
X2932530Y-554694D01*
X2932375Y-552819D01*
X2931910Y-551152D01*
X2931290Y-549902D01*
X2930360Y-548861D01*
X2929120Y-548444D01*
G01X2938730Y-561361D02*
X2944310Y-548444D01*
G01X2951905Y-556777D02*
X2955935D01*
G01X2968180Y-560944D02*
Y-548444D01*
X2962445Y-557402D01*
X2970195D01*
G01X2978720Y-561361D02*
X2978410Y-561152D01*
Y-560736D01*
X2978720Y-560527D01*
X2979030Y-560736D01*
Y-561152D01*
X2978720Y-561361D01*
G01X2991120Y-548444D02*
X2989880Y-548861D01*
X2988950Y-549902D01*
X2988330Y-551152D01*
X2987865Y-552819D01*
X2987710Y-554694D01*
X2987865Y-556569D01*
X2988330Y-558236D01*
X2988950Y-559486D01*
X2989880Y-560527D01*
X2991120Y-560944D01*
X2992360Y-560527D01*
X2993290Y-559486D01*
X2993910Y-558236D01*
X2994375Y-556569D01*
X2994530Y-554694D01*
X2994375Y-552819D01*
X2993910Y-551152D01*
X2993290Y-549902D01*
X2992360Y-548861D01*
X2991120Y-548444D01*
G01X2890215Y-497677D02*
X2893935D01*
G01X2891920Y-494969D02*
Y-500386D01*
G01X2901375Y-491427D02*
X2902305Y-490178D01*
X2903390Y-489552D01*
X2904630Y-489344D01*
X2906180Y-489761D01*
X2907265Y-490802D01*
X2907575Y-492052D01*
X2907420Y-493303D01*
X2906800Y-494344D01*
X2903700Y-496427D01*
X2902305Y-497886D01*
X2901375Y-499969D01*
X2901065Y-501844D01*
X2907575D01*
G01X2916720Y-502261D02*
X2916410Y-502052D01*
Y-501636D01*
X2916720Y-501427D01*
X2917030Y-501636D01*
Y-502052D01*
X2916720Y-502261D01*
G01X2929120Y-489344D02*
X2927880Y-489761D01*
X2926950Y-490802D01*
X2926330Y-492052D01*
X2925865Y-493719D01*
X2925710Y-495594D01*
X2925865Y-497469D01*
X2926330Y-499136D01*
X2926950Y-500386D01*
X2927880Y-501427D01*
X2929120Y-501844D01*
X2930360Y-501427D01*
X2931290Y-500386D01*
X2931910Y-499136D01*
X2932375Y-497469D01*
X2932530Y-495594D01*
X2932375Y-493719D01*
X2931910Y-492052D01*
X2931290Y-490802D01*
X2930360Y-489761D01*
X2929120Y-489344D01*
G01X2938730Y-502261D02*
X2944310Y-489344D01*
G01X2951905Y-497677D02*
X2955935D01*
G01X2963375Y-491427D02*
X2964305Y-490178D01*
X2965390Y-489552D01*
X2966630Y-489344D01*
X2968180Y-489761D01*
X2969265Y-490802D01*
X2969575Y-492052D01*
X2969420Y-493303D01*
X2968800Y-494344D01*
X2965700Y-496427D01*
X2964305Y-497886D01*
X2963375Y-499969D01*
X2963065Y-501844D01*
X2969575D01*
G01X2978720Y-502261D02*
X2978410Y-502052D01*
Y-501636D01*
X2978720Y-501427D01*
X2979030Y-501636D01*
Y-502052D01*
X2978720Y-502261D01*
G01X2991120Y-489344D02*
X2989880Y-489761D01*
X2988950Y-490802D01*
X2988330Y-492052D01*
X2987865Y-493719D01*
X2987710Y-495594D01*
X2987865Y-497469D01*
X2988330Y-499136D01*
X2988950Y-500386D01*
X2989880Y-501427D01*
X2991120Y-501844D01*
X2992360Y-501427D01*
X2993290Y-500386D01*
X2993910Y-499136D01*
X2994375Y-497469D01*
X2994530Y-495594D01*
X2994375Y-493719D01*
X2993910Y-492052D01*
X2993290Y-490802D01*
X2992360Y-489761D01*
X2991120Y-489344D01*
G01X2939505Y-379477D02*
X2943535D01*
G01X2939505Y-320377D02*
X2943535D01*
G01X2939505Y-261277D02*
X2943535D01*
G01X2939505Y-202177D02*
X2943535D01*
G01X2939505Y-143077D02*
X2943535D01*
G01X2939505Y-83977D02*
X2943535D01*
G01X2939505Y-24877D02*
X2943535D01*
G01X2939505Y34223D02*
X2943535D01*
G01X2939505Y93323D02*
X2943535D01*
G01X2939505Y152423D02*
X2943535D01*
G01X2939505Y211523D02*
X2943535D01*
G01X2939505Y270623D02*
X2943535D01*
G01X2939505Y329723D02*
X2943535D01*
G01X2939505Y388823D02*
X2943535D01*
G01X2939505Y447923D02*
X2943535D01*
G01X2939505Y507023D02*
X2943535D01*
G01X2939505Y566123D02*
X2943535D01*
G01X2939505Y625223D02*
X2943535D01*
G01X2939505Y684323D02*
X2943535D01*
G01X2939505Y743423D02*
X2943535D01*
G01X2939505Y802523D02*
X2943535D01*
G01X2939505Y861623D02*
X2943535D01*
G01X2939505Y920723D02*
X2943535D01*
G01X2939505Y979823D02*
X2943535D01*
G01X2939505Y1038923D02*
X2943535D01*
G01X2939505Y1098023D02*
X2943535D01*
G01X2939505Y1157123D02*
X2943535D01*
G01X2939505Y1216223D02*
X2943535D01*
G01X2939505Y1275323D02*
X2943535D01*
G01X2939505Y1334423D02*
X2943535D01*
G01X2939505Y1393523D02*
X2943535D01*
G01X2939505Y1452623D02*
X2943535D01*
G01X2939505Y1511723D02*
X2943535D01*
G01X3015820Y-666644D02*
Y-679144D01*
G01X3012255Y-666644D02*
X3019385D01*
G01X3028220Y-679144D02*
X3026980Y-678936D01*
X3025895Y-678103D01*
X3024965Y-676852D01*
X3024345Y-675394D01*
X3024035Y-673727D01*
Y-672061D01*
X3024345Y-670394D01*
X3024965Y-668936D01*
X3025895Y-667686D01*
X3026980Y-666852D01*
X3028220Y-666644D01*
X3029460Y-666852D01*
X3030545Y-667686D01*
X3031475Y-668936D01*
X3032095Y-670394D01*
X3032405Y-672061D01*
Y-673727D01*
X3032095Y-675394D01*
X3031475Y-676852D01*
X3030545Y-678103D01*
X3029460Y-678936D01*
X3028220Y-679144D01*
G01X3040620Y-666644D02*
Y-679144D01*
G01X3037055Y-666644D02*
X3044185D01*
G01X3049145Y-679144D02*
X3053020Y-666644D01*
X3056895Y-679144D01*
G01X3055500Y-674769D02*
X3050540D01*
G01X3062320Y-666644D02*
Y-679144D01*
X3068520D01*
G01X3086965D02*
Y-666644D01*
G01X3093475D02*
Y-679144D01*
G01Y-672894D02*
X3086965D01*
G01X3102620Y-679144D02*
X3101380Y-678936D01*
X3100295Y-678103D01*
X3099365Y-676852D01*
X3098745Y-675394D01*
X3098435Y-673727D01*
Y-672061D01*
X3098745Y-670394D01*
X3099365Y-668936D01*
X3100295Y-667686D01*
X3101380Y-666852D01*
X3102620Y-666644D01*
X3103860Y-666852D01*
X3104945Y-667686D01*
X3105875Y-668936D01*
X3106495Y-670394D01*
X3106805Y-672061D01*
Y-673727D01*
X3106495Y-675394D01*
X3105875Y-676852D01*
X3104945Y-678103D01*
X3103860Y-678936D01*
X3102620Y-679144D01*
G01X3111920Y-666644D02*
Y-679144D01*
X3118120D01*
G01X3130520D02*
X3124320D01*
Y-666644D01*
X3130520D01*
G01X3128040Y-672686D02*
X3124320D01*
G01X3136565Y-677478D02*
X3137805Y-678519D01*
X3139200Y-679144D01*
X3140440D01*
X3141680Y-678519D01*
X3142610Y-677478D01*
X3143075Y-676019D01*
X3142765Y-674561D01*
X3141990Y-673311D01*
X3140595Y-672477D01*
X3138735Y-672061D01*
X3137650Y-671227D01*
X3137185Y-669769D01*
X3137495Y-668311D01*
X3138270Y-667269D01*
X3139355Y-666644D01*
X3140440D01*
X3141525Y-667061D01*
X3142455Y-668102D01*
G01X3152220Y-679561D02*
X3151910Y-679352D01*
Y-678936D01*
X3152220Y-678727D01*
X3152530Y-678936D01*
Y-679352D01*
X3152220Y-679561D01*
G01Y-673936D02*
X3151910Y-673727D01*
Y-673311D01*
X3152220Y-673102D01*
X3152530Y-673311D01*
Y-673727D01*
X3152220Y-673936D01*
G01X3046455Y-620044D02*
Y-607544D01*
X3053585Y-620044D01*
Y-607544D01*
G01X3062420Y-620044D02*
X3061180Y-619836D01*
X3060095Y-619003D01*
X3059165Y-617752D01*
X3058545Y-616294D01*
X3058235Y-614627D01*
Y-612961D01*
X3058545Y-611294D01*
X3059165Y-609836D01*
X3060095Y-608586D01*
X3061180Y-607752D01*
X3062420Y-607544D01*
X3063660Y-607752D01*
X3064745Y-608586D01*
X3065675Y-609836D01*
X3066295Y-611294D01*
X3066605Y-612961D01*
Y-614627D01*
X3066295Y-616294D01*
X3065675Y-617752D01*
X3064745Y-619003D01*
X3063660Y-619836D01*
X3062420Y-620044D01*
G01X3071255D02*
Y-607544D01*
X3078385Y-620044D01*
Y-607544D01*
G01X3085205Y-615877D02*
X3089235D01*
G01X3096520Y-620044D02*
Y-607544D01*
X3100240D01*
X3101480Y-608169D01*
X3102410Y-609627D01*
X3102720Y-611294D01*
X3102410Y-612961D01*
X3101635Y-614211D01*
X3100240Y-614836D01*
X3096520D01*
G01X3108920Y-607544D02*
Y-620044D01*
X3115120D01*
G01X3120545D02*
X3124420Y-607544D01*
X3128295Y-620044D01*
G01X3126900Y-615669D02*
X3121940D01*
G01X3136820Y-607544D02*
Y-620044D01*
G01X3133255Y-607544D02*
X3140385D01*
G01X3152320Y-620044D02*
X3146120D01*
Y-607544D01*
X3152320D01*
G01X3149840Y-613586D02*
X3146120D01*
G01X3158210Y-620044D02*
Y-607544D01*
X3161310D01*
X3162550Y-608169D01*
X3163480Y-609002D01*
X3164255Y-610252D01*
X3164875Y-611711D01*
X3165030Y-613794D01*
X3164875Y-615877D01*
X3164255Y-617336D01*
X3163480Y-618586D01*
X3162550Y-619419D01*
X3161310Y-620044D01*
X3158210D01*
G01X3046455Y-560944D02*
Y-548444D01*
X3053585Y-560944D01*
Y-548444D01*
G01X3062420Y-560944D02*
X3061180Y-560736D01*
X3060095Y-559903D01*
X3059165Y-558652D01*
X3058545Y-557194D01*
X3058235Y-555527D01*
Y-553861D01*
X3058545Y-552194D01*
X3059165Y-550736D01*
X3060095Y-549486D01*
X3061180Y-548652D01*
X3062420Y-548444D01*
X3063660Y-548652D01*
X3064745Y-549486D01*
X3065675Y-550736D01*
X3066295Y-552194D01*
X3066605Y-553861D01*
Y-555527D01*
X3066295Y-557194D01*
X3065675Y-558652D01*
X3064745Y-559903D01*
X3063660Y-560736D01*
X3062420Y-560944D01*
G01X3071255D02*
Y-548444D01*
X3078385Y-560944D01*
Y-548444D01*
G01X3085205Y-556777D02*
X3089235D01*
G01X3096520Y-560944D02*
Y-548444D01*
X3100240D01*
X3101480Y-549069D01*
X3102410Y-550527D01*
X3102720Y-552194D01*
X3102410Y-553861D01*
X3101635Y-555111D01*
X3100240Y-555736D01*
X3096520D01*
G01X3108920Y-548444D02*
Y-560944D01*
X3115120D01*
G01X3120545D02*
X3124420Y-548444D01*
X3128295Y-560944D01*
G01X3126900Y-556569D02*
X3121940D01*
G01X3136820Y-548444D02*
Y-560944D01*
G01X3133255Y-548444D02*
X3140385D01*
G01X3152320Y-560944D02*
X3146120D01*
Y-548444D01*
X3152320D01*
G01X3149840Y-554486D02*
X3146120D01*
G01X3158210Y-560944D02*
Y-548444D01*
X3161310D01*
X3162550Y-549069D01*
X3163480Y-549902D01*
X3164255Y-551152D01*
X3164875Y-552611D01*
X3165030Y-554694D01*
X3164875Y-556777D01*
X3164255Y-558236D01*
X3163480Y-559486D01*
X3162550Y-560319D01*
X3161310Y-560944D01*
X3158210D01*
G01X3046455Y-383644D02*
Y-371144D01*
X3053585Y-383644D01*
Y-371144D01*
G01X3062420Y-383644D02*
X3061180Y-383436D01*
X3060095Y-382603D01*
X3059165Y-381352D01*
X3058545Y-379894D01*
X3058235Y-378227D01*
Y-376561D01*
X3058545Y-374894D01*
X3059165Y-373436D01*
X3060095Y-372186D01*
X3061180Y-371352D01*
X3062420Y-371144D01*
X3063660Y-371352D01*
X3064745Y-372186D01*
X3065675Y-373436D01*
X3066295Y-374894D01*
X3066605Y-376561D01*
Y-378227D01*
X3066295Y-379894D01*
X3065675Y-381352D01*
X3064745Y-382603D01*
X3063660Y-383436D01*
X3062420Y-383644D01*
G01X3071255D02*
Y-371144D01*
X3078385Y-383644D01*
Y-371144D01*
G01X3085205Y-379477D02*
X3089235D01*
G01X3096520Y-383644D02*
Y-371144D01*
X3100240D01*
X3101480Y-371769D01*
X3102410Y-373227D01*
X3102720Y-374894D01*
X3102410Y-376561D01*
X3101635Y-377811D01*
X3100240Y-378436D01*
X3096520D01*
G01X3108920Y-371144D02*
Y-383644D01*
X3115120D01*
G01X3120545D02*
X3124420Y-371144D01*
X3128295Y-383644D01*
G01X3126900Y-379269D02*
X3121940D01*
G01X3136820Y-371144D02*
Y-383644D01*
G01X3133255Y-371144D02*
X3140385D01*
G01X3152320Y-383644D02*
X3146120D01*
Y-371144D01*
X3152320D01*
G01X3149840Y-377186D02*
X3146120D01*
G01X3158210Y-383644D02*
Y-371144D01*
X3161310D01*
X3162550Y-371769D01*
X3163480Y-372602D01*
X3164255Y-373852D01*
X3164875Y-375311D01*
X3165030Y-377394D01*
X3164875Y-379477D01*
X3164255Y-380936D01*
X3163480Y-382186D01*
X3162550Y-383019D01*
X3161310Y-383644D01*
X3158210D01*
G01X3046455Y-324544D02*
Y-312044D01*
X3053585Y-324544D01*
Y-312044D01*
G01X3062420Y-324544D02*
X3061180Y-324336D01*
X3060095Y-323503D01*
X3059165Y-322252D01*
X3058545Y-320794D01*
X3058235Y-319127D01*
Y-317461D01*
X3058545Y-315794D01*
X3059165Y-314336D01*
X3060095Y-313086D01*
X3061180Y-312252D01*
X3062420Y-312044D01*
X3063660Y-312252D01*
X3064745Y-313086D01*
X3065675Y-314336D01*
X3066295Y-315794D01*
X3066605Y-317461D01*
Y-319127D01*
X3066295Y-320794D01*
X3065675Y-322252D01*
X3064745Y-323503D01*
X3063660Y-324336D01*
X3062420Y-324544D01*
G01X3071255D02*
Y-312044D01*
X3078385Y-324544D01*
Y-312044D01*
G01X3085205Y-320377D02*
X3089235D01*
G01X3096520Y-324544D02*
Y-312044D01*
X3100240D01*
X3101480Y-312669D01*
X3102410Y-314127D01*
X3102720Y-315794D01*
X3102410Y-317461D01*
X3101635Y-318711D01*
X3100240Y-319336D01*
X3096520D01*
G01X3108920Y-312044D02*
Y-324544D01*
X3115120D01*
G01X3120545D02*
X3124420Y-312044D01*
X3128295Y-324544D01*
G01X3126900Y-320169D02*
X3121940D01*
G01X3136820Y-312044D02*
Y-324544D01*
G01X3133255Y-312044D02*
X3140385D01*
G01X3152320Y-324544D02*
X3146120D01*
Y-312044D01*
X3152320D01*
G01X3149840Y-318086D02*
X3146120D01*
G01X3158210Y-324544D02*
Y-312044D01*
X3161310D01*
X3162550Y-312669D01*
X3163480Y-313502D01*
X3164255Y-314752D01*
X3164875Y-316211D01*
X3165030Y-318294D01*
X3164875Y-320377D01*
X3164255Y-321836D01*
X3163480Y-323086D01*
X3162550Y-323919D01*
X3161310Y-324544D01*
X3158210D01*
G01X3046455Y-265444D02*
Y-252944D01*
X3053585Y-265444D01*
Y-252944D01*
G01X3062420Y-265444D02*
X3061180Y-265236D01*
X3060095Y-264403D01*
X3059165Y-263152D01*
X3058545Y-261694D01*
X3058235Y-260027D01*
Y-258361D01*
X3058545Y-256694D01*
X3059165Y-255236D01*
X3060095Y-253986D01*
X3061180Y-253152D01*
X3062420Y-252944D01*
X3063660Y-253152D01*
X3064745Y-253986D01*
X3065675Y-255236D01*
X3066295Y-256694D01*
X3066605Y-258361D01*
Y-260027D01*
X3066295Y-261694D01*
X3065675Y-263152D01*
X3064745Y-264403D01*
X3063660Y-265236D01*
X3062420Y-265444D01*
G01X3071255D02*
Y-252944D01*
X3078385Y-265444D01*
Y-252944D01*
G01X3085205Y-261277D02*
X3089235D01*
G01X3096520Y-265444D02*
Y-252944D01*
X3100240D01*
X3101480Y-253569D01*
X3102410Y-255027D01*
X3102720Y-256694D01*
X3102410Y-258361D01*
X3101635Y-259611D01*
X3100240Y-260236D01*
X3096520D01*
G01X3108920Y-252944D02*
Y-265444D01*
X3115120D01*
G01X3120545D02*
X3124420Y-252944D01*
X3128295Y-265444D01*
G01X3126900Y-261069D02*
X3121940D01*
G01X3136820Y-252944D02*
Y-265444D01*
G01X3133255Y-252944D02*
X3140385D01*
G01X3152320Y-265444D02*
X3146120D01*
Y-252944D01*
X3152320D01*
G01X3149840Y-258986D02*
X3146120D01*
G01X3158210Y-265444D02*
Y-252944D01*
X3161310D01*
X3162550Y-253569D01*
X3163480Y-254402D01*
X3164255Y-255652D01*
X3164875Y-257111D01*
X3165030Y-259194D01*
X3164875Y-261277D01*
X3164255Y-262736D01*
X3163480Y-263986D01*
X3162550Y-264819D01*
X3161310Y-265444D01*
X3158210D01*
G01X3046455Y-206344D02*
Y-193844D01*
X3053585Y-206344D01*
Y-193844D01*
G01X3062420Y-206344D02*
X3061180Y-206136D01*
X3060095Y-205303D01*
X3059165Y-204052D01*
X3058545Y-202594D01*
X3058235Y-200927D01*
Y-199261D01*
X3058545Y-197594D01*
X3059165Y-196136D01*
X3060095Y-194886D01*
X3061180Y-194052D01*
X3062420Y-193844D01*
X3063660Y-194052D01*
X3064745Y-194886D01*
X3065675Y-196136D01*
X3066295Y-197594D01*
X3066605Y-199261D01*
Y-200927D01*
X3066295Y-202594D01*
X3065675Y-204052D01*
X3064745Y-205303D01*
X3063660Y-206136D01*
X3062420Y-206344D01*
G01X3071255D02*
Y-193844D01*
X3078385Y-206344D01*
Y-193844D01*
G01X3085205Y-202177D02*
X3089235D01*
G01X3096520Y-206344D02*
Y-193844D01*
X3100240D01*
X3101480Y-194469D01*
X3102410Y-195927D01*
X3102720Y-197594D01*
X3102410Y-199261D01*
X3101635Y-200511D01*
X3100240Y-201136D01*
X3096520D01*
G01X3108920Y-193844D02*
Y-206344D01*
X3115120D01*
G01X3120545D02*
X3124420Y-193844D01*
X3128295Y-206344D01*
G01X3126900Y-201969D02*
X3121940D01*
G01X3136820Y-193844D02*
Y-206344D01*
G01X3133255Y-193844D02*
X3140385D01*
G01X3152320Y-206344D02*
X3146120D01*
Y-193844D01*
X3152320D01*
G01X3149840Y-199886D02*
X3146120D01*
G01X3158210Y-206344D02*
Y-193844D01*
X3161310D01*
X3162550Y-194469D01*
X3163480Y-195302D01*
X3164255Y-196552D01*
X3164875Y-198011D01*
X3165030Y-200094D01*
X3164875Y-202177D01*
X3164255Y-203636D01*
X3163480Y-204886D01*
X3162550Y-205719D01*
X3161310Y-206344D01*
X3158210D01*
G01X3046455Y-147244D02*
Y-134744D01*
X3053585Y-147244D01*
Y-134744D01*
G01X3062420Y-147244D02*
X3061180Y-147036D01*
X3060095Y-146203D01*
X3059165Y-144952D01*
X3058545Y-143494D01*
X3058235Y-141827D01*
Y-140161D01*
X3058545Y-138494D01*
X3059165Y-137036D01*
X3060095Y-135786D01*
X3061180Y-134952D01*
X3062420Y-134744D01*
X3063660Y-134952D01*
X3064745Y-135786D01*
X3065675Y-137036D01*
X3066295Y-138494D01*
X3066605Y-140161D01*
Y-141827D01*
X3066295Y-143494D01*
X3065675Y-144952D01*
X3064745Y-146203D01*
X3063660Y-147036D01*
X3062420Y-147244D01*
G01X3071255D02*
Y-134744D01*
X3078385Y-147244D01*
Y-134744D01*
G01X3085205Y-143077D02*
X3089235D01*
G01X3096520Y-147244D02*
Y-134744D01*
X3100240D01*
X3101480Y-135369D01*
X3102410Y-136827D01*
X3102720Y-138494D01*
X3102410Y-140161D01*
X3101635Y-141411D01*
X3100240Y-142036D01*
X3096520D01*
G01X3108920Y-134744D02*
Y-147244D01*
X3115120D01*
G01X3120545D02*
X3124420Y-134744D01*
X3128295Y-147244D01*
G01X3126900Y-142869D02*
X3121940D01*
G01X3136820Y-134744D02*
Y-147244D01*
G01X3133255Y-134744D02*
X3140385D01*
G01X3152320Y-147244D02*
X3146120D01*
Y-134744D01*
X3152320D01*
G01X3149840Y-140786D02*
X3146120D01*
G01X3158210Y-147244D02*
Y-134744D01*
X3161310D01*
X3162550Y-135369D01*
X3163480Y-136202D01*
X3164255Y-137452D01*
X3164875Y-138911D01*
X3165030Y-140994D01*
X3164875Y-143077D01*
X3164255Y-144536D01*
X3163480Y-145786D01*
X3162550Y-146619D01*
X3161310Y-147244D01*
X3158210D01*
G01X3046455Y-88144D02*
Y-75644D01*
X3053585Y-88144D01*
Y-75644D01*
G01X3062420Y-88144D02*
X3061180Y-87936D01*
X3060095Y-87103D01*
X3059165Y-85852D01*
X3058545Y-84394D01*
X3058235Y-82727D01*
Y-81061D01*
X3058545Y-79394D01*
X3059165Y-77936D01*
X3060095Y-76686D01*
X3061180Y-75852D01*
X3062420Y-75644D01*
X3063660Y-75852D01*
X3064745Y-76686D01*
X3065675Y-77936D01*
X3066295Y-79394D01*
X3066605Y-81061D01*
Y-82727D01*
X3066295Y-84394D01*
X3065675Y-85852D01*
X3064745Y-87103D01*
X3063660Y-87936D01*
X3062420Y-88144D01*
G01X3071255D02*
Y-75644D01*
X3078385Y-88144D01*
Y-75644D01*
G01X3085205Y-83977D02*
X3089235D01*
G01X3096520Y-88144D02*
Y-75644D01*
X3100240D01*
X3101480Y-76269D01*
X3102410Y-77727D01*
X3102720Y-79394D01*
X3102410Y-81061D01*
X3101635Y-82311D01*
X3100240Y-82936D01*
X3096520D01*
G01X3108920Y-75644D02*
Y-88144D01*
X3115120D01*
G01X3120545D02*
X3124420Y-75644D01*
X3128295Y-88144D01*
G01X3126900Y-83769D02*
X3121940D01*
G01X3136820Y-75644D02*
Y-88144D01*
G01X3133255Y-75644D02*
X3140385D01*
G01X3152320Y-88144D02*
X3146120D01*
Y-75644D01*
X3152320D01*
G01X3149840Y-81686D02*
X3146120D01*
G01X3158210Y-88144D02*
Y-75644D01*
X3161310D01*
X3162550Y-76269D01*
X3163480Y-77102D01*
X3164255Y-78352D01*
X3164875Y-79811D01*
X3165030Y-81894D01*
X3164875Y-83977D01*
X3164255Y-85436D01*
X3163480Y-86686D01*
X3162550Y-87519D01*
X3161310Y-88144D01*
X3158210D01*
G01X3046455Y-29044D02*
Y-16544D01*
X3053585Y-29044D01*
Y-16544D01*
G01X3062420Y-29044D02*
X3061180Y-28836D01*
X3060095Y-28003D01*
X3059165Y-26752D01*
X3058545Y-25294D01*
X3058235Y-23627D01*
Y-21961D01*
X3058545Y-20294D01*
X3059165Y-18836D01*
X3060095Y-17586D01*
X3061180Y-16752D01*
X3062420Y-16544D01*
X3063660Y-16752D01*
X3064745Y-17586D01*
X3065675Y-18836D01*
X3066295Y-20294D01*
X3066605Y-21961D01*
Y-23627D01*
X3066295Y-25294D01*
X3065675Y-26752D01*
X3064745Y-28003D01*
X3063660Y-28836D01*
X3062420Y-29044D01*
G01X3071255D02*
Y-16544D01*
X3078385Y-29044D01*
Y-16544D01*
G01X3085205Y-24877D02*
X3089235D01*
G01X3096520Y-29044D02*
Y-16544D01*
X3100240D01*
X3101480Y-17169D01*
X3102410Y-18627D01*
X3102720Y-20294D01*
X3102410Y-21961D01*
X3101635Y-23211D01*
X3100240Y-23836D01*
X3096520D01*
G01X3108920Y-16544D02*
Y-29044D01*
X3115120D01*
G01X3120545D02*
X3124420Y-16544D01*
X3128295Y-29044D01*
G01X3126900Y-24669D02*
X3121940D01*
G01X3136820Y-16544D02*
Y-29044D01*
G01X3133255Y-16544D02*
X3140385D01*
G01X3152320Y-29044D02*
X3146120D01*
Y-16544D01*
X3152320D01*
G01X3149840Y-22586D02*
X3146120D01*
G01X3158210Y-29044D02*
Y-16544D01*
X3161310D01*
X3162550Y-17169D01*
X3163480Y-18002D01*
X3164255Y-19252D01*
X3164875Y-20711D01*
X3165030Y-22794D01*
X3164875Y-24877D01*
X3164255Y-26336D01*
X3163480Y-27586D01*
X3162550Y-28419D01*
X3161310Y-29044D01*
X3158210D01*
G01X3046455Y30056D02*
Y42556D01*
X3053585Y30056D01*
Y42556D01*
G01X3062420Y30056D02*
X3061180Y30264D01*
X3060095Y31097D01*
X3059165Y32348D01*
X3058545Y33806D01*
X3058235Y35473D01*
Y37139D01*
X3058545Y38806D01*
X3059165Y40264D01*
X3060095Y41514D01*
X3061180Y42348D01*
X3062420Y42556D01*
X3063660Y42348D01*
X3064745Y41514D01*
X3065675Y40264D01*
X3066295Y38806D01*
X3066605Y37139D01*
Y35473D01*
X3066295Y33806D01*
X3065675Y32348D01*
X3064745Y31097D01*
X3063660Y30264D01*
X3062420Y30056D01*
G01X3071255D02*
Y42556D01*
X3078385Y30056D01*
Y42556D01*
G01X3085205Y34223D02*
X3089235D01*
G01X3096520Y30056D02*
Y42556D01*
X3100240D01*
X3101480Y41931D01*
X3102410Y40473D01*
X3102720Y38806D01*
X3102410Y37139D01*
X3101635Y35889D01*
X3100240Y35264D01*
X3096520D01*
G01X3108920Y42556D02*
Y30056D01*
X3115120D01*
G01X3120545D02*
X3124420Y42556D01*
X3128295Y30056D01*
G01X3126900Y34431D02*
X3121940D01*
G01X3136820Y42556D02*
Y30056D01*
G01X3133255Y42556D02*
X3140385D01*
G01X3152320Y30056D02*
X3146120D01*
Y42556D01*
X3152320D01*
G01X3149840Y36514D02*
X3146120D01*
G01X3158210Y30056D02*
Y42556D01*
X3161310D01*
X3162550Y41931D01*
X3163480Y41098D01*
X3164255Y39848D01*
X3164875Y38389D01*
X3165030Y36306D01*
X3164875Y34223D01*
X3164255Y32764D01*
X3163480Y31514D01*
X3162550Y30681D01*
X3161310Y30056D01*
X3158210D01*
G01X3046455Y89156D02*
Y101656D01*
X3053585Y89156D01*
Y101656D01*
G01X3062420Y89156D02*
X3061180Y89364D01*
X3060095Y90197D01*
X3059165Y91448D01*
X3058545Y92906D01*
X3058235Y94573D01*
Y96239D01*
X3058545Y97906D01*
X3059165Y99364D01*
X3060095Y100614D01*
X3061180Y101448D01*
X3062420Y101656D01*
X3063660Y101448D01*
X3064745Y100614D01*
X3065675Y99364D01*
X3066295Y97906D01*
X3066605Y96239D01*
Y94573D01*
X3066295Y92906D01*
X3065675Y91448D01*
X3064745Y90197D01*
X3063660Y89364D01*
X3062420Y89156D01*
G01X3071255D02*
Y101656D01*
X3078385Y89156D01*
Y101656D01*
G01X3085205Y93323D02*
X3089235D01*
G01X3096520Y89156D02*
Y101656D01*
X3100240D01*
X3101480Y101031D01*
X3102410Y99573D01*
X3102720Y97906D01*
X3102410Y96239D01*
X3101635Y94989D01*
X3100240Y94364D01*
X3096520D01*
G01X3108920Y101656D02*
Y89156D01*
X3115120D01*
G01X3120545D02*
X3124420Y101656D01*
X3128295Y89156D01*
G01X3126900Y93531D02*
X3121940D01*
G01X3136820Y101656D02*
Y89156D01*
G01X3133255Y101656D02*
X3140385D01*
G01X3152320Y89156D02*
X3146120D01*
Y101656D01*
X3152320D01*
G01X3149840Y95614D02*
X3146120D01*
G01X3158210Y89156D02*
Y101656D01*
X3161310D01*
X3162550Y101031D01*
X3163480Y100198D01*
X3164255Y98948D01*
X3164875Y97489D01*
X3165030Y95406D01*
X3164875Y93323D01*
X3164255Y91864D01*
X3163480Y90614D01*
X3162550Y89781D01*
X3161310Y89156D01*
X3158210D01*
G01X3046455Y148256D02*
Y160756D01*
X3053585Y148256D01*
Y160756D01*
G01X3062420Y148256D02*
X3061180Y148464D01*
X3060095Y149297D01*
X3059165Y150548D01*
X3058545Y152006D01*
X3058235Y153673D01*
Y155339D01*
X3058545Y157006D01*
X3059165Y158464D01*
X3060095Y159714D01*
X3061180Y160548D01*
X3062420Y160756D01*
X3063660Y160548D01*
X3064745Y159714D01*
X3065675Y158464D01*
X3066295Y157006D01*
X3066605Y155339D01*
Y153673D01*
X3066295Y152006D01*
X3065675Y150548D01*
X3064745Y149297D01*
X3063660Y148464D01*
X3062420Y148256D01*
G01X3071255D02*
Y160756D01*
X3078385Y148256D01*
Y160756D01*
G01X3085205Y152423D02*
X3089235D01*
G01X3096520Y148256D02*
Y160756D01*
X3100240D01*
X3101480Y160131D01*
X3102410Y158673D01*
X3102720Y157006D01*
X3102410Y155339D01*
X3101635Y154089D01*
X3100240Y153464D01*
X3096520D01*
G01X3108920Y160756D02*
Y148256D01*
X3115120D01*
G01X3120545D02*
X3124420Y160756D01*
X3128295Y148256D01*
G01X3126900Y152631D02*
X3121940D01*
G01X3136820Y160756D02*
Y148256D01*
G01X3133255Y160756D02*
X3140385D01*
G01X3152320Y148256D02*
X3146120D01*
Y160756D01*
X3152320D01*
G01X3149840Y154714D02*
X3146120D01*
G01X3158210Y148256D02*
Y160756D01*
X3161310D01*
X3162550Y160131D01*
X3163480Y159298D01*
X3164255Y158048D01*
X3164875Y156589D01*
X3165030Y154506D01*
X3164875Y152423D01*
X3164255Y150964D01*
X3163480Y149714D01*
X3162550Y148881D01*
X3161310Y148256D01*
X3158210D01*
G01X3046455Y207356D02*
Y219856D01*
X3053585Y207356D01*
Y219856D01*
G01X3062420Y207356D02*
X3061180Y207564D01*
X3060095Y208397D01*
X3059165Y209648D01*
X3058545Y211106D01*
X3058235Y212773D01*
Y214439D01*
X3058545Y216106D01*
X3059165Y217564D01*
X3060095Y218814D01*
X3061180Y219648D01*
X3062420Y219856D01*
X3063660Y219648D01*
X3064745Y218814D01*
X3065675Y217564D01*
X3066295Y216106D01*
X3066605Y214439D01*
Y212773D01*
X3066295Y211106D01*
X3065675Y209648D01*
X3064745Y208397D01*
X3063660Y207564D01*
X3062420Y207356D01*
G01X3071255D02*
Y219856D01*
X3078385Y207356D01*
Y219856D01*
G01X3085205Y211523D02*
X3089235D01*
G01X3096520Y207356D02*
Y219856D01*
X3100240D01*
X3101480Y219231D01*
X3102410Y217773D01*
X3102720Y216106D01*
X3102410Y214439D01*
X3101635Y213189D01*
X3100240Y212564D01*
X3096520D01*
G01X3108920Y219856D02*
Y207356D01*
X3115120D01*
G01X3120545D02*
X3124420Y219856D01*
X3128295Y207356D01*
G01X3126900Y211731D02*
X3121940D01*
G01X3136820Y219856D02*
Y207356D01*
G01X3133255Y219856D02*
X3140385D01*
G01X3152320Y207356D02*
X3146120D01*
Y219856D01*
X3152320D01*
G01X3149840Y213814D02*
X3146120D01*
G01X3158210Y207356D02*
Y219856D01*
X3161310D01*
X3162550Y219231D01*
X3163480Y218398D01*
X3164255Y217148D01*
X3164875Y215689D01*
X3165030Y213606D01*
X3164875Y211523D01*
X3164255Y210064D01*
X3163480Y208814D01*
X3162550Y207981D01*
X3161310Y207356D01*
X3158210D01*
G01X3046455Y266456D02*
Y278956D01*
X3053585Y266456D01*
Y278956D01*
G01X3062420Y266456D02*
X3061180Y266664D01*
X3060095Y267497D01*
X3059165Y268748D01*
X3058545Y270206D01*
X3058235Y271873D01*
Y273539D01*
X3058545Y275206D01*
X3059165Y276664D01*
X3060095Y277914D01*
X3061180Y278748D01*
X3062420Y278956D01*
X3063660Y278748D01*
X3064745Y277914D01*
X3065675Y276664D01*
X3066295Y275206D01*
X3066605Y273539D01*
Y271873D01*
X3066295Y270206D01*
X3065675Y268748D01*
X3064745Y267497D01*
X3063660Y266664D01*
X3062420Y266456D01*
G01X3071255D02*
Y278956D01*
X3078385Y266456D01*
Y278956D01*
G01X3085205Y270623D02*
X3089235D01*
G01X3096520Y266456D02*
Y278956D01*
X3100240D01*
X3101480Y278331D01*
X3102410Y276873D01*
X3102720Y275206D01*
X3102410Y273539D01*
X3101635Y272289D01*
X3100240Y271664D01*
X3096520D01*
G01X3108920Y278956D02*
Y266456D01*
X3115120D01*
G01X3120545D02*
X3124420Y278956D01*
X3128295Y266456D01*
G01X3126900Y270831D02*
X3121940D01*
G01X3136820Y278956D02*
Y266456D01*
G01X3133255Y278956D02*
X3140385D01*
G01X3152320Y266456D02*
X3146120D01*
Y278956D01*
X3152320D01*
G01X3149840Y272914D02*
X3146120D01*
G01X3158210Y266456D02*
Y278956D01*
X3161310D01*
X3162550Y278331D01*
X3163480Y277498D01*
X3164255Y276248D01*
X3164875Y274789D01*
X3165030Y272706D01*
X3164875Y270623D01*
X3164255Y269164D01*
X3163480Y267914D01*
X3162550Y267081D01*
X3161310Y266456D01*
X3158210D01*
G01X3046455Y325556D02*
Y338056D01*
X3053585Y325556D01*
Y338056D01*
G01X3062420Y325556D02*
X3061180Y325764D01*
X3060095Y326597D01*
X3059165Y327848D01*
X3058545Y329306D01*
X3058235Y330973D01*
Y332639D01*
X3058545Y334306D01*
X3059165Y335764D01*
X3060095Y337014D01*
X3061180Y337848D01*
X3062420Y338056D01*
X3063660Y337848D01*
X3064745Y337014D01*
X3065675Y335764D01*
X3066295Y334306D01*
X3066605Y332639D01*
Y330973D01*
X3066295Y329306D01*
X3065675Y327848D01*
X3064745Y326597D01*
X3063660Y325764D01*
X3062420Y325556D01*
G01X3071255D02*
Y338056D01*
X3078385Y325556D01*
Y338056D01*
G01X3085205Y329723D02*
X3089235D01*
G01X3096520Y325556D02*
Y338056D01*
X3100240D01*
X3101480Y337431D01*
X3102410Y335973D01*
X3102720Y334306D01*
X3102410Y332639D01*
X3101635Y331389D01*
X3100240Y330764D01*
X3096520D01*
G01X3108920Y338056D02*
Y325556D01*
X3115120D01*
G01X3120545D02*
X3124420Y338056D01*
X3128295Y325556D01*
G01X3126900Y329931D02*
X3121940D01*
G01X3136820Y338056D02*
Y325556D01*
G01X3133255Y338056D02*
X3140385D01*
G01X3152320Y325556D02*
X3146120D01*
Y338056D01*
X3152320D01*
G01X3149840Y332014D02*
X3146120D01*
G01X3158210Y325556D02*
Y338056D01*
X3161310D01*
X3162550Y337431D01*
X3163480Y336598D01*
X3164255Y335348D01*
X3164875Y333889D01*
X3165030Y331806D01*
X3164875Y329723D01*
X3164255Y328264D01*
X3163480Y327014D01*
X3162550Y326181D01*
X3161310Y325556D01*
X3158210D01*
G01X3071720Y-501844D02*
Y-489344D01*
X3075440D01*
X3076680Y-489969D01*
X3077610Y-491427D01*
X3077920Y-493094D01*
X3077610Y-494761D01*
X3076835Y-496011D01*
X3075440Y-496636D01*
X3071720D01*
G01X3084120Y-489344D02*
Y-501844D01*
X3090320D01*
G01X3095745D02*
X3099620Y-489344D01*
X3103495Y-501844D01*
G01X3102100Y-497469D02*
X3097140D01*
G01X3112020Y-489344D02*
Y-501844D01*
G01X3108455Y-489344D02*
X3115585D01*
G01X3127520Y-501844D02*
X3121320D01*
Y-489344D01*
X3127520D01*
G01X3125040Y-495386D02*
X3121320D01*
G01X3133410Y-501844D02*
Y-489344D01*
X3136510D01*
X3137750Y-489969D01*
X3138680Y-490802D01*
X3139455Y-492052D01*
X3140075Y-493511D01*
X3140230Y-495594D01*
X3140075Y-497677D01*
X3139455Y-499136D01*
X3138680Y-500386D01*
X3137750Y-501219D01*
X3136510Y-501844D01*
X3133410D01*
G01X3071720Y-442744D02*
Y-430244D01*
X3075440D01*
X3076680Y-430869D01*
X3077610Y-432327D01*
X3077920Y-433994D01*
X3077610Y-435661D01*
X3076835Y-436911D01*
X3075440Y-437536D01*
X3071720D01*
G01X3084120Y-430244D02*
Y-442744D01*
X3090320D01*
G01X3095745D02*
X3099620Y-430244D01*
X3103495Y-442744D01*
G01X3102100Y-438369D02*
X3097140D01*
G01X3112020Y-430244D02*
Y-442744D01*
G01X3108455Y-430244D02*
X3115585D01*
G01X3127520Y-442744D02*
X3121320D01*
Y-430244D01*
X3127520D01*
G01X3125040Y-436286D02*
X3121320D01*
G01X3133410Y-442744D02*
Y-430244D01*
X3136510D01*
X3137750Y-430869D01*
X3138680Y-431702D01*
X3139455Y-432952D01*
X3140075Y-434411D01*
X3140230Y-436494D01*
X3140075Y-438577D01*
X3139455Y-440036D01*
X3138680Y-441286D01*
X3137750Y-442119D01*
X3136510Y-442744D01*
X3133410D01*
G01X3071720Y384656D02*
Y397156D01*
X3075440D01*
X3076680Y396531D01*
X3077610Y395073D01*
X3077920Y393406D01*
X3077610Y391739D01*
X3076835Y390489D01*
X3075440Y389864D01*
X3071720D01*
G01X3084120Y397156D02*
Y384656D01*
X3090320D01*
G01X3095745D02*
X3099620Y397156D01*
X3103495Y384656D01*
G01X3102100Y389031D02*
X3097140D01*
G01X3112020Y397156D02*
Y384656D01*
G01X3108455Y397156D02*
X3115585D01*
G01X3127520Y384656D02*
X3121320D01*
Y397156D01*
X3127520D01*
G01X3125040Y391114D02*
X3121320D01*
G01X3133410Y384656D02*
Y397156D01*
X3136510D01*
X3137750Y396531D01*
X3138680Y395698D01*
X3139455Y394448D01*
X3140075Y392989D01*
X3140230Y390906D01*
X3140075Y388823D01*
X3139455Y387364D01*
X3138680Y386114D01*
X3137750Y385281D01*
X3136510Y384656D01*
X3133410D01*
G01X3071720Y443756D02*
Y456256D01*
X3075440D01*
X3076680Y455631D01*
X3077610Y454173D01*
X3077920Y452506D01*
X3077610Y450839D01*
X3076835Y449589D01*
X3075440Y448964D01*
X3071720D01*
G01X3084120Y456256D02*
Y443756D01*
X3090320D01*
G01X3095745D02*
X3099620Y456256D01*
X3103495Y443756D01*
G01X3102100Y448131D02*
X3097140D01*
G01X3112020Y456256D02*
Y443756D01*
G01X3108455Y456256D02*
X3115585D01*
G01X3127520Y443756D02*
X3121320D01*
Y456256D01*
X3127520D01*
G01X3125040Y450214D02*
X3121320D01*
G01X3133410Y443756D02*
Y456256D01*
X3136510D01*
X3137750Y455631D01*
X3138680Y454798D01*
X3139455Y453548D01*
X3140075Y452089D01*
X3140230Y450006D01*
X3140075Y447923D01*
X3139455Y446464D01*
X3138680Y445214D01*
X3137750Y444381D01*
X3136510Y443756D01*
X3133410D01*
G01X3071720Y502856D02*
Y515356D01*
X3075440D01*
X3076680Y514731D01*
X3077610Y513273D01*
X3077920Y511606D01*
X3077610Y509939D01*
X3076835Y508689D01*
X3075440Y508064D01*
X3071720D01*
G01X3084120Y515356D02*
Y502856D01*
X3090320D01*
G01X3095745D02*
X3099620Y515356D01*
X3103495Y502856D01*
G01X3102100Y507231D02*
X3097140D01*
G01X3112020Y515356D02*
Y502856D01*
G01X3108455Y515356D02*
X3115585D01*
G01X3127520Y502856D02*
X3121320D01*
Y515356D01*
X3127520D01*
G01X3125040Y509314D02*
X3121320D01*
G01X3133410Y502856D02*
Y515356D01*
X3136510D01*
X3137750Y514731D01*
X3138680Y513898D01*
X3139455Y512648D01*
X3140075Y511189D01*
X3140230Y509106D01*
X3140075Y507023D01*
X3139455Y505564D01*
X3138680Y504314D01*
X3137750Y503481D01*
X3136510Y502856D01*
X3133410D01*
G01X3071720Y561956D02*
Y574456D01*
X3075440D01*
X3076680Y573831D01*
X3077610Y572373D01*
X3077920Y570706D01*
X3077610Y569039D01*
X3076835Y567789D01*
X3075440Y567164D01*
X3071720D01*
G01X3084120Y574456D02*
Y561956D01*
X3090320D01*
G01X3095745D02*
X3099620Y574456D01*
X3103495Y561956D01*
G01X3102100Y566331D02*
X3097140D01*
G01X3112020Y574456D02*
Y561956D01*
G01X3108455Y574456D02*
X3115585D01*
G01X3127520Y561956D02*
X3121320D01*
Y574456D01*
X3127520D01*
G01X3125040Y568414D02*
X3121320D01*
G01X3133410Y561956D02*
Y574456D01*
X3136510D01*
X3137750Y573831D01*
X3138680Y572998D01*
X3139455Y571748D01*
X3140075Y570289D01*
X3140230Y568206D01*
X3140075Y566123D01*
X3139455Y564664D01*
X3138680Y563414D01*
X3137750Y562581D01*
X3136510Y561956D01*
X3133410D01*
G01X3071720Y621056D02*
Y633556D01*
X3075440D01*
X3076680Y632931D01*
X3077610Y631473D01*
X3077920Y629806D01*
X3077610Y628139D01*
X3076835Y626889D01*
X3075440Y626264D01*
X3071720D01*
G01X3084120Y633556D02*
Y621056D01*
X3090320D01*
G01X3095745D02*
X3099620Y633556D01*
X3103495Y621056D01*
G01X3102100Y625431D02*
X3097140D01*
G01X3112020Y633556D02*
Y621056D01*
G01X3108455Y633556D02*
X3115585D01*
G01X3127520Y621056D02*
X3121320D01*
Y633556D01*
X3127520D01*
G01X3125040Y627514D02*
X3121320D01*
G01X3133410Y621056D02*
Y633556D01*
X3136510D01*
X3137750Y632931D01*
X3138680Y632098D01*
X3139455Y630848D01*
X3140075Y629389D01*
X3140230Y627306D01*
X3140075Y625223D01*
X3139455Y623764D01*
X3138680Y622514D01*
X3137750Y621681D01*
X3136510Y621056D01*
X3133410D01*
G01X3071720Y680156D02*
Y692656D01*
X3075440D01*
X3076680Y692031D01*
X3077610Y690573D01*
X3077920Y688906D01*
X3077610Y687239D01*
X3076835Y685989D01*
X3075440Y685364D01*
X3071720D01*
G01X3084120Y692656D02*
Y680156D01*
X3090320D01*
G01X3095745D02*
X3099620Y692656D01*
X3103495Y680156D01*
G01X3102100Y684531D02*
X3097140D01*
G01X3112020Y692656D02*
Y680156D01*
G01X3108455Y692656D02*
X3115585D01*
G01X3127520Y680156D02*
X3121320D01*
Y692656D01*
X3127520D01*
G01X3125040Y686614D02*
X3121320D01*
G01X3133410Y680156D02*
Y692656D01*
X3136510D01*
X3137750Y692031D01*
X3138680Y691198D01*
X3139455Y689948D01*
X3140075Y688489D01*
X3140230Y686406D01*
X3140075Y684323D01*
X3139455Y682864D01*
X3138680Y681614D01*
X3137750Y680781D01*
X3136510Y680156D01*
X3133410D01*
G01X3071720Y739256D02*
Y751756D01*
X3075440D01*
X3076680Y751131D01*
X3077610Y749673D01*
X3077920Y748006D01*
X3077610Y746339D01*
X3076835Y745089D01*
X3075440Y744464D01*
X3071720D01*
G01X3084120Y751756D02*
Y739256D01*
X3090320D01*
G01X3095745D02*
X3099620Y751756D01*
X3103495Y739256D01*
G01X3102100Y743631D02*
X3097140D01*
G01X3112020Y751756D02*
Y739256D01*
G01X3108455Y751756D02*
X3115585D01*
G01X3127520Y739256D02*
X3121320D01*
Y751756D01*
X3127520D01*
G01X3125040Y745714D02*
X3121320D01*
G01X3133410Y739256D02*
Y751756D01*
X3136510D01*
X3137750Y751131D01*
X3138680Y750298D01*
X3139455Y749048D01*
X3140075Y747589D01*
X3140230Y745506D01*
X3140075Y743423D01*
X3139455Y741964D01*
X3138680Y740714D01*
X3137750Y739881D01*
X3136510Y739256D01*
X3133410D01*
G01X3071720Y798356D02*
Y810856D01*
X3075440D01*
X3076680Y810231D01*
X3077610Y808773D01*
X3077920Y807106D01*
X3077610Y805439D01*
X3076835Y804189D01*
X3075440Y803564D01*
X3071720D01*
G01X3084120Y810856D02*
Y798356D01*
X3090320D01*
G01X3095745D02*
X3099620Y810856D01*
X3103495Y798356D01*
G01X3102100Y802731D02*
X3097140D01*
G01X3112020Y810856D02*
Y798356D01*
G01X3108455Y810856D02*
X3115585D01*
G01X3127520Y798356D02*
X3121320D01*
Y810856D01*
X3127520D01*
G01X3125040Y804814D02*
X3121320D01*
G01X3133410Y798356D02*
Y810856D01*
X3136510D01*
X3137750Y810231D01*
X3138680Y809398D01*
X3139455Y808148D01*
X3140075Y806689D01*
X3140230Y804606D01*
X3140075Y802523D01*
X3139455Y801064D01*
X3138680Y799814D01*
X3137750Y798981D01*
X3136510Y798356D01*
X3133410D01*
G01X3071720Y857456D02*
Y869956D01*
X3075440D01*
X3076680Y869331D01*
X3077610Y867873D01*
X3077920Y866206D01*
X3077610Y864539D01*
X3076835Y863289D01*
X3075440Y862664D01*
X3071720D01*
G01X3084120Y869956D02*
Y857456D01*
X3090320D01*
G01X3095745D02*
X3099620Y869956D01*
X3103495Y857456D01*
G01X3102100Y861831D02*
X3097140D01*
G01X3112020Y869956D02*
Y857456D01*
G01X3108455Y869956D02*
X3115585D01*
G01X3127520Y857456D02*
X3121320D01*
Y869956D01*
X3127520D01*
G01X3125040Y863914D02*
X3121320D01*
G01X3133410Y857456D02*
Y869956D01*
X3136510D01*
X3137750Y869331D01*
X3138680Y868498D01*
X3139455Y867248D01*
X3140075Y865789D01*
X3140230Y863706D01*
X3140075Y861623D01*
X3139455Y860164D01*
X3138680Y858914D01*
X3137750Y858081D01*
X3136510Y857456D01*
X3133410D01*
G01X3071720Y916556D02*
Y929056D01*
X3075440D01*
X3076680Y928431D01*
X3077610Y926973D01*
X3077920Y925306D01*
X3077610Y923639D01*
X3076835Y922389D01*
X3075440Y921764D01*
X3071720D01*
G01X3084120Y929056D02*
Y916556D01*
X3090320D01*
G01X3095745D02*
X3099620Y929056D01*
X3103495Y916556D01*
G01X3102100Y920931D02*
X3097140D01*
G01X3112020Y929056D02*
Y916556D01*
G01X3108455Y929056D02*
X3115585D01*
G01X3127520Y916556D02*
X3121320D01*
Y929056D01*
X3127520D01*
G01X3125040Y923014D02*
X3121320D01*
G01X3133410Y916556D02*
Y929056D01*
X3136510D01*
X3137750Y928431D01*
X3138680Y927598D01*
X3139455Y926348D01*
X3140075Y924889D01*
X3140230Y922806D01*
X3140075Y920723D01*
X3139455Y919264D01*
X3138680Y918014D01*
X3137750Y917181D01*
X3136510Y916556D01*
X3133410D01*
G01X3071720Y975656D02*
Y988156D01*
X3075440D01*
X3076680Y987531D01*
X3077610Y986073D01*
X3077920Y984406D01*
X3077610Y982739D01*
X3076835Y981489D01*
X3075440Y980864D01*
X3071720D01*
G01X3084120Y988156D02*
Y975656D01*
X3090320D01*
G01X3095745D02*
X3099620Y988156D01*
X3103495Y975656D01*
G01X3102100Y980031D02*
X3097140D01*
G01X3112020Y988156D02*
Y975656D01*
G01X3108455Y988156D02*
X3115585D01*
G01X3127520Y975656D02*
X3121320D01*
Y988156D01*
X3127520D01*
G01X3125040Y982114D02*
X3121320D01*
G01X3133410Y975656D02*
Y988156D01*
X3136510D01*
X3137750Y987531D01*
X3138680Y986698D01*
X3139455Y985448D01*
X3140075Y983989D01*
X3140230Y981906D01*
X3140075Y979823D01*
X3139455Y978364D01*
X3138680Y977114D01*
X3137750Y976281D01*
X3136510Y975656D01*
X3133410D01*
G01X3071720Y1034756D02*
Y1047256D01*
X3075440D01*
X3076680Y1046631D01*
X3077610Y1045173D01*
X3077920Y1043506D01*
X3077610Y1041839D01*
X3076835Y1040589D01*
X3075440Y1039964D01*
X3071720D01*
G01X3084120Y1047256D02*
Y1034756D01*
X3090320D01*
G01X3095745D02*
X3099620Y1047256D01*
X3103495Y1034756D01*
G01X3102100Y1039131D02*
X3097140D01*
G01X3112020Y1047256D02*
Y1034756D01*
G01X3108455Y1047256D02*
X3115585D01*
G01X3127520Y1034756D02*
X3121320D01*
Y1047256D01*
X3127520D01*
G01X3125040Y1041214D02*
X3121320D01*
G01X3133410Y1034756D02*
Y1047256D01*
X3136510D01*
X3137750Y1046631D01*
X3138680Y1045798D01*
X3139455Y1044548D01*
X3140075Y1043089D01*
X3140230Y1041006D01*
X3140075Y1038923D01*
X3139455Y1037464D01*
X3138680Y1036214D01*
X3137750Y1035381D01*
X3136510Y1034756D01*
X3133410D01*
G01X3071720Y1093856D02*
Y1106356D01*
X3075440D01*
X3076680Y1105731D01*
X3077610Y1104273D01*
X3077920Y1102606D01*
X3077610Y1100939D01*
X3076835Y1099689D01*
X3075440Y1099064D01*
X3071720D01*
G01X3084120Y1106356D02*
Y1093856D01*
X3090320D01*
G01X3095745D02*
X3099620Y1106356D01*
X3103495Y1093856D01*
G01X3102100Y1098231D02*
X3097140D01*
G01X3112020Y1106356D02*
Y1093856D01*
G01X3108455Y1106356D02*
X3115585D01*
G01X3127520Y1093856D02*
X3121320D01*
Y1106356D01*
X3127520D01*
G01X3125040Y1100314D02*
X3121320D01*
G01X3133410Y1093856D02*
Y1106356D01*
X3136510D01*
X3137750Y1105731D01*
X3138680Y1104898D01*
X3139455Y1103648D01*
X3140075Y1102189D01*
X3140230Y1100106D01*
X3140075Y1098023D01*
X3139455Y1096564D01*
X3138680Y1095314D01*
X3137750Y1094481D01*
X3136510Y1093856D01*
X3133410D01*
G01X3071720Y1152956D02*
Y1165456D01*
X3075440D01*
X3076680Y1164831D01*
X3077610Y1163373D01*
X3077920Y1161706D01*
X3077610Y1160039D01*
X3076835Y1158789D01*
X3075440Y1158164D01*
X3071720D01*
G01X3084120Y1165456D02*
Y1152956D01*
X3090320D01*
G01X3095745D02*
X3099620Y1165456D01*
X3103495Y1152956D01*
G01X3102100Y1157331D02*
X3097140D01*
G01X3112020Y1165456D02*
Y1152956D01*
G01X3108455Y1165456D02*
X3115585D01*
G01X3127520Y1152956D02*
X3121320D01*
Y1165456D01*
X3127520D01*
G01X3125040Y1159414D02*
X3121320D01*
G01X3133410Y1152956D02*
Y1165456D01*
X3136510D01*
X3137750Y1164831D01*
X3138680Y1163998D01*
X3139455Y1162748D01*
X3140075Y1161289D01*
X3140230Y1159206D01*
X3140075Y1157123D01*
X3139455Y1155664D01*
X3138680Y1154414D01*
X3137750Y1153581D01*
X3136510Y1152956D01*
X3133410D01*
G01X3071720Y1212056D02*
Y1224556D01*
X3075440D01*
X3076680Y1223931D01*
X3077610Y1222473D01*
X3077920Y1220806D01*
X3077610Y1219139D01*
X3076835Y1217889D01*
X3075440Y1217264D01*
X3071720D01*
G01X3084120Y1224556D02*
Y1212056D01*
X3090320D01*
G01X3095745D02*
X3099620Y1224556D01*
X3103495Y1212056D01*
G01X3102100Y1216431D02*
X3097140D01*
G01X3112020Y1224556D02*
Y1212056D01*
G01X3108455Y1224556D02*
X3115585D01*
G01X3127520Y1212056D02*
X3121320D01*
Y1224556D01*
X3127520D01*
G01X3125040Y1218514D02*
X3121320D01*
G01X3133410Y1212056D02*
Y1224556D01*
X3136510D01*
X3137750Y1223931D01*
X3138680Y1223098D01*
X3139455Y1221848D01*
X3140075Y1220389D01*
X3140230Y1218306D01*
X3140075Y1216223D01*
X3139455Y1214764D01*
X3138680Y1213514D01*
X3137750Y1212681D01*
X3136510Y1212056D01*
X3133410D01*
G01X3071720Y1271156D02*
Y1283656D01*
X3075440D01*
X3076680Y1283031D01*
X3077610Y1281573D01*
X3077920Y1279906D01*
X3077610Y1278239D01*
X3076835Y1276989D01*
X3075440Y1276364D01*
X3071720D01*
G01X3084120Y1283656D02*
Y1271156D01*
X3090320D01*
G01X3095745D02*
X3099620Y1283656D01*
X3103495Y1271156D01*
G01X3102100Y1275531D02*
X3097140D01*
G01X3112020Y1283656D02*
Y1271156D01*
G01X3108455Y1283656D02*
X3115585D01*
G01X3127520Y1271156D02*
X3121320D01*
Y1283656D01*
X3127520D01*
G01X3125040Y1277614D02*
X3121320D01*
G01X3133410Y1271156D02*
Y1283656D01*
X3136510D01*
X3137750Y1283031D01*
X3138680Y1282198D01*
X3139455Y1280948D01*
X3140075Y1279489D01*
X3140230Y1277406D01*
X3140075Y1275323D01*
X3139455Y1273864D01*
X3138680Y1272614D01*
X3137750Y1271781D01*
X3136510Y1271156D01*
X3133410D01*
G01X3071720Y1330256D02*
Y1342756D01*
X3075440D01*
X3076680Y1342131D01*
X3077610Y1340673D01*
X3077920Y1339006D01*
X3077610Y1337339D01*
X3076835Y1336089D01*
X3075440Y1335464D01*
X3071720D01*
G01X3084120Y1342756D02*
Y1330256D01*
X3090320D01*
G01X3095745D02*
X3099620Y1342756D01*
X3103495Y1330256D01*
G01X3102100Y1334631D02*
X3097140D01*
G01X3112020Y1342756D02*
Y1330256D01*
G01X3108455Y1342756D02*
X3115585D01*
G01X3127520Y1330256D02*
X3121320D01*
Y1342756D01*
X3127520D01*
G01X3125040Y1336714D02*
X3121320D01*
G01X3133410Y1330256D02*
Y1342756D01*
X3136510D01*
X3137750Y1342131D01*
X3138680Y1341298D01*
X3139455Y1340048D01*
X3140075Y1338589D01*
X3140230Y1336506D01*
X3140075Y1334423D01*
X3139455Y1332964D01*
X3138680Y1331714D01*
X3137750Y1330881D01*
X3136510Y1330256D01*
X3133410D01*
G01X3071720Y1389356D02*
Y1401856D01*
X3075440D01*
X3076680Y1401231D01*
X3077610Y1399773D01*
X3077920Y1398106D01*
X3077610Y1396439D01*
X3076835Y1395189D01*
X3075440Y1394564D01*
X3071720D01*
G01X3084120Y1401856D02*
Y1389356D01*
X3090320D01*
G01X3095745D02*
X3099620Y1401856D01*
X3103495Y1389356D01*
G01X3102100Y1393731D02*
X3097140D01*
G01X3112020Y1401856D02*
Y1389356D01*
G01X3108455Y1401856D02*
X3115585D01*
G01X3127520Y1389356D02*
X3121320D01*
Y1401856D01*
X3127520D01*
G01X3125040Y1395814D02*
X3121320D01*
G01X3133410Y1389356D02*
Y1401856D01*
X3136510D01*
X3137750Y1401231D01*
X3138680Y1400398D01*
X3139455Y1399148D01*
X3140075Y1397689D01*
X3140230Y1395606D01*
X3140075Y1393523D01*
X3139455Y1392064D01*
X3138680Y1390814D01*
X3137750Y1389981D01*
X3136510Y1389356D01*
X3133410D01*
G01X3071720Y1448456D02*
Y1460956D01*
X3075440D01*
X3076680Y1460331D01*
X3077610Y1458873D01*
X3077920Y1457206D01*
X3077610Y1455539D01*
X3076835Y1454289D01*
X3075440Y1453664D01*
X3071720D01*
G01X3084120Y1460956D02*
Y1448456D01*
X3090320D01*
G01X3095745D02*
X3099620Y1460956D01*
X3103495Y1448456D01*
G01X3102100Y1452831D02*
X3097140D01*
G01X3112020Y1460956D02*
Y1448456D01*
G01X3108455Y1460956D02*
X3115585D01*
G01X3127520Y1448456D02*
X3121320D01*
Y1460956D01*
X3127520D01*
G01X3125040Y1454914D02*
X3121320D01*
G01X3133410Y1448456D02*
Y1460956D01*
X3136510D01*
X3137750Y1460331D01*
X3138680Y1459498D01*
X3139455Y1458248D01*
X3140075Y1456789D01*
X3140230Y1454706D01*
X3140075Y1452623D01*
X3139455Y1451164D01*
X3138680Y1449914D01*
X3137750Y1449081D01*
X3136510Y1448456D01*
X3133410D01*
G01X3071720Y1507556D02*
Y1520056D01*
X3075440D01*
X3076680Y1519431D01*
X3077610Y1517973D01*
X3077920Y1516306D01*
X3077610Y1514639D01*
X3076835Y1513389D01*
X3075440Y1512764D01*
X3071720D01*
G01X3084120Y1520056D02*
Y1507556D01*
X3090320D01*
G01X3095745D02*
X3099620Y1520056D01*
X3103495Y1507556D01*
G01X3102100Y1511931D02*
X3097140D01*
G01X3112020Y1520056D02*
Y1507556D01*
G01X3108455Y1520056D02*
X3115585D01*
G01X3127520Y1507556D02*
X3121320D01*
Y1520056D01*
X3127520D01*
G01X3125040Y1514014D02*
X3121320D01*
G01X3133410Y1507556D02*
Y1520056D01*
X3136510D01*
X3137750Y1519431D01*
X3138680Y1518598D01*
X3139455Y1517348D01*
X3140075Y1515889D01*
X3140230Y1513806D01*
X3140075Y1511723D01*
X3139455Y1510264D01*
X3138680Y1509014D01*
X3137750Y1508181D01*
X3136510Y1507556D01*
X3133410D01*
G01X3071720Y1549606D02*
Y1562106D01*
X3075440D01*
X3076680Y1561481D01*
X3077610Y1560023D01*
X3077920Y1558356D01*
X3077610Y1556689D01*
X3076835Y1555439D01*
X3075440Y1554814D01*
X3071720D01*
G01X3084120Y1562106D02*
Y1549606D01*
X3090320D01*
G01X3095745D02*
X3099620Y1562106D01*
X3103495Y1549606D01*
G01X3102100Y1553981D02*
X3097140D01*
G01X3112020Y1562106D02*
Y1549606D01*
G01X3108455Y1562106D02*
X3115585D01*
G01X3127520Y1549606D02*
X3121320D01*
Y1562106D01*
X3127520D01*
G01X3125040Y1556064D02*
X3121320D01*
G01X3133410Y1549606D02*
Y1562106D01*
X3136510D01*
X3137750Y1561481D01*
X3138680Y1560648D01*
X3139455Y1559398D01*
X3140075Y1557939D01*
X3140230Y1555856D01*
X3140075Y1553773D01*
X3139455Y1552314D01*
X3138680Y1551064D01*
X3137750Y1550231D01*
X3136510Y1549606D01*
X3133410D01*
G01X3185180Y-679144D02*
Y-666644D01*
X3179445Y-675602D01*
X3187195D01*
G01X3197580Y-679144D02*
Y-666644D01*
X3191845Y-675602D01*
X3199595D01*
G01X3207810Y-679144D02*
X3208120Y-676436D01*
X3208585Y-674144D01*
X3209205Y-672061D01*
X3209980Y-669769D01*
X3211220Y-666644D01*
X3205020D01*
G01X3220520D02*
X3219280Y-667061D01*
X3218350Y-668102D01*
X3217730Y-669352D01*
X3217265Y-671019D01*
X3217110Y-672894D01*
X3217265Y-674769D01*
X3217730Y-676436D01*
X3218350Y-677686D01*
X3219280Y-678727D01*
X3220520Y-679144D01*
X3221760Y-678727D01*
X3222690Y-677686D01*
X3223310Y-676436D01*
X3223775Y-674769D01*
X3223930Y-672894D01*
X3223775Y-671019D01*
X3223310Y-669352D01*
X3222690Y-668102D01*
X3221760Y-667061D01*
X3220520Y-666644D01*
G01X3232920Y-679144D02*
Y-666644D01*
X3231060Y-669144D01*
G01Y-679144D02*
X3234780D01*
G01X3180375Y1340673D02*
X3181305Y1341922D01*
X3182390Y1342548D01*
X3183630Y1342756D01*
X3185180Y1342339D01*
X3186265Y1341298D01*
X3186575Y1340048D01*
X3186420Y1338797D01*
X3185800Y1337756D01*
X3182700Y1335673D01*
X3181305Y1334214D01*
X3180375Y1332131D01*
X3180065Y1330256D01*
X3186575D01*
G01X3192775Y1335464D02*
X3193860Y1336923D01*
X3194790Y1337756D01*
X3196030Y1338173D01*
X3197115Y1337756D01*
X3197890Y1336923D01*
X3198510Y1335673D01*
X3198665Y1334214D01*
X3198510Y1332964D01*
X3197890Y1331714D01*
X3196960Y1330673D01*
X3195875Y1330256D01*
X3194635Y1330673D01*
X3193550Y1331922D01*
X3192930Y1333798D01*
X3192775Y1335881D01*
X3193085Y1338589D01*
X3193550Y1340048D01*
X3194325Y1341506D01*
X3195410Y1342548D01*
X3196495Y1342756D01*
X3197580Y1342339D01*
X3198355Y1341298D01*
G01X3205175Y1335464D02*
X3206260Y1336923D01*
X3207190Y1337756D01*
X3208430Y1338173D01*
X3209515Y1337756D01*
X3210290Y1336923D01*
X3210910Y1335673D01*
X3211065Y1334214D01*
X3210910Y1332964D01*
X3210290Y1331714D01*
X3209360Y1330673D01*
X3208275Y1330256D01*
X3207035Y1330673D01*
X3205950Y1331922D01*
X3205330Y1333798D01*
X3205175Y1335881D01*
X3205485Y1338589D01*
X3205950Y1340048D01*
X3206725Y1341506D01*
X3207810Y1342548D01*
X3208895Y1342756D01*
X3209980Y1342339D01*
X3210755Y1341298D01*
G01X3220520Y1330256D02*
Y1342756D01*
X3218660Y1340256D01*
G01Y1330256D02*
X3222380D01*
G01X3232920D02*
Y1342756D01*
X3231060Y1340256D01*
G01Y1330256D02*
X3234780D01*
G01X3183320Y1507556D02*
Y1520056D01*
X3181460Y1517556D01*
G01Y1507556D02*
X3185180D01*
G01X3197580D02*
Y1520056D01*
X3191845Y1511098D01*
X3199595D01*
G01X3209980Y1507556D02*
Y1520056D01*
X3204245Y1511098D01*
X3211995D01*
G01X3217110Y1509431D02*
X3218040Y1508389D01*
X3219125Y1507764D01*
X3220520Y1507556D01*
X3221915Y1507973D01*
X3223000Y1508806D01*
X3223775Y1510264D01*
X3223930Y1511931D01*
X3223620Y1513598D01*
X3222845Y1514639D01*
X3221760Y1515473D01*
X3220675Y1515681D01*
X3219590Y1515473D01*
X3218195Y1514639D01*
X3218660Y1520056D01*
X3222845D01*
G01X3229975Y1512764D02*
X3231060Y1514223D01*
X3231990Y1515056D01*
X3233230Y1515473D01*
X3234315Y1515056D01*
X3235090Y1514223D01*
X3235710Y1512973D01*
X3235865Y1511514D01*
X3235710Y1510264D01*
X3235090Y1509014D01*
X3234160Y1507973D01*
X3233075Y1507556D01*
X3231835Y1507973D01*
X3230750Y1509222D01*
X3230130Y1511098D01*
X3229975Y1513181D01*
X3230285Y1515889D01*
X3230750Y1517348D01*
X3231525Y1518806D01*
X3232610Y1519848D01*
X3233695Y1520056D01*
X3234780Y1519639D01*
X3235555Y1518598D01*
G01X3201610Y-501844D02*
X3201920Y-499136D01*
X3202385Y-496844D01*
X3203005Y-494761D01*
X3203780Y-492469D01*
X3205020Y-489344D01*
X3198820D01*
G01X3211375Y-491427D02*
X3212305Y-490178D01*
X3213390Y-489552D01*
X3214630Y-489344D01*
X3216180Y-489761D01*
X3217265Y-490802D01*
X3217575Y-492052D01*
X3217420Y-493303D01*
X3216800Y-494344D01*
X3213700Y-496427D01*
X3212305Y-497886D01*
X3211375Y-499969D01*
X3211065Y-501844D01*
X3217575D01*
G01X3201920Y-265444D02*
Y-252944D01*
X3200060Y-255444D01*
G01Y-265444D02*
X3203780D01*
G01X3216180D02*
Y-252944D01*
X3210445Y-261902D01*
X3218195D01*
G01X3195720Y266456D02*
Y278956D01*
X3193860Y276456D01*
G01Y266456D02*
X3197580D01*
G01X3205175Y276873D02*
X3206105Y278122D01*
X3207190Y278748D01*
X3208430Y278956D01*
X3209980Y278539D01*
X3211065Y277498D01*
X3211375Y276248D01*
X3211220Y274997D01*
X3210600Y273956D01*
X3207500Y271873D01*
X3206105Y270414D01*
X3205175Y268331D01*
X3204865Y266456D01*
X3211375D01*
G01X3220520D02*
X3221605Y266664D01*
X3222845Y267289D01*
X3223620Y268331D01*
X3223930Y269789D01*
X3223620Y271247D01*
X3222690Y272498D01*
X3221295Y273123D01*
X3219745D01*
X3218815Y273539D01*
X3218040Y274581D01*
X3217730Y276039D01*
X3218195Y277498D01*
X3219280Y278539D01*
X3220520Y278956D01*
X3221760Y278539D01*
X3222845Y277498D01*
X3223310Y276039D01*
X3223000Y274581D01*
X3222225Y273539D01*
X3221295Y273123D01*
X3219745D01*
X3218350Y272498D01*
X3217420Y271247D01*
X3217110Y269789D01*
X3217420Y268331D01*
X3218195Y267289D01*
X3219435Y266664D01*
X3220520Y266456D01*
G01X3198975Y395073D02*
X3199905Y396322D01*
X3200990Y396948D01*
X3202230Y397156D01*
X3203780Y396739D01*
X3204865Y395698D01*
X3205175Y394448D01*
X3205020Y393197D01*
X3204400Y392156D01*
X3201300Y390073D01*
X3199905Y388614D01*
X3198975Y386531D01*
X3198665Y384656D01*
X3205175D01*
G01X3214320D02*
Y397156D01*
X3212460Y394656D01*
G01Y384656D02*
X3216180D01*
G01X3198975Y572373D02*
X3199905Y573622D01*
X3200990Y574248D01*
X3202230Y574456D01*
X3203780Y574039D01*
X3204865Y572998D01*
X3205175Y571748D01*
X3205020Y570497D01*
X3204400Y569456D01*
X3201300Y567373D01*
X3199905Y565914D01*
X3198975Y563831D01*
X3198665Y561956D01*
X3205175D01*
G01X3216180D02*
Y574456D01*
X3210445Y565498D01*
X3218195D01*
G01X3203780Y680156D02*
Y692656D01*
X3198045Y683698D01*
X3205795D01*
G01X3214320Y680156D02*
X3215405Y680364D01*
X3216645Y680989D01*
X3217420Y682031D01*
X3217730Y683489D01*
X3217420Y684947D01*
X3216490Y686198D01*
X3215095Y686823D01*
X3213545D01*
X3212615Y687239D01*
X3211840Y688281D01*
X3211530Y689739D01*
X3211995Y691198D01*
X3213080Y692239D01*
X3214320Y692656D01*
X3215560Y692239D01*
X3216645Y691198D01*
X3217110Y689739D01*
X3216800Y688281D01*
X3216025Y687239D01*
X3215095Y686823D01*
X3213545D01*
X3212150Y686198D01*
X3211220Y684947D01*
X3210910Y683489D01*
X3211220Y682031D01*
X3211995Y680989D01*
X3213235Y680364D01*
X3214320Y680156D01*
G01X3198510Y800856D02*
X3199440Y799397D01*
X3200680Y798564D01*
X3202075Y798356D01*
X3203315Y798564D01*
X3204555Y799606D01*
X3205330Y800856D01*
X3205485Y802106D01*
X3205175Y803564D01*
X3204090Y804606D01*
X3203005Y805023D01*
X3201610D01*
G01X3203005D02*
X3203935Y805648D01*
X3204710Y806689D01*
X3205020Y807939D01*
X3204710Y809189D01*
X3203935Y810231D01*
X3202540Y810856D01*
X3201145Y810648D01*
X3199750Y809814D01*
G01X3211375Y808773D02*
X3212305Y810022D01*
X3213390Y810648D01*
X3214630Y810856D01*
X3216180Y810439D01*
X3217265Y809398D01*
X3217575Y808148D01*
X3217420Y806897D01*
X3216800Y805856D01*
X3213700Y803773D01*
X3212305Y802314D01*
X3211375Y800231D01*
X3211065Y798356D01*
X3217575D01*
G01X3198975Y867873D02*
X3199905Y869122D01*
X3200990Y869748D01*
X3202230Y869956D01*
X3203780Y869539D01*
X3204865Y868498D01*
X3205175Y867248D01*
X3205020Y865997D01*
X3204400Y864956D01*
X3201300Y862873D01*
X3199905Y861414D01*
X3198975Y859331D01*
X3198665Y857456D01*
X3205175D01*
G01X3214320D02*
Y869956D01*
X3212460Y867456D01*
G01Y857456D02*
X3216180D01*
G01X3198975Y921764D02*
X3200060Y923223D01*
X3200990Y924056D01*
X3202230Y924473D01*
X3203315Y924056D01*
X3204090Y923223D01*
X3204710Y921973D01*
X3204865Y920514D01*
X3204710Y919264D01*
X3204090Y918014D01*
X3203160Y916973D01*
X3202075Y916556D01*
X3200835Y916973D01*
X3199750Y918222D01*
X3199130Y920098D01*
X3198975Y922181D01*
X3199285Y924889D01*
X3199750Y926348D01*
X3200525Y927806D01*
X3201610Y928848D01*
X3202695Y929056D01*
X3203780Y928639D01*
X3204555Y927598D01*
G01X3214320Y929056D02*
X3213080Y928639D01*
X3212150Y927598D01*
X3211530Y926348D01*
X3211065Y924681D01*
X3210910Y922806D01*
X3211065Y920931D01*
X3211530Y919264D01*
X3212150Y918014D01*
X3213080Y916973D01*
X3214320Y916556D01*
X3215560Y916973D01*
X3216490Y918014D01*
X3217110Y919264D01*
X3217575Y920931D01*
X3217730Y922806D01*
X3217575Y924681D01*
X3217110Y926348D01*
X3216490Y927598D01*
X3215560Y928639D01*
X3214320Y929056D01*
G01X3198510Y978156D02*
X3199440Y976697D01*
X3200680Y975864D01*
X3202075Y975656D01*
X3203315Y975864D01*
X3204555Y976906D01*
X3205330Y978156D01*
X3205485Y979406D01*
X3205175Y980864D01*
X3204090Y981906D01*
X3203005Y982323D01*
X3201610D01*
G01X3203005D02*
X3203935Y982948D01*
X3204710Y983989D01*
X3205020Y985239D01*
X3204710Y986489D01*
X3203935Y987531D01*
X3202540Y988156D01*
X3201145Y987948D01*
X3199750Y987114D01*
G01X3214320Y988156D02*
X3213080Y987739D01*
X3212150Y986698D01*
X3211530Y985448D01*
X3211065Y983781D01*
X3210910Y981906D01*
X3211065Y980031D01*
X3211530Y978364D01*
X3212150Y977114D01*
X3213080Y976073D01*
X3214320Y975656D01*
X3215560Y976073D01*
X3216490Y977114D01*
X3217110Y978364D01*
X3217575Y980031D01*
X3217730Y981906D01*
X3217575Y983781D01*
X3217110Y985448D01*
X3216490Y986698D01*
X3215560Y987739D01*
X3214320Y988156D01*
G01X3203780Y1152956D02*
Y1165456D01*
X3198045Y1156498D01*
X3205795D01*
G01X3214320Y1165456D02*
X3213080Y1165039D01*
X3212150Y1163998D01*
X3211530Y1162748D01*
X3211065Y1161081D01*
X3210910Y1159206D01*
X3211065Y1157331D01*
X3211530Y1155664D01*
X3212150Y1154414D01*
X3213080Y1153373D01*
X3214320Y1152956D01*
X3215560Y1153373D01*
X3216490Y1154414D01*
X3217110Y1155664D01*
X3217575Y1157331D01*
X3217730Y1159206D01*
X3217575Y1161081D01*
X3217110Y1162748D01*
X3216490Y1163998D01*
X3215560Y1165039D01*
X3214320Y1165456D01*
G01X3192310Y1214556D02*
X3193240Y1213097D01*
X3194480Y1212264D01*
X3195875Y1212056D01*
X3197115Y1212264D01*
X3198355Y1213306D01*
X3199130Y1214556D01*
X3199285Y1215806D01*
X3198975Y1217264D01*
X3197890Y1218306D01*
X3196805Y1218723D01*
X3195410D01*
G01X3196805D02*
X3197735Y1219348D01*
X3198510Y1220389D01*
X3198820Y1221639D01*
X3198510Y1222889D01*
X3197735Y1223931D01*
X3196340Y1224556D01*
X3194945Y1224348D01*
X3193550Y1223514D01*
G01X3204710Y1214556D02*
X3205640Y1213097D01*
X3206880Y1212264D01*
X3208275Y1212056D01*
X3209515Y1212264D01*
X3210755Y1213306D01*
X3211530Y1214556D01*
X3211685Y1215806D01*
X3211375Y1217264D01*
X3210290Y1218306D01*
X3209205Y1218723D01*
X3207810D01*
G01X3209205D02*
X3210135Y1219348D01*
X3210910Y1220389D01*
X3211220Y1221639D01*
X3210910Y1222889D01*
X3210135Y1223931D01*
X3208740Y1224556D01*
X3207345Y1224348D01*
X3205950Y1223514D01*
G01X3217575Y1217264D02*
X3218660Y1218723D01*
X3219590Y1219556D01*
X3220830Y1219973D01*
X3221915Y1219556D01*
X3222690Y1218723D01*
X3223310Y1217473D01*
X3223465Y1216014D01*
X3223310Y1214764D01*
X3222690Y1213514D01*
X3221760Y1212473D01*
X3220675Y1212056D01*
X3219435Y1212473D01*
X3218350Y1213722D01*
X3217730Y1215598D01*
X3217575Y1217681D01*
X3217885Y1220389D01*
X3218350Y1221848D01*
X3219125Y1223306D01*
X3220210Y1224348D01*
X3221295Y1224556D01*
X3222380Y1224139D01*
X3223155Y1223098D01*
G01X3192775Y1276364D02*
X3193860Y1277823D01*
X3194790Y1278656D01*
X3196030Y1279073D01*
X3197115Y1278656D01*
X3197890Y1277823D01*
X3198510Y1276573D01*
X3198665Y1275114D01*
X3198510Y1273864D01*
X3197890Y1272614D01*
X3196960Y1271573D01*
X3195875Y1271156D01*
X3194635Y1271573D01*
X3193550Y1272822D01*
X3192930Y1274698D01*
X3192775Y1276781D01*
X3193085Y1279489D01*
X3193550Y1280948D01*
X3194325Y1282406D01*
X3195410Y1283448D01*
X3196495Y1283656D01*
X3197580Y1283239D01*
X3198355Y1282198D01*
G01X3208120Y1283656D02*
X3206880Y1283239D01*
X3205950Y1282198D01*
X3205330Y1280948D01*
X3204865Y1279281D01*
X3204710Y1277406D01*
X3204865Y1275531D01*
X3205330Y1273864D01*
X3205950Y1272614D01*
X3206880Y1271573D01*
X3208120Y1271156D01*
X3209360Y1271573D01*
X3210290Y1272614D01*
X3210910Y1273864D01*
X3211375Y1275531D01*
X3211530Y1277406D01*
X3211375Y1279281D01*
X3210910Y1280948D01*
X3210290Y1282198D01*
X3209360Y1283239D01*
X3208120Y1283656D01*
G01X3220520Y1271156D02*
X3221605Y1271364D01*
X3222845Y1271989D01*
X3223620Y1273031D01*
X3223930Y1274489D01*
X3223620Y1275947D01*
X3222690Y1277198D01*
X3221295Y1277823D01*
X3219745D01*
X3218815Y1278239D01*
X3218040Y1279281D01*
X3217730Y1280739D01*
X3218195Y1282198D01*
X3219280Y1283239D01*
X3220520Y1283656D01*
X3221760Y1283239D01*
X3222845Y1282198D01*
X3223310Y1280739D01*
X3223000Y1279281D01*
X3222225Y1278239D01*
X3221295Y1277823D01*
X3219745D01*
X3218350Y1277198D01*
X3217420Y1275947D01*
X3217110Y1274489D01*
X3217420Y1273031D01*
X3218195Y1271989D01*
X3219435Y1271364D01*
X3220520Y1271156D01*
G01X3189520Y1389356D02*
Y1401856D01*
X3187660Y1399356D01*
G01Y1389356D02*
X3191380D01*
G01X3199285Y1390814D02*
X3200370Y1389773D01*
X3201610Y1389356D01*
X3202850Y1389773D01*
X3203935Y1391022D01*
X3204710Y1392898D01*
X3205020Y1394773D01*
Y1397064D01*
X3204710Y1398939D01*
X3203935Y1400606D01*
X3203005Y1401439D01*
X3201920Y1401856D01*
X3200680Y1401439D01*
X3199750Y1400606D01*
X3199130Y1399356D01*
X3198820Y1397689D01*
X3199130Y1396231D01*
X3199905Y1394773D01*
X3200835Y1393939D01*
X3201920Y1393731D01*
X3203160Y1394147D01*
X3204090Y1395189D01*
X3205020Y1397064D01*
G01X3211375Y1394564D02*
X3212460Y1396023D01*
X3213390Y1396856D01*
X3214630Y1397273D01*
X3215715Y1396856D01*
X3216490Y1396023D01*
X3217110Y1394773D01*
X3217265Y1393314D01*
X3217110Y1392064D01*
X3216490Y1390814D01*
X3215560Y1389773D01*
X3214475Y1389356D01*
X3213235Y1389773D01*
X3212150Y1391022D01*
X3211530Y1392898D01*
X3211375Y1394981D01*
X3211685Y1397689D01*
X3212150Y1399148D01*
X3212925Y1400606D01*
X3214010Y1401648D01*
X3215095Y1401856D01*
X3216180Y1401439D01*
X3216955Y1400398D01*
G01X3228580Y1389356D02*
Y1401856D01*
X3222845Y1392898D01*
X3230595D01*
G01X3195720Y1448456D02*
Y1460956D01*
X3193860Y1458456D01*
G01Y1448456D02*
X3197580D01*
G01X3207810D02*
X3208120Y1451164D01*
X3208585Y1453456D01*
X3209205Y1455539D01*
X3209980Y1457831D01*
X3211220Y1460956D01*
X3205020D01*
G01X3217575Y1453664D02*
X3218660Y1455123D01*
X3219590Y1455956D01*
X3220830Y1456373D01*
X3221915Y1455956D01*
X3222690Y1455123D01*
X3223310Y1453873D01*
X3223465Y1452414D01*
X3223310Y1451164D01*
X3222690Y1449914D01*
X3221760Y1448873D01*
X3220675Y1448456D01*
X3219435Y1448873D01*
X3218350Y1450122D01*
X3217730Y1451998D01*
X3217575Y1454081D01*
X3217885Y1456789D01*
X3218350Y1458248D01*
X3219125Y1459706D01*
X3220210Y1460748D01*
X3221295Y1460956D01*
X3222380Y1460539D01*
X3223155Y1459498D01*
G01X3195720Y1549606D02*
X3194480Y1549814D01*
X3193395Y1550647D01*
X3192465Y1551898D01*
X3191845Y1553356D01*
X3191535Y1555023D01*
Y1556689D01*
X3191845Y1558356D01*
X3192465Y1559814D01*
X3193395Y1561064D01*
X3194480Y1561898D01*
X3195720Y1562106D01*
X3196960Y1561898D01*
X3198045Y1561064D01*
X3198975Y1559814D01*
X3199595Y1558356D01*
X3199905Y1556689D01*
Y1555023D01*
X3199595Y1553356D01*
X3198975Y1551898D01*
X3198045Y1550647D01*
X3196960Y1549814D01*
X3195720Y1549606D01*
G01X3196960Y1552939D02*
X3198820Y1549606D01*
G01X3208120Y1562106D02*
Y1549606D01*
G01X3204555Y1562106D02*
X3211685D01*
G01X3220520Y1549606D02*
Y1555231D01*
X3217420Y1562106D01*
G01X3223620D02*
X3220520Y1555231D01*
G01X3208120Y-620044D02*
Y-607544D01*
X3206260Y-610044D01*
G01Y-620044D02*
X3209980D01*
G01X3205175Y-550527D02*
X3206105Y-549278D01*
X3207190Y-548652D01*
X3208430Y-548444D01*
X3209980Y-548861D01*
X3211065Y-549902D01*
X3211375Y-551152D01*
X3211220Y-552403D01*
X3210600Y-553444D01*
X3207500Y-555527D01*
X3206105Y-556986D01*
X3205175Y-559069D01*
X3204865Y-560944D01*
X3211375D01*
G01X3205175Y-432327D02*
X3206105Y-431078D01*
X3207190Y-430452D01*
X3208430Y-430244D01*
X3209980Y-430661D01*
X3211065Y-431702D01*
X3211375Y-432952D01*
X3211220Y-434203D01*
X3210600Y-435244D01*
X3207500Y-437327D01*
X3206105Y-438786D01*
X3205175Y-440869D01*
X3204865Y-442744D01*
X3211375D01*
G01X3209980Y-383644D02*
Y-371144D01*
X3204245Y-380102D01*
X3211995D01*
G01X3205175Y-314127D02*
X3206105Y-312878D01*
X3207190Y-312252D01*
X3208430Y-312044D01*
X3209980Y-312461D01*
X3211065Y-313502D01*
X3211375Y-314752D01*
X3211220Y-316003D01*
X3210600Y-317044D01*
X3207500Y-319127D01*
X3206105Y-320586D01*
X3205175Y-322669D01*
X3204865Y-324544D01*
X3211375D01*
G01X3205175Y-201136D02*
X3206260Y-199677D01*
X3207190Y-198844D01*
X3208430Y-198427D01*
X3209515Y-198844D01*
X3210290Y-199677D01*
X3210910Y-200927D01*
X3211065Y-202386D01*
X3210910Y-203636D01*
X3210290Y-204886D01*
X3209360Y-205927D01*
X3208275Y-206344D01*
X3207035Y-205927D01*
X3205950Y-204678D01*
X3205330Y-202802D01*
X3205175Y-200719D01*
X3205485Y-198011D01*
X3205950Y-196552D01*
X3206725Y-195094D01*
X3207810Y-194052D01*
X3208895Y-193844D01*
X3209980Y-194261D01*
X3210755Y-195302D01*
G01X3209980Y-147244D02*
Y-134744D01*
X3204245Y-143702D01*
X3211995D01*
G01X3208120Y-88144D02*
Y-75644D01*
X3206260Y-78144D01*
G01Y-88144D02*
X3209980D01*
G01X3205175Y-18627D02*
X3206105Y-17378D01*
X3207190Y-16752D01*
X3208430Y-16544D01*
X3209980Y-16961D01*
X3211065Y-18002D01*
X3211375Y-19252D01*
X3211220Y-20503D01*
X3210600Y-21544D01*
X3207500Y-23627D01*
X3206105Y-25086D01*
X3205175Y-27169D01*
X3204865Y-29044D01*
X3211375D01*
G01X3208120Y30056D02*
Y42556D01*
X3206260Y40056D01*
G01Y30056D02*
X3209980D01*
G01X3208120Y89156D02*
Y101656D01*
X3206260Y99156D01*
G01Y89156D02*
X3209980D01*
G01X3205175Y158673D02*
X3206105Y159922D01*
X3207190Y160548D01*
X3208430Y160756D01*
X3209980Y160339D01*
X3211065Y159298D01*
X3211375Y158048D01*
X3211220Y156797D01*
X3210600Y155756D01*
X3207500Y153673D01*
X3206105Y152214D01*
X3205175Y150131D01*
X3204865Y148256D01*
X3211375D01*
G01X3208120Y207356D02*
X3209205Y207564D01*
X3210445Y208189D01*
X3211220Y209231D01*
X3211530Y210689D01*
X3211220Y212147D01*
X3210290Y213398D01*
X3208895Y214023D01*
X3207345D01*
X3206415Y214439D01*
X3205640Y215481D01*
X3205330Y216939D01*
X3205795Y218398D01*
X3206880Y219439D01*
X3208120Y219856D01*
X3209360Y219439D01*
X3210445Y218398D01*
X3210910Y216939D01*
X3210600Y215481D01*
X3209825Y214439D01*
X3208895Y214023D01*
X3207345D01*
X3205950Y213398D01*
X3205020Y212147D01*
X3204710Y210689D01*
X3205020Y209231D01*
X3205795Y208189D01*
X3207035Y207564D01*
X3208120Y207356D01*
G01X3205175Y335973D02*
X3206105Y337222D01*
X3207190Y337848D01*
X3208430Y338056D01*
X3209980Y337639D01*
X3211065Y336598D01*
X3211375Y335348D01*
X3211220Y334097D01*
X3210600Y333056D01*
X3207500Y330973D01*
X3206105Y329514D01*
X3205175Y327431D01*
X3204865Y325556D01*
X3211375D01*
G01X3208120Y443756D02*
Y456256D01*
X3206260Y453756D01*
G01Y443756D02*
X3209980D01*
G01X3205175Y513273D02*
X3206105Y514522D01*
X3207190Y515148D01*
X3208430Y515356D01*
X3209980Y514939D01*
X3211065Y513898D01*
X3211375Y512648D01*
X3211220Y511397D01*
X3210600Y510356D01*
X3207500Y508273D01*
X3206105Y506814D01*
X3205175Y504731D01*
X3204865Y502856D01*
X3211375D01*
G01X3205175Y631473D02*
X3206105Y632722D01*
X3207190Y633348D01*
X3208430Y633556D01*
X3209980Y633139D01*
X3211065Y632098D01*
X3211375Y630848D01*
X3211220Y629597D01*
X3210600Y628556D01*
X3207500Y626473D01*
X3206105Y625014D01*
X3205175Y622931D01*
X3204865Y621056D01*
X3211375D01*
G01X3208120Y739256D02*
X3209205Y739464D01*
X3210445Y740089D01*
X3211220Y741131D01*
X3211530Y742589D01*
X3211220Y744047D01*
X3210290Y745298D01*
X3208895Y745923D01*
X3207345D01*
X3206415Y746339D01*
X3205640Y747381D01*
X3205330Y748839D01*
X3205795Y750298D01*
X3206880Y751339D01*
X3208120Y751756D01*
X3209360Y751339D01*
X3210445Y750298D01*
X3210910Y748839D01*
X3210600Y747381D01*
X3209825Y746339D01*
X3208895Y745923D01*
X3207345D01*
X3205950Y745298D01*
X3205020Y744047D01*
X3204710Y742589D01*
X3205020Y741131D01*
X3205795Y740089D01*
X3207035Y739464D01*
X3208120Y739256D01*
G01Y1034756D02*
Y1047256D01*
X3206260Y1044756D01*
G01Y1034756D02*
X3209980D01*
G01X3208120Y1093856D02*
X3209205Y1094064D01*
X3210445Y1094689D01*
X3211220Y1095731D01*
X3211530Y1097189D01*
X3211220Y1098647D01*
X3210290Y1099898D01*
X3208895Y1100523D01*
X3207345D01*
X3206415Y1100939D01*
X3205640Y1101981D01*
X3205330Y1103439D01*
X3205795Y1104898D01*
X3206880Y1105939D01*
X3208120Y1106356D01*
X3209360Y1105939D01*
X3210445Y1104898D01*
X3210910Y1103439D01*
X3210600Y1101981D01*
X3209825Y1100939D01*
X3208895Y1100523D01*
X3207345D01*
X3205950Y1099898D01*
X3205020Y1098647D01*
X3204710Y1097189D01*
X3205020Y1095731D01*
X3205795Y1094689D01*
X3207035Y1094064D01*
X3208120Y1093856D01*
G01X3313686Y915949D02*
Y923449D01*
X3316020D01*
X3316766Y923074D01*
X3317233Y922574D01*
X3317420Y921574D01*
X3317233Y920574D01*
X3316673Y919949D01*
X3316020Y919574D01*
X3313686D01*
G01X3316020D02*
X3317420Y915949D01*
G01X3324920D02*
X3321186D01*
Y923449D01*
X3324920D01*
G01X3323426Y919824D02*
X3321186D01*
G01X3332606Y922824D02*
X3332046Y923199D01*
X3331393Y923449D01*
X3330646D01*
X3329806Y923074D01*
X3329153Y922449D01*
X3328686Y921699D01*
X3328313Y920449D01*
X3328220Y919324D01*
X3328406Y918199D01*
X3328686Y917449D01*
X3329246Y916699D01*
X3329900Y916199D01*
X3330553Y915949D01*
X3331206D01*
X3331860Y916199D01*
X3332420Y916574D01*
X3332886Y917074D01*
G01X3338053Y915949D02*
X3337306Y916074D01*
X3336653Y916574D01*
X3336093Y917324D01*
X3335720Y918199D01*
X3335533Y919199D01*
Y920199D01*
X3335720Y921199D01*
X3336093Y922074D01*
X3336653Y922824D01*
X3337306Y923324D01*
X3338053Y923449D01*
X3338800Y923324D01*
X3339453Y922824D01*
X3340013Y922074D01*
X3340386Y921199D01*
X3340573Y920199D01*
Y919199D01*
X3340386Y918199D01*
X3340013Y917324D01*
X3339453Y916574D01*
X3338800Y916074D01*
X3338053Y915949D01*
G01X3343126D02*
Y923449D01*
X3345553Y917199D01*
X3347980Y923449D01*
Y915949D01*
G01X3350626D02*
Y923449D01*
X3353053Y917199D01*
X3355480Y923449D01*
Y915949D01*
G01X3362420D02*
X3358686D01*
Y923449D01*
X3362420D01*
G01X3360926Y919824D02*
X3358686D01*
G01X3365906Y915949D02*
Y923449D01*
X3370200Y915949D01*
Y923449D01*
G01X3373500Y915949D02*
Y923449D01*
X3375366D01*
X3376113Y923074D01*
X3376673Y922574D01*
X3377140Y921824D01*
X3377513Y920949D01*
X3377606Y919699D01*
X3377513Y918449D01*
X3377140Y917574D01*
X3376673Y916824D01*
X3376113Y916324D01*
X3375366Y915949D01*
X3373500D01*
G01X3384920D02*
X3381186D01*
Y923449D01*
X3384920D01*
G01X3383426Y919824D02*
X3381186D01*
G01X3388500Y915949D02*
Y923449D01*
X3390366D01*
X3391113Y923074D01*
X3391673Y922574D01*
X3392140Y921824D01*
X3392513Y920949D01*
X3392606Y919699D01*
X3392513Y918449D01*
X3392140Y917574D01*
X3391673Y916824D01*
X3391113Y916324D01*
X3390366Y915949D01*
X3388500D01*
G01X3403500D02*
Y923449D01*
X3405366D01*
X3406113Y923074D01*
X3406673Y922574D01*
X3407140Y921824D01*
X3407513Y920949D01*
X3407606Y919699D01*
X3407513Y918449D01*
X3407140Y917574D01*
X3406673Y916824D01*
X3406113Y916324D01*
X3405366Y915949D01*
X3403500D01*
G01X3411186D02*
Y923449D01*
X3413520D01*
X3414266Y923074D01*
X3414733Y922574D01*
X3414920Y921574D01*
X3414733Y920574D01*
X3414173Y919949D01*
X3413520Y919574D01*
X3411186D01*
G01X3413520D02*
X3414920Y915949D01*
G01X3419433Y923449D02*
X3421673D01*
G01X3420553D02*
Y915949D01*
G01X3419433D02*
X3421673D01*
G01X3426186Y923449D02*
Y915949D01*
X3429920D01*
G01X3433686Y923449D02*
Y915949D01*
X3437420D01*
G01X3448593Y916949D02*
X3449340Y916324D01*
X3450180Y915949D01*
X3450926D01*
X3451673Y916324D01*
X3452233Y916949D01*
X3452513Y917824D01*
X3452326Y918699D01*
X3451860Y919449D01*
X3451020Y919949D01*
X3449900Y920199D01*
X3449246Y920699D01*
X3448966Y921574D01*
X3449153Y922449D01*
X3449620Y923074D01*
X3450273Y923449D01*
X3450926D01*
X3451580Y923199D01*
X3452140Y922574D01*
G01X3456933Y923449D02*
X3459173D01*
G01X3458053D02*
Y915949D01*
G01X3456933D02*
X3459173D01*
G01X3463780Y923449D02*
X3467326D01*
X3463780Y915949D01*
X3467326D01*
G01X3474920D02*
X3471186D01*
Y923449D01*
X3474920D01*
G01X3473426Y919824D02*
X3471186D01*
G01X3486280Y915949D02*
Y923449D01*
X3489826D01*
G01X3488520Y919824D02*
X3486280D01*
G01X3495553Y915949D02*
X3494806Y916074D01*
X3494153Y916574D01*
X3493593Y917324D01*
X3493220Y918199D01*
X3493033Y919199D01*
Y920199D01*
X3493220Y921199D01*
X3493593Y922074D01*
X3494153Y922824D01*
X3494806Y923324D01*
X3495553Y923449D01*
X3496300Y923324D01*
X3496953Y922824D01*
X3497513Y922074D01*
X3497886Y921199D01*
X3498073Y920199D01*
Y919199D01*
X3497886Y918199D01*
X3497513Y917324D01*
X3496953Y916574D01*
X3496300Y916074D01*
X3495553Y915949D01*
G01X3501186D02*
Y923449D01*
X3503520D01*
X3504266Y923074D01*
X3504733Y922574D01*
X3504920Y921574D01*
X3504733Y920574D01*
X3504173Y919949D01*
X3503520Y919574D01*
X3501186D01*
G01X3503520D02*
X3504920Y915949D01*
G01X3518053D02*
Y923449D01*
X3516933Y921949D01*
G01Y915949D02*
X3519173D01*
G01X3525553Y915699D02*
X3525366Y915824D01*
Y916074D01*
X3525553Y916199D01*
X3525740Y916074D01*
Y915824D01*
X3525553Y915699D01*
G01X3533053Y923449D02*
X3532306Y923199D01*
X3531746Y922574D01*
X3531373Y921824D01*
X3531093Y920824D01*
X3531000Y919699D01*
X3531093Y918574D01*
X3531373Y917574D01*
X3531746Y916824D01*
X3532306Y916199D01*
X3533053Y915949D01*
X3533800Y916199D01*
X3534360Y916824D01*
X3534733Y917574D01*
X3535013Y918574D01*
X3535106Y919699D01*
X3535013Y920824D01*
X3534733Y921824D01*
X3534360Y922574D01*
X3533800Y923199D01*
X3533053Y923449D01*
G01X3538780Y922199D02*
X3539340Y922949D01*
X3539993Y923324D01*
X3540740Y923449D01*
X3541673Y923199D01*
X3542326Y922574D01*
X3542513Y921824D01*
X3542420Y921074D01*
X3542046Y920449D01*
X3540180Y919199D01*
X3539340Y918324D01*
X3538780Y917074D01*
X3538593Y915949D01*
X3542513D01*
G01X3545626D02*
Y923449D01*
X3548053Y917199D01*
X3550480Y923449D01*
Y915949D01*
G01X3553126D02*
Y923449D01*
X3555553Y917199D01*
X3557980Y923449D01*
Y915949D01*
G01X3568780D02*
Y923449D01*
X3572326D01*
G01X3571020Y919824D02*
X3568780D01*
G01X3576933Y923449D02*
X3579173D01*
G01X3578053D02*
Y915949D01*
G01X3576933D02*
X3579173D01*
G01X3583406D02*
Y923449D01*
X3587700Y915949D01*
Y923449D01*
G01X3591933D02*
X3594173D01*
G01X3593053D02*
Y915949D01*
G01X3591933D02*
X3594173D01*
G01X3598593Y916949D02*
X3599340Y916324D01*
X3600180Y915949D01*
X3600926D01*
X3601673Y916324D01*
X3602233Y916949D01*
X3602513Y917824D01*
X3602326Y918699D01*
X3601860Y919449D01*
X3601020Y919949D01*
X3599900Y920199D01*
X3599246Y920699D01*
X3598966Y921574D01*
X3599153Y922449D01*
X3599620Y923074D01*
X3600273Y923449D01*
X3600926D01*
X3601580Y923199D01*
X3602140Y922574D01*
G01X3606093Y915949D02*
Y923449D01*
G01X3610013D02*
Y915949D01*
G01Y919699D02*
X3606093D01*
G01X3617420Y915949D02*
X3613686D01*
Y923449D01*
X3617420D01*
G01X3615926Y919824D02*
X3613686D01*
G01X3621000Y915949D02*
Y923449D01*
X3622866D01*
X3623613Y923074D01*
X3624173Y922574D01*
X3624640Y921824D01*
X3625013Y920949D01*
X3625106Y919699D01*
X3625013Y918449D01*
X3624640Y917574D01*
X3624173Y916824D01*
X3623613Y916324D01*
X3622866Y915949D01*
X3621000D01*
G01X3636186D02*
Y923449D01*
X3638426D01*
X3639173Y923074D01*
X3639733Y922199D01*
X3639920Y921199D01*
X3639733Y920199D01*
X3639266Y919449D01*
X3638426Y919074D01*
X3636186D01*
G01X3645553Y923449D02*
Y915949D01*
G01X3643406Y923449D02*
X3647700D01*
G01X3651093Y915949D02*
Y923449D01*
G01X3655013D02*
Y915949D01*
G01Y919699D02*
X3651093D01*
G01X3666933Y923449D02*
X3669173D01*
G01X3668053D02*
Y915949D01*
G01X3666933D02*
X3669173D01*
G01X3673593Y916949D02*
X3674340Y916324D01*
X3675180Y915949D01*
X3675926D01*
X3676673Y916324D01*
X3677233Y916949D01*
X3677513Y917824D01*
X3677326Y918699D01*
X3676860Y919449D01*
X3676020Y919949D01*
X3674900Y920199D01*
X3674246Y920699D01*
X3673966Y921574D01*
X3674153Y922449D01*
X3674620Y923074D01*
X3675273Y923449D01*
X3675926D01*
X3676580Y923199D01*
X3677140Y922574D01*
G01X3690553Y915949D02*
Y923449D01*
X3689433Y921949D01*
G01Y915949D02*
X3691673D01*
G01X3698053Y915699D02*
X3697866Y915824D01*
Y916074D01*
X3698053Y916199D01*
X3698240Y916074D01*
Y915824D01*
X3698053Y915699D01*
G01X3705553Y915949D02*
Y923449D01*
X3704433Y921949D01*
G01Y915949D02*
X3706673D01*
G01X3711000Y917074D02*
X3711560Y916449D01*
X3712213Y916074D01*
X3713053Y915949D01*
X3713893Y916199D01*
X3714546Y916699D01*
X3715013Y917574D01*
X3715106Y918574D01*
X3714920Y919574D01*
X3714453Y920199D01*
X3713800Y920699D01*
X3713146Y920824D01*
X3712493Y920699D01*
X3711653Y920199D01*
X3711933Y923449D01*
X3714453D01*
G01X3719526Y918449D02*
X3721766D01*
G01X3720553Y920074D02*
Y916824D01*
G01X3726373Y915699D02*
X3729733Y923449D01*
G01X3734340Y918449D02*
X3736766D01*
G01X3743053Y923449D02*
X3742306Y923199D01*
X3741746Y922574D01*
X3741373Y921824D01*
X3741093Y920824D01*
X3741000Y919699D01*
X3741093Y918574D01*
X3741373Y917574D01*
X3741746Y916824D01*
X3742306Y916199D01*
X3743053Y915949D01*
X3743800Y916199D01*
X3744360Y916824D01*
X3744733Y917574D01*
X3745013Y918574D01*
X3745106Y919699D01*
X3745013Y920824D01*
X3744733Y921824D01*
X3744360Y922574D01*
X3743800Y923199D01*
X3743053Y923449D01*
G01X3750553Y915699D02*
X3750366Y915824D01*
Y916074D01*
X3750553Y916199D01*
X3750740Y916074D01*
Y915824D01*
X3750553Y915699D01*
G01X3758053Y923449D02*
X3757306Y923199D01*
X3756746Y922574D01*
X3756373Y921824D01*
X3756093Y920824D01*
X3756000Y919699D01*
X3756093Y918574D01*
X3756373Y917574D01*
X3756746Y916824D01*
X3757306Y916199D01*
X3758053Y915949D01*
X3758800Y916199D01*
X3759360Y916824D01*
X3759733Y917574D01*
X3760013Y918574D01*
X3760106Y919699D01*
X3760013Y920824D01*
X3759733Y921824D01*
X3759360Y922574D01*
X3758800Y923199D01*
X3758053Y923449D01*
G01X3763780Y922199D02*
X3764340Y922949D01*
X3764993Y923324D01*
X3765740Y923449D01*
X3766673Y923199D01*
X3767326Y922574D01*
X3767513Y921824D01*
X3767420Y921074D01*
X3767046Y920449D01*
X3765180Y919199D01*
X3764340Y918324D01*
X3763780Y917074D01*
X3763593Y915949D01*
X3767513D01*
G01X3771000Y917074D02*
X3771560Y916449D01*
X3772213Y916074D01*
X3773053Y915949D01*
X3773893Y916199D01*
X3774546Y916699D01*
X3775013Y917574D01*
X3775106Y918574D01*
X3774920Y919574D01*
X3774453Y920199D01*
X3773800Y920699D01*
X3773146Y920824D01*
X3772493Y920699D01*
X3771653Y920199D01*
X3771933Y923449D01*
X3774453D01*
G01X3778126Y915949D02*
Y923449D01*
X3780553Y917199D01*
X3782980Y923449D01*
Y915949D01*
G01X3785626D02*
Y923449D01*
X3788053Y917199D01*
X3790480Y923449D01*
Y915949D01*
G01X3388645Y1228831D02*
Y1236331D01*
X3391072Y1230081D01*
X3393499Y1236331D01*
Y1228831D01*
G01X3396239D02*
X3398572Y1236331D01*
X3400905Y1228831D01*
G01X3400065Y1231456D02*
X3397079D01*
G01X3404205Y1228831D02*
Y1236331D01*
X3406539D01*
X3407285Y1235956D01*
X3407752Y1235456D01*
X3407939Y1234456D01*
X3407752Y1233456D01*
X3407192Y1232831D01*
X3406539Y1232456D01*
X3404205D01*
G01X3406539D02*
X3407939Y1228831D01*
G01X3411519D02*
Y1236331D01*
G01X3415065D02*
X3411519Y1231706D01*
G01X3415625Y1228831D02*
X3413105Y1233831D01*
G01X3421072Y1228581D02*
X3420885Y1228706D01*
Y1228956D01*
X3421072Y1229081D01*
X3421259Y1228956D01*
Y1228706D01*
X3421072Y1228581D01*
G01Y1231956D02*
X3420885Y1232081D01*
Y1232331D01*
X3421072Y1232456D01*
X3421259Y1232331D01*
Y1232081D01*
X3421072Y1231956D01*
G01X3428572Y1236331D02*
Y1228831D01*
G01X3426425Y1236331D02*
X3430719D01*
G01X3434952D02*
X3437192D01*
G01X3436072D02*
Y1228831D01*
G01X3434952D02*
X3437192D01*
G01X3441425D02*
Y1236331D01*
X3445719Y1228831D01*
Y1236331D01*
G01X3456705D02*
Y1228831D01*
X3460439D01*
G01X3467939D02*
X3464205D01*
Y1236331D01*
X3467939D01*
G01X3466445Y1232706D02*
X3464205D01*
G01X3471239Y1228831D02*
X3473572Y1236331D01*
X3475905Y1228831D01*
G01X3475065Y1231456D02*
X3472079D01*
G01X3479019Y1228831D02*
Y1236331D01*
X3480885D01*
X3481632Y1235956D01*
X3482192Y1235456D01*
X3482659Y1234706D01*
X3483032Y1233831D01*
X3483125Y1232581D01*
X3483032Y1231331D01*
X3482659Y1230456D01*
X3482192Y1229706D01*
X3481632Y1229206D01*
X3480885Y1228831D01*
X3479019D01*
G01X3488572Y1228581D02*
X3488385Y1228706D01*
Y1228956D01*
X3488572Y1229081D01*
X3488759Y1228956D01*
Y1228706D01*
X3488572Y1228581D01*
G01Y1231956D02*
X3488385Y1232081D01*
Y1232331D01*
X3488572Y1232456D01*
X3488759Y1232331D01*
Y1232081D01*
X3488572Y1231956D01*
G01X3494205Y1228831D02*
Y1236331D01*
X3496539D01*
X3497285Y1235956D01*
X3497752Y1235456D01*
X3497939Y1234456D01*
X3497752Y1233456D01*
X3497192Y1232831D01*
X3496539Y1232456D01*
X3494205D01*
G01X3496539D02*
X3497939Y1228831D01*
G01X3505439D02*
X3501705D01*
Y1236331D01*
X3505439D01*
G01X3503945Y1232706D02*
X3501705D01*
G01X3513125Y1235706D02*
X3512565Y1236081D01*
X3511912Y1236331D01*
X3511165D01*
X3510325Y1235956D01*
X3509672Y1235331D01*
X3509205Y1234581D01*
X3508832Y1233331D01*
X3508739Y1232206D01*
X3508925Y1231081D01*
X3509205Y1230331D01*
X3509765Y1229581D01*
X3510419Y1229081D01*
X3511072Y1228831D01*
X3511725D01*
X3512379Y1229081D01*
X3512939Y1229456D01*
X3513405Y1229956D01*
G01X3518572Y1228831D02*
X3517825Y1228956D01*
X3517172Y1229456D01*
X3516612Y1230206D01*
X3516239Y1231081D01*
X3516052Y1232081D01*
Y1233081D01*
X3516239Y1234081D01*
X3516612Y1234956D01*
X3517172Y1235706D01*
X3517825Y1236206D01*
X3518572Y1236331D01*
X3519319Y1236206D01*
X3519972Y1235706D01*
X3520532Y1234956D01*
X3520905Y1234081D01*
X3521092Y1233081D01*
Y1232081D01*
X3520905Y1231081D01*
X3520532Y1230206D01*
X3519972Y1229456D01*
X3519319Y1228956D01*
X3518572Y1228831D01*
G01X3523645D02*
Y1236331D01*
X3526072Y1230081D01*
X3528499Y1236331D01*
Y1228831D01*
G01X3531145D02*
Y1236331D01*
X3533572Y1230081D01*
X3535999Y1236331D01*
Y1228831D01*
G01X3542939D02*
X3539205D01*
Y1236331D01*
X3542939D01*
G01X3541445Y1232706D02*
X3539205D01*
G01X3546425Y1228831D02*
Y1236331D01*
X3550719Y1228831D01*
Y1236331D01*
G01X3554019Y1228831D02*
Y1236331D01*
X3555885D01*
X3556632Y1235956D01*
X3557192Y1235456D01*
X3557659Y1234706D01*
X3558032Y1233831D01*
X3558125Y1232581D01*
X3558032Y1231331D01*
X3557659Y1230456D01*
X3557192Y1229706D01*
X3556632Y1229206D01*
X3555885Y1228831D01*
X3554019D01*
G01X3565439D02*
X3561705D01*
Y1236331D01*
X3565439D01*
G01X3563945Y1232706D02*
X3561705D01*
G01X3569019Y1228831D02*
Y1236331D01*
X3570885D01*
X3571632Y1235956D01*
X3572192Y1235456D01*
X3572659Y1234706D01*
X3573032Y1233831D01*
X3573125Y1232581D01*
X3573032Y1231331D01*
X3572659Y1230456D01*
X3572192Y1229706D01*
X3571632Y1229206D01*
X3570885Y1228831D01*
X3569019D01*
G01X3584019D02*
Y1236331D01*
X3585885D01*
X3586632Y1235956D01*
X3587192Y1235456D01*
X3587659Y1234706D01*
X3588032Y1233831D01*
X3588125Y1232581D01*
X3588032Y1231331D01*
X3587659Y1230456D01*
X3587192Y1229706D01*
X3586632Y1229206D01*
X3585885Y1228831D01*
X3584019D01*
G01X3591705D02*
Y1236331D01*
X3594039D01*
X3594785Y1235956D01*
X3595252Y1235456D01*
X3595439Y1234456D01*
X3595252Y1233456D01*
X3594692Y1232831D01*
X3594039Y1232456D01*
X3591705D01*
G01X3594039D02*
X3595439Y1228831D01*
G01X3599952Y1236331D02*
X3602192D01*
G01X3601072D02*
Y1228831D01*
G01X3599952D02*
X3602192D01*
G01X3606705Y1236331D02*
Y1228831D01*
X3610439D01*
G01X3614205Y1236331D02*
Y1228831D01*
X3617939D01*
G01X3629112Y1229831D02*
X3629859Y1229206D01*
X3630699Y1228831D01*
X3631445D01*
X3632192Y1229206D01*
X3632752Y1229831D01*
X3633032Y1230706D01*
X3632845Y1231581D01*
X3632379Y1232331D01*
X3631539Y1232831D01*
X3630419Y1233081D01*
X3629765Y1233581D01*
X3629485Y1234456D01*
X3629672Y1235331D01*
X3630139Y1235956D01*
X3630792Y1236331D01*
X3631445D01*
X3632099Y1236081D01*
X3632659Y1235456D01*
G01X3637452Y1236331D02*
X3639692D01*
G01X3638572D02*
Y1228831D01*
G01X3637452D02*
X3639692D01*
G01X3644299Y1236331D02*
X3647845D01*
X3644299Y1228831D01*
X3647845D01*
G01X3655439D02*
X3651705D01*
Y1236331D01*
X3655439D01*
G01X3653945Y1232706D02*
X3651705D01*
G01X3666799Y1228831D02*
Y1236331D01*
X3670345D01*
G01X3669039Y1232706D02*
X3666799D01*
G01X3676072Y1228831D02*
X3675325Y1228956D01*
X3674672Y1229456D01*
X3674112Y1230206D01*
X3673739Y1231081D01*
X3673552Y1232081D01*
Y1233081D01*
X3673739Y1234081D01*
X3674112Y1234956D01*
X3674672Y1235706D01*
X3675325Y1236206D01*
X3676072Y1236331D01*
X3676819Y1236206D01*
X3677472Y1235706D01*
X3678032Y1234956D01*
X3678405Y1234081D01*
X3678592Y1233081D01*
Y1232081D01*
X3678405Y1231081D01*
X3678032Y1230206D01*
X3677472Y1229456D01*
X3676819Y1228956D01*
X3676072Y1228831D01*
G01X3681705D02*
Y1236331D01*
X3684039D01*
X3684785Y1235956D01*
X3685252Y1235456D01*
X3685439Y1234456D01*
X3685252Y1233456D01*
X3684692Y1232831D01*
X3684039Y1232456D01*
X3681705D01*
G01X3684039D02*
X3685439Y1228831D01*
G01X3698572Y1236331D02*
X3697825Y1236081D01*
X3697265Y1235456D01*
X3696892Y1234706D01*
X3696612Y1233706D01*
X3696519Y1232581D01*
X3696612Y1231456D01*
X3696892Y1230456D01*
X3697265Y1229706D01*
X3697825Y1229081D01*
X3698572Y1228831D01*
X3699319Y1229081D01*
X3699879Y1229706D01*
X3700252Y1230456D01*
X3700532Y1231456D01*
X3700625Y1232581D01*
X3700532Y1233706D01*
X3700252Y1234706D01*
X3699879Y1235456D01*
X3699319Y1236081D01*
X3698572Y1236331D01*
G01X3706072Y1228581D02*
X3705885Y1228706D01*
Y1228956D01*
X3706072Y1229081D01*
X3706259Y1228956D01*
Y1228706D01*
X3706072Y1228581D01*
G01X3711519Y1229956D02*
X3712079Y1229331D01*
X3712732Y1228956D01*
X3713572Y1228831D01*
X3714412Y1229081D01*
X3715065Y1229581D01*
X3715532Y1230456D01*
X3715625Y1231456D01*
X3715439Y1232456D01*
X3714972Y1233081D01*
X3714319Y1233581D01*
X3713665Y1233706D01*
X3713012Y1233581D01*
X3712172Y1233081D01*
X3712452Y1236331D01*
X3714972D01*
G01X3718645Y1228831D02*
Y1236331D01*
X3721072Y1230081D01*
X3723499Y1236331D01*
Y1228831D01*
G01X3726145D02*
Y1236331D01*
X3728572Y1230081D01*
X3730999Y1236331D01*
Y1228831D01*
G01X3741799D02*
Y1236331D01*
X3745345D01*
G01X3744039Y1232706D02*
X3741799D01*
G01X3749952Y1236331D02*
X3752192D01*
G01X3751072D02*
Y1228831D01*
G01X3749952D02*
X3752192D01*
G01X3756425D02*
Y1236331D01*
X3760719Y1228831D01*
Y1236331D01*
G01X3764952D02*
X3767192D01*
G01X3766072D02*
Y1228831D01*
G01X3764952D02*
X3767192D01*
G01X3771612Y1229831D02*
X3772359Y1229206D01*
X3773199Y1228831D01*
X3773945D01*
X3774692Y1229206D01*
X3775252Y1229831D01*
X3775532Y1230706D01*
X3775345Y1231581D01*
X3774879Y1232331D01*
X3774039Y1232831D01*
X3772919Y1233081D01*
X3772265Y1233581D01*
X3771985Y1234456D01*
X3772172Y1235331D01*
X3772639Y1235956D01*
X3773292Y1236331D01*
X3773945D01*
X3774599Y1236081D01*
X3775159Y1235456D01*
G01X3779112Y1228831D02*
Y1236331D01*
G01X3783032D02*
Y1228831D01*
G01Y1232581D02*
X3779112D01*
G01X3790439Y1228831D02*
X3786705D01*
Y1236331D01*
X3790439D01*
G01X3788945Y1232706D02*
X3786705D01*
G01X3794019Y1228831D02*
Y1236331D01*
X3795885D01*
X3796632Y1235956D01*
X3797192Y1235456D01*
X3797659Y1234706D01*
X3798032Y1233831D01*
X3798125Y1232581D01*
X3798032Y1231331D01*
X3797659Y1230456D01*
X3797192Y1229706D01*
X3796632Y1229206D01*
X3795885Y1228831D01*
X3794019D01*
G01X3809205D02*
Y1236331D01*
X3811445D01*
X3812192Y1235956D01*
X3812752Y1235081D01*
X3812939Y1234081D01*
X3812752Y1233081D01*
X3812285Y1232331D01*
X3811445Y1231956D01*
X3809205D01*
G01X3818572Y1236331D02*
Y1228831D01*
G01X3816425Y1236331D02*
X3820719D01*
G01X3824112Y1228831D02*
Y1236331D01*
G01X3828032D02*
Y1228831D01*
G01Y1232581D02*
X3824112D01*
G01X3839952Y1236331D02*
X3842192D01*
G01X3841072D02*
Y1228831D01*
G01X3839952D02*
X3842192D01*
G01X3846612Y1229831D02*
X3847359Y1229206D01*
X3848199Y1228831D01*
X3848945D01*
X3849692Y1229206D01*
X3850252Y1229831D01*
X3850532Y1230706D01*
X3850345Y1231581D01*
X3849879Y1232331D01*
X3849039Y1232831D01*
X3847919Y1233081D01*
X3847265Y1233581D01*
X3846985Y1234456D01*
X3847172Y1235331D01*
X3847639Y1235956D01*
X3848292Y1236331D01*
X3848945D01*
X3849599Y1236081D01*
X3850159Y1235456D01*
G01X3863572Y1236331D02*
X3862825Y1236081D01*
X3862265Y1235456D01*
X3861892Y1234706D01*
X3861612Y1233706D01*
X3861519Y1232581D01*
X3861612Y1231456D01*
X3861892Y1230456D01*
X3862265Y1229706D01*
X3862825Y1229081D01*
X3863572Y1228831D01*
X3864319Y1229081D01*
X3864879Y1229706D01*
X3865252Y1230456D01*
X3865532Y1231456D01*
X3865625Y1232581D01*
X3865532Y1233706D01*
X3865252Y1234706D01*
X3864879Y1235456D01*
X3864319Y1236081D01*
X3863572Y1236331D01*
G01X3871072Y1228581D02*
X3870885Y1228706D01*
Y1228956D01*
X3871072Y1229081D01*
X3871259Y1228956D01*
Y1228706D01*
X3871072Y1228581D01*
G01X3876799Y1231956D02*
X3877452Y1232831D01*
X3878012Y1233331D01*
X3878759Y1233581D01*
X3879412Y1233331D01*
X3879879Y1232831D01*
X3880252Y1232081D01*
X3880345Y1231206D01*
X3880252Y1230456D01*
X3879879Y1229706D01*
X3879319Y1229081D01*
X3878665Y1228831D01*
X3877919Y1229081D01*
X3877265Y1229831D01*
X3876892Y1230956D01*
X3876799Y1232206D01*
X3876985Y1233831D01*
X3877265Y1234706D01*
X3877732Y1235581D01*
X3878385Y1236206D01*
X3879039Y1236331D01*
X3879692Y1236081D01*
X3880159Y1235456D01*
G01X3883645Y1228831D02*
Y1236331D01*
X3886072Y1230081D01*
X3888499Y1236331D01*
Y1228831D01*
G01X3891145D02*
Y1236331D01*
X3893572Y1230081D01*
X3895999Y1236331D01*
Y1228831D01*
G01X3906145D02*
Y1236331D01*
X3908572Y1230081D01*
X3910999Y1236331D01*
Y1228831D01*
G01X3917939D02*
X3914205D01*
Y1236331D01*
X3917939D01*
G01X3916445Y1232706D02*
X3914205D01*
G01X3923572Y1236331D02*
Y1228831D01*
G01X3921425Y1236331D02*
X3925719D01*
G01X3929205Y1228831D02*
Y1236331D01*
X3931539D01*
X3932285Y1235956D01*
X3932752Y1235456D01*
X3932939Y1234456D01*
X3932752Y1233456D01*
X3932192Y1232831D01*
X3931539Y1232456D01*
X3929205D01*
G01X3931539D02*
X3932939Y1228831D01*
G01X3937452Y1236331D02*
X3939692D01*
G01X3938572D02*
Y1228831D01*
G01X3937452D02*
X3939692D01*
G01X3948125Y1235706D02*
X3947565Y1236081D01*
X3946912Y1236331D01*
X3946165D01*
X3945325Y1235956D01*
X3944672Y1235331D01*
X3944205Y1234581D01*
X3943832Y1233331D01*
X3943739Y1232206D01*
X3943925Y1231081D01*
X3944205Y1230331D01*
X3944765Y1229581D01*
X3945419Y1229081D01*
X3946072Y1228831D01*
X3946725D01*
X3947379Y1229081D01*
X3947939Y1229456D01*
X3948405Y1229956D01*
G01X3959019Y1228831D02*
Y1236331D01*
X3960885D01*
X3961632Y1235956D01*
X3962192Y1235456D01*
X3962659Y1234706D01*
X3963032Y1233831D01*
X3963125Y1232581D01*
X3963032Y1231331D01*
X3962659Y1230456D01*
X3962192Y1229706D01*
X3961632Y1229206D01*
X3960885Y1228831D01*
X3959019D01*
G01X3966705D02*
Y1236331D01*
X3969039D01*
X3969785Y1235956D01*
X3970252Y1235456D01*
X3970439Y1234456D01*
X3970252Y1233456D01*
X3969692Y1232831D01*
X3969039Y1232456D01*
X3966705D01*
G01X3969039D02*
X3970439Y1228831D01*
G01X3974952Y1236331D02*
X3977192D01*
G01X3976072D02*
Y1228831D01*
G01X3974952D02*
X3977192D01*
G01X3981705Y1236331D02*
Y1228831D01*
X3985439D01*
G01X3989205Y1236331D02*
Y1228831D01*
X3992939D01*
G01X3998105Y1226331D02*
X3997172Y1227581D01*
X3996705Y1228831D01*
Y1233831D01*
X3997172Y1235081D01*
X3998105Y1236331D01*
G01X4006072D02*
X4005325Y1236081D01*
X4004765Y1235456D01*
X4004392Y1234706D01*
X4004112Y1233706D01*
X4004019Y1232581D01*
X4004112Y1231456D01*
X4004392Y1230456D01*
X4004765Y1229706D01*
X4005325Y1229081D01*
X4006072Y1228831D01*
X4006819Y1229081D01*
X4007379Y1229706D01*
X4007752Y1230456D01*
X4008032Y1231456D01*
X4008125Y1232581D01*
X4008032Y1233706D01*
X4007752Y1234706D01*
X4007379Y1235456D01*
X4006819Y1236081D01*
X4006072Y1236331D01*
G01X4013572Y1228581D02*
X4013385Y1228706D01*
Y1228956D01*
X4013572Y1229081D01*
X4013759Y1228956D01*
Y1228706D01*
X4013572Y1228581D01*
G01X4021072Y1236331D02*
X4020325Y1236081D01*
X4019765Y1235456D01*
X4019392Y1234706D01*
X4019112Y1233706D01*
X4019019Y1232581D01*
X4019112Y1231456D01*
X4019392Y1230456D01*
X4019765Y1229706D01*
X4020325Y1229081D01*
X4021072Y1228831D01*
X4021819Y1229081D01*
X4022379Y1229706D01*
X4022752Y1230456D01*
X4023032Y1231456D01*
X4023125Y1232581D01*
X4023032Y1233706D01*
X4022752Y1234706D01*
X4022379Y1235456D01*
X4021819Y1236081D01*
X4021072Y1236331D01*
G01X4026799Y1235081D02*
X4027359Y1235831D01*
X4028012Y1236206D01*
X4028759Y1236331D01*
X4029692Y1236081D01*
X4030345Y1235456D01*
X4030532Y1234706D01*
X4030439Y1233956D01*
X4030065Y1233331D01*
X4028199Y1232081D01*
X4027359Y1231206D01*
X4026799Y1229956D01*
X4026612Y1228831D01*
X4030532D01*
G01X4034019Y1230331D02*
X4034579Y1229456D01*
X4035325Y1228956D01*
X4036165Y1228831D01*
X4036912Y1228956D01*
X4037659Y1229581D01*
X4038125Y1230331D01*
X4038219Y1231081D01*
X4038032Y1231956D01*
X4037379Y1232581D01*
X4036725Y1232831D01*
X4035885D01*
G01X4036725D02*
X4037285Y1233206D01*
X4037752Y1233831D01*
X4037939Y1234581D01*
X4037752Y1235331D01*
X4037285Y1235956D01*
X4036445Y1236331D01*
X4035605Y1236206D01*
X4034765Y1235706D01*
G01X4041799Y1231956D02*
X4042452Y1232831D01*
X4043012Y1233331D01*
X4043759Y1233581D01*
X4044412Y1233331D01*
X4044879Y1232831D01*
X4045252Y1232081D01*
X4045345Y1231206D01*
X4045252Y1230456D01*
X4044879Y1229706D01*
X4044319Y1229081D01*
X4043665Y1228831D01*
X4042919Y1229081D01*
X4042265Y1229831D01*
X4041892Y1230956D01*
X4041799Y1232206D01*
X4041985Y1233831D01*
X4042265Y1234706D01*
X4042732Y1235581D01*
X4043385Y1236206D01*
X4044039Y1236331D01*
X4044692Y1236081D01*
X4045159Y1235456D01*
G01X4050232Y1234706D02*
X4050699Y1236331D01*
G01X4051912D02*
X4051445Y1234706D01*
G01X4059039Y1226331D02*
X4059972Y1227581D01*
X4060439Y1228831D01*
Y1233831D01*
X4059972Y1235081D01*
X4059039Y1236331D01*
G01X4066072Y1228581D02*
X4065885Y1228706D01*
Y1228956D01*
X4066072Y1229081D01*
X4066259Y1228956D01*
Y1228706D01*
X4066072Y1228581D01*
G01X3388905Y1287181D02*
Y1294681D01*
X3393199Y1287181D01*
Y1294681D01*
G01X3398552Y1287181D02*
X3397805Y1287306D01*
X3397152Y1287806D01*
X3396592Y1288556D01*
X3396219Y1289431D01*
X3396032Y1290431D01*
Y1291431D01*
X3396219Y1292431D01*
X3396592Y1293306D01*
X3397152Y1294056D01*
X3397805Y1294556D01*
X3398552Y1294681D01*
X3399299Y1294556D01*
X3399952Y1294056D01*
X3400512Y1293306D01*
X3400885Y1292431D01*
X3401072Y1291431D01*
Y1290431D01*
X3400885Y1289431D01*
X3400512Y1288556D01*
X3399952Y1287806D01*
X3399299Y1287306D01*
X3398552Y1287181D01*
G01X3403905D02*
Y1294681D01*
X3408199Y1287181D01*
Y1294681D01*
G01X3412339Y1289681D02*
X3414765D01*
G01X3418625Y1287181D02*
Y1294681D01*
X3421052Y1288431D01*
X3423479Y1294681D01*
Y1287181D01*
G01X3426219D02*
X3428552Y1294681D01*
X3430885Y1287181D01*
G01X3430045Y1289806D02*
X3427059D01*
G01X3434185Y1287181D02*
Y1294681D01*
X3436519D01*
X3437265Y1294306D01*
X3437732Y1293806D01*
X3437919Y1292806D01*
X3437732Y1291806D01*
X3437172Y1291181D01*
X3436519Y1290806D01*
X3434185D01*
G01X3436519D02*
X3437919Y1287181D01*
G01X3441499D02*
Y1294681D01*
G01X3445045D02*
X3441499Y1290056D01*
G01X3445605Y1287181D02*
X3443085Y1292181D01*
G01X3451052Y1286931D02*
X3450865Y1287056D01*
Y1287306D01*
X3451052Y1287431D01*
X3451239Y1287306D01*
Y1287056D01*
X3451052Y1286931D01*
G01Y1290306D02*
X3450865Y1290431D01*
Y1290681D01*
X3451052Y1290806D01*
X3451239Y1290681D01*
Y1290431D01*
X3451052Y1290306D01*
G01X3458552Y1294681D02*
Y1287181D01*
G01X3456405Y1294681D02*
X3460699D01*
G01X3464932D02*
X3467172D01*
G01X3466052D02*
Y1287181D01*
G01X3464932D02*
X3467172D01*
G01X3471405D02*
Y1294681D01*
X3475699Y1287181D01*
Y1294681D01*
G01X3486685D02*
Y1287181D01*
X3490419D01*
G01X3497919D02*
X3494185D01*
Y1294681D01*
X3497919D01*
G01X3496425Y1291056D02*
X3494185D01*
G01X3501219Y1287181D02*
X3503552Y1294681D01*
X3505885Y1287181D01*
G01X3505045Y1289806D02*
X3502059D01*
G01X3508999Y1287181D02*
Y1294681D01*
X3510865D01*
X3511612Y1294306D01*
X3512172Y1293806D01*
X3512639Y1293056D01*
X3513012Y1292181D01*
X3513105Y1290931D01*
X3513012Y1289681D01*
X3512639Y1288806D01*
X3512172Y1288056D01*
X3511612Y1287556D01*
X3510865Y1287181D01*
X3508999D01*
G01X3518552Y1286931D02*
X3518365Y1287056D01*
Y1287306D01*
X3518552Y1287431D01*
X3518739Y1287306D01*
Y1287056D01*
X3518552Y1286931D01*
G01Y1290306D02*
X3518365Y1290431D01*
Y1290681D01*
X3518552Y1290806D01*
X3518739Y1290681D01*
Y1290431D01*
X3518552Y1290306D01*
G01X3524185Y1287181D02*
Y1294681D01*
X3526519D01*
X3527265Y1294306D01*
X3527732Y1293806D01*
X3527919Y1292806D01*
X3527732Y1291806D01*
X3527172Y1291181D01*
X3526519Y1290806D01*
X3524185D01*
G01X3526519D02*
X3527919Y1287181D01*
G01X3535419D02*
X3531685D01*
Y1294681D01*
X3535419D01*
G01X3533925Y1291056D02*
X3531685D01*
G01X3543105Y1294056D02*
X3542545Y1294431D01*
X3541892Y1294681D01*
X3541145D01*
X3540305Y1294306D01*
X3539652Y1293681D01*
X3539185Y1292931D01*
X3538812Y1291681D01*
X3538719Y1290556D01*
X3538905Y1289431D01*
X3539185Y1288681D01*
X3539745Y1287931D01*
X3540399Y1287431D01*
X3541052Y1287181D01*
X3541705D01*
X3542359Y1287431D01*
X3542919Y1287806D01*
X3543385Y1288306D01*
G01X3548552Y1287181D02*
X3547805Y1287306D01*
X3547152Y1287806D01*
X3546592Y1288556D01*
X3546219Y1289431D01*
X3546032Y1290431D01*
Y1291431D01*
X3546219Y1292431D01*
X3546592Y1293306D01*
X3547152Y1294056D01*
X3547805Y1294556D01*
X3548552Y1294681D01*
X3549299Y1294556D01*
X3549952Y1294056D01*
X3550512Y1293306D01*
X3550885Y1292431D01*
X3551072Y1291431D01*
Y1290431D01*
X3550885Y1289431D01*
X3550512Y1288556D01*
X3549952Y1287806D01*
X3549299Y1287306D01*
X3548552Y1287181D01*
G01X3553625D02*
Y1294681D01*
X3556052Y1288431D01*
X3558479Y1294681D01*
Y1287181D01*
G01X3561125D02*
Y1294681D01*
X3563552Y1288431D01*
X3565979Y1294681D01*
Y1287181D01*
G01X3572919D02*
X3569185D01*
Y1294681D01*
X3572919D01*
G01X3571425Y1291056D02*
X3569185D01*
G01X3576405Y1287181D02*
Y1294681D01*
X3580699Y1287181D01*
Y1294681D01*
G01X3583999Y1287181D02*
Y1294681D01*
X3585865D01*
X3586612Y1294306D01*
X3587172Y1293806D01*
X3587639Y1293056D01*
X3588012Y1292181D01*
X3588105Y1290931D01*
X3588012Y1289681D01*
X3587639Y1288806D01*
X3587172Y1288056D01*
X3586612Y1287556D01*
X3585865Y1287181D01*
X3583999D01*
G01X3595419D02*
X3591685D01*
Y1294681D01*
X3595419D01*
G01X3593925Y1291056D02*
X3591685D01*
G01X3598999Y1287181D02*
Y1294681D01*
X3600865D01*
X3601612Y1294306D01*
X3602172Y1293806D01*
X3602639Y1293056D01*
X3603012Y1292181D01*
X3603105Y1290931D01*
X3603012Y1289681D01*
X3602639Y1288806D01*
X3602172Y1288056D01*
X3601612Y1287556D01*
X3600865Y1287181D01*
X3598999D01*
G01X3613999D02*
Y1294681D01*
X3615865D01*
X3616612Y1294306D01*
X3617172Y1293806D01*
X3617639Y1293056D01*
X3618012Y1292181D01*
X3618105Y1290931D01*
X3618012Y1289681D01*
X3617639Y1288806D01*
X3617172Y1288056D01*
X3616612Y1287556D01*
X3615865Y1287181D01*
X3613999D01*
G01X3621685D02*
Y1294681D01*
X3624019D01*
X3624765Y1294306D01*
X3625232Y1293806D01*
X3625419Y1292806D01*
X3625232Y1291806D01*
X3624672Y1291181D01*
X3624019Y1290806D01*
X3621685D01*
G01X3624019D02*
X3625419Y1287181D01*
G01X3629932Y1294681D02*
X3632172D01*
G01X3631052D02*
Y1287181D01*
G01X3629932D02*
X3632172D01*
G01X3636685Y1294681D02*
Y1287181D01*
X3640419D01*
G01X3644185Y1294681D02*
Y1287181D01*
X3647919D01*
G01X3659092Y1288181D02*
X3659839Y1287556D01*
X3660679Y1287181D01*
X3661425D01*
X3662172Y1287556D01*
X3662732Y1288181D01*
X3663012Y1289056D01*
X3662825Y1289931D01*
X3662359Y1290681D01*
X3661519Y1291181D01*
X3660399Y1291431D01*
X3659745Y1291931D01*
X3659465Y1292806D01*
X3659652Y1293681D01*
X3660119Y1294306D01*
X3660772Y1294681D01*
X3661425D01*
X3662079Y1294431D01*
X3662639Y1293806D01*
G01X3667432Y1294681D02*
X3669672D01*
G01X3668552D02*
Y1287181D01*
G01X3667432D02*
X3669672D01*
G01X3674279Y1294681D02*
X3677825D01*
X3674279Y1287181D01*
X3677825D01*
G01X3685419D02*
X3681685D01*
Y1294681D01*
X3685419D01*
G01X3683925Y1291056D02*
X3681685D01*
G01X3696779Y1287181D02*
Y1294681D01*
X3700325D01*
G01X3699019Y1291056D02*
X3696779D01*
G01X3706052Y1287181D02*
X3705305Y1287306D01*
X3704652Y1287806D01*
X3704092Y1288556D01*
X3703719Y1289431D01*
X3703532Y1290431D01*
Y1291431D01*
X3703719Y1292431D01*
X3704092Y1293306D01*
X3704652Y1294056D01*
X3705305Y1294556D01*
X3706052Y1294681D01*
X3706799Y1294556D01*
X3707452Y1294056D01*
X3708012Y1293306D01*
X3708385Y1292431D01*
X3708572Y1291431D01*
Y1290431D01*
X3708385Y1289431D01*
X3708012Y1288556D01*
X3707452Y1287806D01*
X3706799Y1287306D01*
X3706052Y1287181D01*
G01X3711685D02*
Y1294681D01*
X3714019D01*
X3714765Y1294306D01*
X3715232Y1293806D01*
X3715419Y1292806D01*
X3715232Y1291806D01*
X3714672Y1291181D01*
X3714019Y1290806D01*
X3711685D01*
G01X3714019D02*
X3715419Y1287181D01*
G01X3728552Y1294681D02*
X3727805Y1294431D01*
X3727245Y1293806D01*
X3726872Y1293056D01*
X3726592Y1292056D01*
X3726499Y1290931D01*
X3726592Y1289806D01*
X3726872Y1288806D01*
X3727245Y1288056D01*
X3727805Y1287431D01*
X3728552Y1287181D01*
X3729299Y1287431D01*
X3729859Y1288056D01*
X3730232Y1288806D01*
X3730512Y1289806D01*
X3730605Y1290931D01*
X3730512Y1292056D01*
X3730232Y1293056D01*
X3729859Y1293806D01*
X3729299Y1294431D01*
X3728552Y1294681D01*
G01X3736052Y1286931D02*
X3735865Y1287056D01*
Y1287306D01*
X3736052Y1287431D01*
X3736239Y1287306D01*
Y1287056D01*
X3736052Y1286931D01*
G01X3741499Y1288681D02*
X3742059Y1287806D01*
X3742805Y1287306D01*
X3743645Y1287181D01*
X3744392Y1287306D01*
X3745139Y1287931D01*
X3745605Y1288681D01*
X3745699Y1289431D01*
X3745512Y1290306D01*
X3744859Y1290931D01*
X3744205Y1291181D01*
X3743365D01*
G01X3744205D02*
X3744765Y1291556D01*
X3745232Y1292181D01*
X3745419Y1292931D01*
X3745232Y1293681D01*
X3744765Y1294306D01*
X3743925Y1294681D01*
X3743085Y1294556D01*
X3742245Y1294056D01*
G01X3749279Y1290306D02*
X3749932Y1291181D01*
X3750492Y1291681D01*
X3751239Y1291931D01*
X3751892Y1291681D01*
X3752359Y1291181D01*
X3752732Y1290431D01*
X3752825Y1289556D01*
X3752732Y1288806D01*
X3752359Y1288056D01*
X3751799Y1287431D01*
X3751145Y1287181D01*
X3750399Y1287431D01*
X3749745Y1288181D01*
X3749372Y1289306D01*
X3749279Y1290556D01*
X3749465Y1292181D01*
X3749745Y1293056D01*
X3750212Y1293931D01*
X3750865Y1294556D01*
X3751519Y1294681D01*
X3752172Y1294431D01*
X3752639Y1293806D01*
G01X3756125Y1287181D02*
Y1294681D01*
X3758552Y1288431D01*
X3760979Y1294681D01*
Y1287181D01*
G01X3763625D02*
Y1294681D01*
X3766052Y1288431D01*
X3768479Y1294681D01*
Y1287181D01*
G01X3779279D02*
Y1294681D01*
X3782825D01*
G01X3781519Y1291056D02*
X3779279D01*
G01X3787432Y1294681D02*
X3789672D01*
G01X3788552D02*
Y1287181D01*
G01X3787432D02*
X3789672D01*
G01X3793905D02*
Y1294681D01*
X3798199Y1287181D01*
Y1294681D01*
G01X3802432D02*
X3804672D01*
G01X3803552D02*
Y1287181D01*
G01X3802432D02*
X3804672D01*
G01X3809092Y1288181D02*
X3809839Y1287556D01*
X3810679Y1287181D01*
X3811425D01*
X3812172Y1287556D01*
X3812732Y1288181D01*
X3813012Y1289056D01*
X3812825Y1289931D01*
X3812359Y1290681D01*
X3811519Y1291181D01*
X3810399Y1291431D01*
X3809745Y1291931D01*
X3809465Y1292806D01*
X3809652Y1293681D01*
X3810119Y1294306D01*
X3810772Y1294681D01*
X3811425D01*
X3812079Y1294431D01*
X3812639Y1293806D01*
G01X3816592Y1287181D02*
Y1294681D01*
G01X3820512D02*
Y1287181D01*
G01Y1290931D02*
X3816592D01*
G01X3827919Y1287181D02*
X3824185D01*
Y1294681D01*
X3827919D01*
G01X3826425Y1291056D02*
X3824185D01*
G01X3831499Y1287181D02*
Y1294681D01*
X3833365D01*
X3834112Y1294306D01*
X3834672Y1293806D01*
X3835139Y1293056D01*
X3835512Y1292181D01*
X3835605Y1290931D01*
X3835512Y1289681D01*
X3835139Y1288806D01*
X3834672Y1288056D01*
X3834112Y1287556D01*
X3833365Y1287181D01*
X3831499D01*
G01X3846685D02*
Y1294681D01*
X3848925D01*
X3849672Y1294306D01*
X3850232Y1293431D01*
X3850419Y1292431D01*
X3850232Y1291431D01*
X3849765Y1290681D01*
X3848925Y1290306D01*
X3846685D01*
G01X3856052Y1294681D02*
Y1287181D01*
G01X3853905Y1294681D02*
X3858199D01*
G01X3861592Y1287181D02*
Y1294681D01*
G01X3865512D02*
Y1287181D01*
G01Y1290931D02*
X3861592D01*
G01X3877432Y1294681D02*
X3879672D01*
G01X3878552D02*
Y1287181D01*
G01X3877432D02*
X3879672D01*
G01X3884092Y1288181D02*
X3884839Y1287556D01*
X3885679Y1287181D01*
X3886425D01*
X3887172Y1287556D01*
X3887732Y1288181D01*
X3888012Y1289056D01*
X3887825Y1289931D01*
X3887359Y1290681D01*
X3886519Y1291181D01*
X3885399Y1291431D01*
X3884745Y1291931D01*
X3884465Y1292806D01*
X3884652Y1293681D01*
X3885119Y1294306D01*
X3885772Y1294681D01*
X3886425D01*
X3887079Y1294431D01*
X3887639Y1293806D01*
G01X3901052Y1294681D02*
X3900305Y1294431D01*
X3899745Y1293806D01*
X3899372Y1293056D01*
X3899092Y1292056D01*
X3898999Y1290931D01*
X3899092Y1289806D01*
X3899372Y1288806D01*
X3899745Y1288056D01*
X3900305Y1287431D01*
X3901052Y1287181D01*
X3901799Y1287431D01*
X3902359Y1288056D01*
X3902732Y1288806D01*
X3903012Y1289806D01*
X3903105Y1290931D01*
X3903012Y1292056D01*
X3902732Y1293056D01*
X3902359Y1293806D01*
X3901799Y1294431D01*
X3901052Y1294681D01*
G01X3908552Y1286931D02*
X3908365Y1287056D01*
Y1287306D01*
X3908552Y1287431D01*
X3908739Y1287306D01*
Y1287056D01*
X3908552Y1286931D01*
G01X3917172Y1287181D02*
Y1294681D01*
X3913719Y1289306D01*
X3918385D01*
G01X3921499Y1288306D02*
X3922059Y1287681D01*
X3922712Y1287306D01*
X3923552Y1287181D01*
X3924392Y1287431D01*
X3925045Y1287931D01*
X3925512Y1288806D01*
X3925605Y1289806D01*
X3925419Y1290806D01*
X3924952Y1291431D01*
X3924299Y1291931D01*
X3923645Y1292056D01*
X3922992Y1291931D01*
X3922152Y1291431D01*
X3922432Y1294681D01*
X3924952D01*
G01X3928625Y1287181D02*
Y1294681D01*
X3931052Y1288431D01*
X3933479Y1294681D01*
Y1287181D01*
G01X3936125D02*
Y1294681D01*
X3938552Y1288431D01*
X3940979Y1294681D01*
Y1287181D01*
G01X3951125D02*
Y1294681D01*
X3953552Y1288431D01*
X3955979Y1294681D01*
Y1287181D01*
G01X3962919D02*
X3959185D01*
Y1294681D01*
X3962919D01*
G01X3961425Y1291056D02*
X3959185D01*
G01X3968552Y1294681D02*
Y1287181D01*
G01X3966405Y1294681D02*
X3970699D01*
G01X3974185Y1287181D02*
Y1294681D01*
X3976519D01*
X3977265Y1294306D01*
X3977732Y1293806D01*
X3977919Y1292806D01*
X3977732Y1291806D01*
X3977172Y1291181D01*
X3976519Y1290806D01*
X3974185D01*
G01X3976519D02*
X3977919Y1287181D01*
G01X3982432Y1294681D02*
X3984672D01*
G01X3983552D02*
Y1287181D01*
G01X3982432D02*
X3984672D01*
G01X3993105Y1294056D02*
X3992545Y1294431D01*
X3991892Y1294681D01*
X3991145D01*
X3990305Y1294306D01*
X3989652Y1293681D01*
X3989185Y1292931D01*
X3988812Y1291681D01*
X3988719Y1290556D01*
X3988905Y1289431D01*
X3989185Y1288681D01*
X3989745Y1287931D01*
X3990399Y1287431D01*
X3991052Y1287181D01*
X3991705D01*
X3992359Y1287431D01*
X3992919Y1287806D01*
X3993385Y1288306D01*
G01X4003999Y1287181D02*
Y1294681D01*
X4005865D01*
X4006612Y1294306D01*
X4007172Y1293806D01*
X4007639Y1293056D01*
X4008012Y1292181D01*
X4008105Y1290931D01*
X4008012Y1289681D01*
X4007639Y1288806D01*
X4007172Y1288056D01*
X4006612Y1287556D01*
X4005865Y1287181D01*
X4003999D01*
G01X4011685D02*
Y1294681D01*
X4014019D01*
X4014765Y1294306D01*
X4015232Y1293806D01*
X4015419Y1292806D01*
X4015232Y1291806D01*
X4014672Y1291181D01*
X4014019Y1290806D01*
X4011685D01*
G01X4014019D02*
X4015419Y1287181D01*
G01X4019932Y1294681D02*
X4022172D01*
G01X4021052D02*
Y1287181D01*
G01X4019932D02*
X4022172D01*
G01X4026685Y1294681D02*
Y1287181D01*
X4030419D01*
G01X4034185Y1294681D02*
Y1287181D01*
X4037919D01*
G01X4043085Y1284681D02*
X4042152Y1285931D01*
X4041685Y1287181D01*
Y1292181D01*
X4042152Y1293431D01*
X4043085Y1294681D01*
G01X4051052D02*
X4050305Y1294431D01*
X4049745Y1293806D01*
X4049372Y1293056D01*
X4049092Y1292056D01*
X4048999Y1290931D01*
X4049092Y1289806D01*
X4049372Y1288806D01*
X4049745Y1288056D01*
X4050305Y1287431D01*
X4051052Y1287181D01*
X4051799Y1287431D01*
X4052359Y1288056D01*
X4052732Y1288806D01*
X4053012Y1289806D01*
X4053105Y1290931D01*
X4053012Y1292056D01*
X4052732Y1293056D01*
X4052359Y1293806D01*
X4051799Y1294431D01*
X4051052Y1294681D01*
G01X4058552Y1286931D02*
X4058365Y1287056D01*
Y1287306D01*
X4058552Y1287431D01*
X4058739Y1287306D01*
Y1287056D01*
X4058552Y1286931D01*
G01X4066052Y1294681D02*
X4065305Y1294431D01*
X4064745Y1293806D01*
X4064372Y1293056D01*
X4064092Y1292056D01*
X4063999Y1290931D01*
X4064092Y1289806D01*
X4064372Y1288806D01*
X4064745Y1288056D01*
X4065305Y1287431D01*
X4066052Y1287181D01*
X4066799Y1287431D01*
X4067359Y1288056D01*
X4067732Y1288806D01*
X4068012Y1289806D01*
X4068105Y1290931D01*
X4068012Y1292056D01*
X4067732Y1293056D01*
X4067359Y1293806D01*
X4066799Y1294431D01*
X4066052Y1294681D01*
G01X4073552Y1287181D02*
Y1294681D01*
X4072432Y1293181D01*
G01Y1287181D02*
X4074672D01*
G01X4080865D02*
X4081052Y1288806D01*
X4081332Y1290181D01*
X4081705Y1291431D01*
X4082172Y1292806D01*
X4082919Y1294681D01*
X4079185D01*
G01X4088365Y1287181D02*
X4088552Y1288806D01*
X4088832Y1290181D01*
X4089205Y1291431D01*
X4089672Y1292806D01*
X4090419Y1294681D01*
X4086685D01*
G01X4095212Y1293056D02*
X4095679Y1294681D01*
G01X4096892D02*
X4096425Y1293056D01*
G01X4104019Y1284681D02*
X4104952Y1285931D01*
X4105419Y1287181D01*
Y1292181D01*
X4104952Y1293431D01*
X4104019Y1294681D01*
G01X4111052Y1286931D02*
X4110865Y1287056D01*
Y1287306D01*
X4111052Y1287431D01*
X4111239Y1287306D01*
Y1287056D01*
X4111052Y1286931D01*
G01X3417670Y1262401D02*
X3418417Y1261776D01*
X3419257Y1261401D01*
X3420003D01*
X3420750Y1261776D01*
X3421310Y1262401D01*
X3421590Y1263276D01*
X3421403Y1264151D01*
X3420937Y1264901D01*
X3420097Y1265401D01*
X3418977Y1265651D01*
X3418323Y1266151D01*
X3418043Y1267026D01*
X3418230Y1267901D01*
X3418697Y1268526D01*
X3419350Y1268901D01*
X3420003D01*
X3420657Y1268651D01*
X3421217Y1268026D01*
G01X3426010Y1268901D02*
X3428250D01*
G01X3427130D02*
Y1261401D01*
G01X3426010D02*
X3428250D01*
G01X3432763Y1268901D02*
Y1261401D01*
X3436497D01*
G01X3439797Y1268901D02*
X3442130Y1261401D01*
X3444463Y1268901D01*
G01X3451497Y1261401D02*
X3447763D01*
Y1268901D01*
X3451497D01*
G01X3450003Y1265276D02*
X3447763D01*
G01X3455263Y1261401D02*
Y1268901D01*
X3457597D01*
X3458343Y1268526D01*
X3458810Y1268026D01*
X3458997Y1267026D01*
X3458810Y1266026D01*
X3458250Y1265401D01*
X3457597Y1265026D01*
X3455263D01*
G01X3457597D02*
X3458997Y1261401D01*
G01X3464163Y1258901D02*
X3463230Y1260151D01*
X3462763Y1261401D01*
Y1266401D01*
X3463230Y1267651D01*
X3464163Y1268901D01*
G01X3471010D02*
X3473250D01*
G01X3472130D02*
Y1261401D01*
G01X3471010D02*
X3473250D01*
G01X3477203D02*
Y1268901D01*
X3479630Y1262651D01*
X3482057Y1268901D01*
Y1261401D01*
G01X3484703D02*
Y1268901D01*
X3487130Y1262651D01*
X3489557Y1268901D01*
Y1261401D01*
G01X3496497D02*
X3492763D01*
Y1268901D01*
X3496497D01*
G01X3495003Y1265276D02*
X3492763D01*
G01X3500263Y1261401D02*
Y1268901D01*
X3502597D01*
X3503343Y1268526D01*
X3503810Y1268026D01*
X3503997Y1267026D01*
X3503810Y1266026D01*
X3503250Y1265401D01*
X3502597Y1265026D01*
X3500263D01*
G01X3502597D02*
X3503997Y1261401D01*
G01X3507670Y1262401D02*
X3508417Y1261776D01*
X3509257Y1261401D01*
X3510003D01*
X3510750Y1261776D01*
X3511310Y1262401D01*
X3511590Y1263276D01*
X3511403Y1264151D01*
X3510937Y1264901D01*
X3510097Y1265401D01*
X3508977Y1265651D01*
X3508323Y1266151D01*
X3508043Y1267026D01*
X3508230Y1267901D01*
X3508697Y1268526D01*
X3509350Y1268901D01*
X3510003D01*
X3510657Y1268651D01*
X3511217Y1268026D01*
G01X3516010Y1268901D02*
X3518250D01*
G01X3517130D02*
Y1261401D01*
G01X3516010D02*
X3518250D01*
G01X3524630D02*
X3523883Y1261526D01*
X3523230Y1262026D01*
X3522670Y1262776D01*
X3522297Y1263651D01*
X3522110Y1264651D01*
Y1265651D01*
X3522297Y1266651D01*
X3522670Y1267526D01*
X3523230Y1268276D01*
X3523883Y1268776D01*
X3524630Y1268901D01*
X3525377Y1268776D01*
X3526030Y1268276D01*
X3526590Y1267526D01*
X3526963Y1266651D01*
X3527150Y1265651D01*
Y1264651D01*
X3526963Y1263651D01*
X3526590Y1262776D01*
X3526030Y1262026D01*
X3525377Y1261526D01*
X3524630Y1261401D01*
G01X3529983D02*
Y1268901D01*
X3534277Y1261401D01*
Y1268901D01*
G01X3540097Y1258901D02*
X3541030Y1260151D01*
X3541497Y1261401D01*
Y1266401D01*
X3541030Y1267651D01*
X3540097Y1268901D01*
G01X3547130Y1261151D02*
X3546943Y1261276D01*
Y1261526D01*
X3547130Y1261651D01*
X3547317Y1261526D01*
Y1261276D01*
X3547130Y1261151D01*
G01Y1264526D02*
X3546943Y1264651D01*
Y1264901D01*
X3547130Y1265026D01*
X3547317Y1264901D01*
Y1264651D01*
X3547130Y1264526D01*
G01X3552763Y1261401D02*
Y1268901D01*
X3555097D01*
X3555843Y1268526D01*
X3556310Y1268026D01*
X3556497Y1267026D01*
X3556310Y1266026D01*
X3555750Y1265401D01*
X3555097Y1265026D01*
X3552763D01*
G01X3555097D02*
X3556497Y1261401D01*
G01X3563997D02*
X3560263D01*
Y1268901D01*
X3563997D01*
G01X3562503Y1265276D02*
X3560263D01*
G01X3571683Y1268276D02*
X3571123Y1268651D01*
X3570470Y1268901D01*
X3569723D01*
X3568883Y1268526D01*
X3568230Y1267901D01*
X3567763Y1267151D01*
X3567390Y1265901D01*
X3567297Y1264776D01*
X3567483Y1263651D01*
X3567763Y1262901D01*
X3568323Y1262151D01*
X3568977Y1261651D01*
X3569630Y1261401D01*
X3570283D01*
X3570937Y1261651D01*
X3571497Y1262026D01*
X3571963Y1262526D01*
G01X3577130Y1261401D02*
X3576383Y1261526D01*
X3575730Y1262026D01*
X3575170Y1262776D01*
X3574797Y1263651D01*
X3574610Y1264651D01*
Y1265651D01*
X3574797Y1266651D01*
X3575170Y1267526D01*
X3575730Y1268276D01*
X3576383Y1268776D01*
X3577130Y1268901D01*
X3577877Y1268776D01*
X3578530Y1268276D01*
X3579090Y1267526D01*
X3579463Y1266651D01*
X3579650Y1265651D01*
Y1264651D01*
X3579463Y1263651D01*
X3579090Y1262776D01*
X3578530Y1262026D01*
X3577877Y1261526D01*
X3577130Y1261401D01*
G01X3582203D02*
Y1268901D01*
X3584630Y1262651D01*
X3587057Y1268901D01*
Y1261401D01*
G01X3589703D02*
Y1268901D01*
X3592130Y1262651D01*
X3594557Y1268901D01*
Y1261401D01*
G01X3601497D02*
X3597763D01*
Y1268901D01*
X3601497D01*
G01X3600003Y1265276D02*
X3597763D01*
G01X3604983Y1261401D02*
Y1268901D01*
X3609277Y1261401D01*
Y1268901D01*
G01X3612577Y1261401D02*
Y1268901D01*
X3614443D01*
X3615190Y1268526D01*
X3615750Y1268026D01*
X3616217Y1267276D01*
X3616590Y1266401D01*
X3616683Y1265151D01*
X3616590Y1263901D01*
X3616217Y1263026D01*
X3615750Y1262276D01*
X3615190Y1261776D01*
X3614443Y1261401D01*
X3612577D01*
G01X3623997D02*
X3620263D01*
Y1268901D01*
X3623997D01*
G01X3622503Y1265276D02*
X3620263D01*
G01X3627577Y1261401D02*
Y1268901D01*
X3629443D01*
X3630190Y1268526D01*
X3630750Y1268026D01*
X3631217Y1267276D01*
X3631590Y1266401D01*
X3631683Y1265151D01*
X3631590Y1263901D01*
X3631217Y1263026D01*
X3630750Y1262276D01*
X3630190Y1261776D01*
X3629443Y1261401D01*
X3627577D01*
G01X3642577D02*
Y1268901D01*
X3644443D01*
X3645190Y1268526D01*
X3645750Y1268026D01*
X3646217Y1267276D01*
X3646590Y1266401D01*
X3646683Y1265151D01*
X3646590Y1263901D01*
X3646217Y1263026D01*
X3645750Y1262276D01*
X3645190Y1261776D01*
X3644443Y1261401D01*
X3642577D01*
G01X3650263D02*
Y1268901D01*
X3652597D01*
X3653343Y1268526D01*
X3653810Y1268026D01*
X3653997Y1267026D01*
X3653810Y1266026D01*
X3653250Y1265401D01*
X3652597Y1265026D01*
X3650263D01*
G01X3652597D02*
X3653997Y1261401D01*
G01X3658510Y1268901D02*
X3660750D01*
G01X3659630D02*
Y1261401D01*
G01X3658510D02*
X3660750D01*
G01X3665263Y1268901D02*
Y1261401D01*
X3668997D01*
G01X3672763Y1268901D02*
Y1261401D01*
X3676497D01*
G01X3687670Y1262401D02*
X3688417Y1261776D01*
X3689257Y1261401D01*
X3690003D01*
X3690750Y1261776D01*
X3691310Y1262401D01*
X3691590Y1263276D01*
X3691403Y1264151D01*
X3690937Y1264901D01*
X3690097Y1265401D01*
X3688977Y1265651D01*
X3688323Y1266151D01*
X3688043Y1267026D01*
X3688230Y1267901D01*
X3688697Y1268526D01*
X3689350Y1268901D01*
X3690003D01*
X3690657Y1268651D01*
X3691217Y1268026D01*
G01X3696010Y1268901D02*
X3698250D01*
G01X3697130D02*
Y1261401D01*
G01X3696010D02*
X3698250D01*
G01X3702857Y1268901D02*
X3706403D01*
X3702857Y1261401D01*
X3706403D01*
G01X3713997D02*
X3710263D01*
Y1268901D01*
X3713997D01*
G01X3712503Y1265276D02*
X3710263D01*
G01X3725357Y1261401D02*
Y1268901D01*
X3728903D01*
G01X3727597Y1265276D02*
X3725357D01*
G01X3734630Y1261401D02*
X3733883Y1261526D01*
X3733230Y1262026D01*
X3732670Y1262776D01*
X3732297Y1263651D01*
X3732110Y1264651D01*
Y1265651D01*
X3732297Y1266651D01*
X3732670Y1267526D01*
X3733230Y1268276D01*
X3733883Y1268776D01*
X3734630Y1268901D01*
X3735377Y1268776D01*
X3736030Y1268276D01*
X3736590Y1267526D01*
X3736963Y1266651D01*
X3737150Y1265651D01*
Y1264651D01*
X3736963Y1263651D01*
X3736590Y1262776D01*
X3736030Y1262026D01*
X3735377Y1261526D01*
X3734630Y1261401D01*
G01X3740263D02*
Y1268901D01*
X3742597D01*
X3743343Y1268526D01*
X3743810Y1268026D01*
X3743997Y1267026D01*
X3743810Y1266026D01*
X3743250Y1265401D01*
X3742597Y1265026D01*
X3740263D01*
G01X3742597D02*
X3743997Y1261401D01*
G01X3757130Y1268901D02*
X3756383Y1268651D01*
X3755823Y1268026D01*
X3755450Y1267276D01*
X3755170Y1266276D01*
X3755077Y1265151D01*
X3755170Y1264026D01*
X3755450Y1263026D01*
X3755823Y1262276D01*
X3756383Y1261651D01*
X3757130Y1261401D01*
X3757877Y1261651D01*
X3758437Y1262276D01*
X3758810Y1263026D01*
X3759090Y1264026D01*
X3759183Y1265151D01*
X3759090Y1266276D01*
X3758810Y1267276D01*
X3758437Y1268026D01*
X3757877Y1268651D01*
X3757130Y1268901D01*
G01X3764630Y1261151D02*
X3764443Y1261276D01*
Y1261526D01*
X3764630Y1261651D01*
X3764817Y1261526D01*
Y1261276D01*
X3764630Y1261151D01*
G01X3770077Y1262901D02*
X3770637Y1262026D01*
X3771383Y1261526D01*
X3772223Y1261401D01*
X3772970Y1261526D01*
X3773717Y1262151D01*
X3774183Y1262901D01*
X3774277Y1263651D01*
X3774090Y1264526D01*
X3773437Y1265151D01*
X3772783Y1265401D01*
X3771943D01*
G01X3772783D02*
X3773343Y1265776D01*
X3773810Y1266401D01*
X3773997Y1267151D01*
X3773810Y1267901D01*
X3773343Y1268526D01*
X3772503Y1268901D01*
X3771663Y1268776D01*
X3770823Y1268276D01*
G01X3777857Y1264526D02*
X3778510Y1265401D01*
X3779070Y1265901D01*
X3779817Y1266151D01*
X3780470Y1265901D01*
X3780937Y1265401D01*
X3781310Y1264651D01*
X3781403Y1263776D01*
X3781310Y1263026D01*
X3780937Y1262276D01*
X3780377Y1261651D01*
X3779723Y1261401D01*
X3778977Y1261651D01*
X3778323Y1262401D01*
X3777950Y1263526D01*
X3777857Y1264776D01*
X3778043Y1266401D01*
X3778323Y1267276D01*
X3778790Y1268151D01*
X3779443Y1268776D01*
X3780097Y1268901D01*
X3780750Y1268651D01*
X3781217Y1268026D01*
G01X3784703Y1261401D02*
Y1268901D01*
X3787130Y1262651D01*
X3789557Y1268901D01*
Y1261401D01*
G01X3792203D02*
Y1268901D01*
X3794630Y1262651D01*
X3797057Y1268901D01*
Y1261401D01*
G01X3807857D02*
Y1268901D01*
X3811403D01*
G01X3810097Y1265276D02*
X3807857D01*
G01X3816010Y1268901D02*
X3818250D01*
G01X3817130D02*
Y1261401D01*
G01X3816010D02*
X3818250D01*
G01X3822483D02*
Y1268901D01*
X3826777Y1261401D01*
Y1268901D01*
G01X3831010D02*
X3833250D01*
G01X3832130D02*
Y1261401D01*
G01X3831010D02*
X3833250D01*
G01X3837670Y1262401D02*
X3838417Y1261776D01*
X3839257Y1261401D01*
X3840003D01*
X3840750Y1261776D01*
X3841310Y1262401D01*
X3841590Y1263276D01*
X3841403Y1264151D01*
X3840937Y1264901D01*
X3840097Y1265401D01*
X3838977Y1265651D01*
X3838323Y1266151D01*
X3838043Y1267026D01*
X3838230Y1267901D01*
X3838697Y1268526D01*
X3839350Y1268901D01*
X3840003D01*
X3840657Y1268651D01*
X3841217Y1268026D01*
G01X3845170Y1261401D02*
Y1268901D01*
G01X3849090D02*
Y1261401D01*
G01Y1265151D02*
X3845170D01*
G01X3856497Y1261401D02*
X3852763D01*
Y1268901D01*
X3856497D01*
G01X3855003Y1265276D02*
X3852763D01*
G01X3860077Y1261401D02*
Y1268901D01*
X3861943D01*
X3862690Y1268526D01*
X3863250Y1268026D01*
X3863717Y1267276D01*
X3864090Y1266401D01*
X3864183Y1265151D01*
X3864090Y1263901D01*
X3863717Y1263026D01*
X3863250Y1262276D01*
X3862690Y1261776D01*
X3861943Y1261401D01*
X3860077D01*
G01X3875263D02*
Y1268901D01*
X3877503D01*
X3878250Y1268526D01*
X3878810Y1267651D01*
X3878997Y1266651D01*
X3878810Y1265651D01*
X3878343Y1264901D01*
X3877503Y1264526D01*
X3875263D01*
G01X3884630Y1268901D02*
Y1261401D01*
G01X3882483Y1268901D02*
X3886777D01*
G01X3890170Y1261401D02*
Y1268901D01*
G01X3894090D02*
Y1261401D01*
G01Y1265151D02*
X3890170D01*
G01X3906010Y1268901D02*
X3908250D01*
G01X3907130D02*
Y1261401D01*
G01X3906010D02*
X3908250D01*
G01X3912670Y1262401D02*
X3913417Y1261776D01*
X3914257Y1261401D01*
X3915003D01*
X3915750Y1261776D01*
X3916310Y1262401D01*
X3916590Y1263276D01*
X3916403Y1264151D01*
X3915937Y1264901D01*
X3915097Y1265401D01*
X3913977Y1265651D01*
X3913323Y1266151D01*
X3913043Y1267026D01*
X3913230Y1267901D01*
X3913697Y1268526D01*
X3914350Y1268901D01*
X3915003D01*
X3915657Y1268651D01*
X3916217Y1268026D01*
G01X3929630Y1268901D02*
X3928883Y1268651D01*
X3928323Y1268026D01*
X3927950Y1267276D01*
X3927670Y1266276D01*
X3927577Y1265151D01*
X3927670Y1264026D01*
X3927950Y1263026D01*
X3928323Y1262276D01*
X3928883Y1261651D01*
X3929630Y1261401D01*
X3930377Y1261651D01*
X3930937Y1262276D01*
X3931310Y1263026D01*
X3931590Y1264026D01*
X3931683Y1265151D01*
X3931590Y1266276D01*
X3931310Y1267276D01*
X3930937Y1268026D01*
X3930377Y1268651D01*
X3929630Y1268901D01*
G01X3937130Y1261151D02*
X3936943Y1261276D01*
Y1261526D01*
X3937130Y1261651D01*
X3937317Y1261526D01*
Y1261276D01*
X3937130Y1261151D01*
G01X3945750Y1261401D02*
Y1268901D01*
X3942297Y1263526D01*
X3946963D01*
G01X3950077Y1262526D02*
X3950637Y1261901D01*
X3951290Y1261526D01*
X3952130Y1261401D01*
X3952970Y1261651D01*
X3953623Y1262151D01*
X3954090Y1263026D01*
X3954183Y1264026D01*
X3953997Y1265026D01*
X3953530Y1265651D01*
X3952877Y1266151D01*
X3952223Y1266276D01*
X3951570Y1266151D01*
X3950730Y1265651D01*
X3951010Y1268901D01*
X3953530D01*
G01X3957203Y1261401D02*
Y1268901D01*
X3959630Y1262651D01*
X3962057Y1268901D01*
Y1261401D01*
G01X3964703D02*
Y1268901D01*
X3967130Y1262651D01*
X3969557Y1268901D01*
Y1261401D01*
G01X3979703D02*
Y1268901D01*
X3982130Y1262651D01*
X3984557Y1268901D01*
Y1261401D01*
G01X3991497D02*
X3987763D01*
Y1268901D01*
X3991497D01*
G01X3990003Y1265276D02*
X3987763D01*
G01X3997130Y1268901D02*
Y1261401D01*
G01X3994983Y1268901D02*
X3999277D01*
G01X4002763Y1261401D02*
Y1268901D01*
X4005097D01*
X4005843Y1268526D01*
X4006310Y1268026D01*
X4006497Y1267026D01*
X4006310Y1266026D01*
X4005750Y1265401D01*
X4005097Y1265026D01*
X4002763D01*
G01X4005097D02*
X4006497Y1261401D01*
G01X4011010Y1268901D02*
X4013250D01*
G01X4012130D02*
Y1261401D01*
G01X4011010D02*
X4013250D01*
G01X4021683Y1268276D02*
X4021123Y1268651D01*
X4020470Y1268901D01*
X4019723D01*
X4018883Y1268526D01*
X4018230Y1267901D01*
X4017763Y1267151D01*
X4017390Y1265901D01*
X4017297Y1264776D01*
X4017483Y1263651D01*
X4017763Y1262901D01*
X4018323Y1262151D01*
X4018977Y1261651D01*
X4019630Y1261401D01*
X4020283D01*
X4020937Y1261651D01*
X4021497Y1262026D01*
X4021963Y1262526D01*
G01X4032577Y1261401D02*
Y1268901D01*
X4034443D01*
X4035190Y1268526D01*
X4035750Y1268026D01*
X4036217Y1267276D01*
X4036590Y1266401D01*
X4036683Y1265151D01*
X4036590Y1263901D01*
X4036217Y1263026D01*
X4035750Y1262276D01*
X4035190Y1261776D01*
X4034443Y1261401D01*
X4032577D01*
G01X4040263D02*
Y1268901D01*
X4042597D01*
X4043343Y1268526D01*
X4043810Y1268026D01*
X4043997Y1267026D01*
X4043810Y1266026D01*
X4043250Y1265401D01*
X4042597Y1265026D01*
X4040263D01*
G01X4042597D02*
X4043997Y1261401D01*
G01X4048510Y1268901D02*
X4050750D01*
G01X4049630D02*
Y1261401D01*
G01X4048510D02*
X4050750D01*
G01X4055263Y1268901D02*
Y1261401D01*
X4058997D01*
G01X4062763Y1268901D02*
Y1261401D01*
X4066497D01*
G01X4071663Y1258901D02*
X4070730Y1260151D01*
X4070263Y1261401D01*
Y1266401D01*
X4070730Y1267651D01*
X4071663Y1268901D01*
G01X4079630D02*
X4078883Y1268651D01*
X4078323Y1268026D01*
X4077950Y1267276D01*
X4077670Y1266276D01*
X4077577Y1265151D01*
X4077670Y1264026D01*
X4077950Y1263026D01*
X4078323Y1262276D01*
X4078883Y1261651D01*
X4079630Y1261401D01*
X4080377Y1261651D01*
X4080937Y1262276D01*
X4081310Y1263026D01*
X4081590Y1264026D01*
X4081683Y1265151D01*
X4081590Y1266276D01*
X4081310Y1267276D01*
X4080937Y1268026D01*
X4080377Y1268651D01*
X4079630Y1268901D01*
G01X4087130Y1261151D02*
X4086943Y1261276D01*
Y1261526D01*
X4087130Y1261651D01*
X4087317Y1261526D01*
Y1261276D01*
X4087130Y1261151D01*
G01X4094630Y1268901D02*
X4093883Y1268651D01*
X4093323Y1268026D01*
X4092950Y1267276D01*
X4092670Y1266276D01*
X4092577Y1265151D01*
X4092670Y1264026D01*
X4092950Y1263026D01*
X4093323Y1262276D01*
X4093883Y1261651D01*
X4094630Y1261401D01*
X4095377Y1261651D01*
X4095937Y1262276D01*
X4096310Y1263026D01*
X4096590Y1264026D01*
X4096683Y1265151D01*
X4096590Y1266276D01*
X4096310Y1267276D01*
X4095937Y1268026D01*
X4095377Y1268651D01*
X4094630Y1268901D01*
G01X4102130Y1261401D02*
Y1268901D01*
X4101010Y1267401D01*
G01Y1261401D02*
X4103250D01*
G01X4109443D02*
X4109630Y1263026D01*
X4109910Y1264401D01*
X4110283Y1265651D01*
X4110750Y1267026D01*
X4111497Y1268901D01*
X4107763D01*
G01X4116943Y1261401D02*
X4117130Y1263026D01*
X4117410Y1264401D01*
X4117783Y1265651D01*
X4118250Y1267026D01*
X4118997Y1268901D01*
X4115263D01*
G01X4123790Y1267276D02*
X4124257Y1268901D01*
G01X4125470D02*
X4125003Y1267276D01*
G01X4132597Y1258901D02*
X4133530Y1260151D01*
X4133997Y1261401D01*
Y1266401D01*
X4133530Y1267651D01*
X4132597Y1268901D01*
G01X4139630Y1261151D02*
X4139443Y1261276D01*
Y1261526D01*
X4139630Y1261651D01*
X4139817Y1261526D01*
Y1261276D01*
X4139630Y1261151D01*
G01X3422855Y1280256D02*
X3422295Y1280631D01*
X3421642Y1280881D01*
X3420895D01*
X3420055Y1280506D01*
X3419402Y1279881D01*
X3418935Y1279131D01*
X3418562Y1277881D01*
X3418469Y1276756D01*
X3418655Y1275631D01*
X3418935Y1274881D01*
X3419495Y1274131D01*
X3420149Y1273631D01*
X3420802Y1273381D01*
X3421455D01*
X3422109Y1273631D01*
X3422669Y1274006D01*
X3423135Y1274506D01*
G01X3428302Y1273381D02*
X3427555Y1273506D01*
X3426902Y1274006D01*
X3426342Y1274756D01*
X3425969Y1275631D01*
X3425782Y1276631D01*
Y1277631D01*
X3425969Y1278631D01*
X3426342Y1279506D01*
X3426902Y1280256D01*
X3427555Y1280756D01*
X3428302Y1280881D01*
X3429049Y1280756D01*
X3429702Y1280256D01*
X3430262Y1279506D01*
X3430635Y1278631D01*
X3430822Y1277631D01*
Y1276631D01*
X3430635Y1275631D01*
X3430262Y1274756D01*
X3429702Y1274006D01*
X3429049Y1273506D01*
X3428302Y1273381D01*
G01X3433935D02*
Y1280881D01*
X3436175D01*
X3436922Y1280506D01*
X3437482Y1279631D01*
X3437669Y1278631D01*
X3437482Y1277631D01*
X3437015Y1276881D01*
X3436175Y1276506D01*
X3433935D01*
G01X3441435Y1273381D02*
Y1280881D01*
X3443675D01*
X3444422Y1280506D01*
X3444982Y1279631D01*
X3445169Y1278631D01*
X3444982Y1277631D01*
X3444515Y1276881D01*
X3443675Y1276506D01*
X3441435D01*
G01X3452669Y1273381D02*
X3448935D01*
Y1280881D01*
X3452669D01*
G01X3451175Y1277256D02*
X3448935D01*
G01X3456435Y1273381D02*
Y1280881D01*
X3458769D01*
X3459515Y1280506D01*
X3459982Y1280006D01*
X3460169Y1279006D01*
X3459982Y1278006D01*
X3459422Y1277381D01*
X3458769Y1277006D01*
X3456435D01*
G01X3458769D02*
X3460169Y1273381D01*
G01X3473302D02*
X3472555Y1273506D01*
X3471902Y1274006D01*
X3471342Y1274756D01*
X3470969Y1275631D01*
X3470782Y1276631D01*
Y1277631D01*
X3470969Y1278631D01*
X3471342Y1279506D01*
X3471902Y1280256D01*
X3472555Y1280756D01*
X3473302Y1280881D01*
X3474049Y1280756D01*
X3474702Y1280256D01*
X3475262Y1279506D01*
X3475635Y1278631D01*
X3475822Y1277631D01*
Y1276631D01*
X3475635Y1275631D01*
X3475262Y1274756D01*
X3474702Y1274006D01*
X3474049Y1273506D01*
X3473302Y1273381D01*
G01X3478842Y1274381D02*
X3479589Y1273756D01*
X3480429Y1273381D01*
X3481175D01*
X3481922Y1273756D01*
X3482482Y1274381D01*
X3482762Y1275256D01*
X3482575Y1276131D01*
X3482109Y1276881D01*
X3481269Y1277381D01*
X3480149Y1277631D01*
X3479495Y1278131D01*
X3479215Y1279006D01*
X3479402Y1279881D01*
X3479869Y1280506D01*
X3480522Y1280881D01*
X3481175D01*
X3481829Y1280631D01*
X3482389Y1280006D01*
G01X3486435Y1273381D02*
Y1280881D01*
X3488675D01*
X3489422Y1280506D01*
X3489982Y1279631D01*
X3490169Y1278631D01*
X3489982Y1277631D01*
X3489515Y1276881D01*
X3488675Y1276506D01*
X3486435D01*
G01X3494122Y1273131D02*
X3497482Y1280881D01*
G01X3503302D02*
Y1273381D01*
G01X3501155Y1280881D02*
X3505449D01*
G01X3509682D02*
X3511922D01*
G01X3510802D02*
Y1273381D01*
G01X3509682D02*
X3511922D01*
G01X3516155D02*
Y1280881D01*
X3520449Y1273381D01*
Y1280881D01*
G01X3525335Y1270881D02*
X3524402Y1272131D01*
X3523935Y1273381D01*
Y1278381D01*
X3524402Y1279631D01*
X3525335Y1280881D01*
G01X3532182D02*
X3534422D01*
G01X3533302D02*
Y1273381D01*
G01X3532182D02*
X3534422D01*
G01X3538375D02*
Y1280881D01*
X3540802Y1274631D01*
X3543229Y1280881D01*
Y1273381D01*
G01X3545875D02*
Y1280881D01*
X3548302Y1274631D01*
X3550729Y1280881D01*
Y1273381D01*
G01X3557669D02*
X3553935D01*
Y1280881D01*
X3557669D01*
G01X3556175Y1277256D02*
X3553935D01*
G01X3561435Y1273381D02*
Y1280881D01*
X3563769D01*
X3564515Y1280506D01*
X3564982Y1280006D01*
X3565169Y1279006D01*
X3564982Y1278006D01*
X3564422Y1277381D01*
X3563769Y1277006D01*
X3561435D01*
G01X3563769D02*
X3565169Y1273381D01*
G01X3568842Y1274381D02*
X3569589Y1273756D01*
X3570429Y1273381D01*
X3571175D01*
X3571922Y1273756D01*
X3572482Y1274381D01*
X3572762Y1275256D01*
X3572575Y1276131D01*
X3572109Y1276881D01*
X3571269Y1277381D01*
X3570149Y1277631D01*
X3569495Y1278131D01*
X3569215Y1279006D01*
X3569402Y1279881D01*
X3569869Y1280506D01*
X3570522Y1280881D01*
X3571175D01*
X3571829Y1280631D01*
X3572389Y1280006D01*
G01X3577182Y1280881D02*
X3579422D01*
G01X3578302D02*
Y1273381D01*
G01X3577182D02*
X3579422D01*
G01X3585802D02*
X3585055Y1273506D01*
X3584402Y1274006D01*
X3583842Y1274756D01*
X3583469Y1275631D01*
X3583282Y1276631D01*
Y1277631D01*
X3583469Y1278631D01*
X3583842Y1279506D01*
X3584402Y1280256D01*
X3585055Y1280756D01*
X3585802Y1280881D01*
X3586549Y1280756D01*
X3587202Y1280256D01*
X3587762Y1279506D01*
X3588135Y1278631D01*
X3588322Y1277631D01*
Y1276631D01*
X3588135Y1275631D01*
X3587762Y1274756D01*
X3587202Y1274006D01*
X3586549Y1273506D01*
X3585802Y1273381D01*
G01X3591155D02*
Y1280881D01*
X3595449Y1273381D01*
Y1280881D01*
G01X3601269Y1270881D02*
X3602202Y1272131D01*
X3602669Y1273381D01*
Y1278381D01*
X3602202Y1279631D01*
X3601269Y1280881D01*
G01X3608302Y1273131D02*
X3608115Y1273256D01*
Y1273506D01*
X3608302Y1273631D01*
X3608489Y1273506D01*
Y1273256D01*
X3608302Y1273131D01*
G01Y1276506D02*
X3608115Y1276631D01*
Y1276881D01*
X3608302Y1277006D01*
X3608489Y1276881D01*
Y1276631D01*
X3608302Y1276506D01*
G01X3613935Y1273381D02*
Y1280881D01*
X3616269D01*
X3617015Y1280506D01*
X3617482Y1280006D01*
X3617669Y1279006D01*
X3617482Y1278006D01*
X3616922Y1277381D01*
X3616269Y1277006D01*
X3613935D01*
G01X3616269D02*
X3617669Y1273381D01*
G01X3625169D02*
X3621435D01*
Y1280881D01*
X3625169D01*
G01X3623675Y1277256D02*
X3621435D01*
G01X3632855Y1280256D02*
X3632295Y1280631D01*
X3631642Y1280881D01*
X3630895D01*
X3630055Y1280506D01*
X3629402Y1279881D01*
X3628935Y1279131D01*
X3628562Y1277881D01*
X3628469Y1276756D01*
X3628655Y1275631D01*
X3628935Y1274881D01*
X3629495Y1274131D01*
X3630149Y1273631D01*
X3630802Y1273381D01*
X3631455D01*
X3632109Y1273631D01*
X3632669Y1274006D01*
X3633135Y1274506D01*
G01X3638302Y1273381D02*
X3637555Y1273506D01*
X3636902Y1274006D01*
X3636342Y1274756D01*
X3635969Y1275631D01*
X3635782Y1276631D01*
Y1277631D01*
X3635969Y1278631D01*
X3636342Y1279506D01*
X3636902Y1280256D01*
X3637555Y1280756D01*
X3638302Y1280881D01*
X3639049Y1280756D01*
X3639702Y1280256D01*
X3640262Y1279506D01*
X3640635Y1278631D01*
X3640822Y1277631D01*
Y1276631D01*
X3640635Y1275631D01*
X3640262Y1274756D01*
X3639702Y1274006D01*
X3639049Y1273506D01*
X3638302Y1273381D01*
G01X3643375D02*
Y1280881D01*
X3645802Y1274631D01*
X3648229Y1280881D01*
Y1273381D01*
G01X3650875D02*
Y1280881D01*
X3653302Y1274631D01*
X3655729Y1280881D01*
Y1273381D01*
G01X3662669D02*
X3658935D01*
Y1280881D01*
X3662669D01*
G01X3661175Y1277256D02*
X3658935D01*
G01X3666155Y1273381D02*
Y1280881D01*
X3670449Y1273381D01*
Y1280881D01*
G01X3673749Y1273381D02*
Y1280881D01*
X3675615D01*
X3676362Y1280506D01*
X3676922Y1280006D01*
X3677389Y1279256D01*
X3677762Y1278381D01*
X3677855Y1277131D01*
X3677762Y1275881D01*
X3677389Y1275006D01*
X3676922Y1274256D01*
X3676362Y1273756D01*
X3675615Y1273381D01*
X3673749D01*
G01X3685169D02*
X3681435D01*
Y1280881D01*
X3685169D01*
G01X3683675Y1277256D02*
X3681435D01*
G01X3688749Y1273381D02*
Y1280881D01*
X3690615D01*
X3691362Y1280506D01*
X3691922Y1280006D01*
X3692389Y1279256D01*
X3692762Y1278381D01*
X3692855Y1277131D01*
X3692762Y1275881D01*
X3692389Y1275006D01*
X3691922Y1274256D01*
X3691362Y1273756D01*
X3690615Y1273381D01*
X3688749D01*
G01X3703749D02*
Y1280881D01*
X3705615D01*
X3706362Y1280506D01*
X3706922Y1280006D01*
X3707389Y1279256D01*
X3707762Y1278381D01*
X3707855Y1277131D01*
X3707762Y1275881D01*
X3707389Y1275006D01*
X3706922Y1274256D01*
X3706362Y1273756D01*
X3705615Y1273381D01*
X3703749D01*
G01X3711435D02*
Y1280881D01*
X3713769D01*
X3714515Y1280506D01*
X3714982Y1280006D01*
X3715169Y1279006D01*
X3714982Y1278006D01*
X3714422Y1277381D01*
X3713769Y1277006D01*
X3711435D01*
G01X3713769D02*
X3715169Y1273381D01*
G01X3719682Y1280881D02*
X3721922D01*
G01X3720802D02*
Y1273381D01*
G01X3719682D02*
X3721922D01*
G01X3726435Y1280881D02*
Y1273381D01*
X3730169D01*
G01X3733935Y1280881D02*
Y1273381D01*
X3737669D01*
G01X3748842Y1274381D02*
X3749589Y1273756D01*
X3750429Y1273381D01*
X3751175D01*
X3751922Y1273756D01*
X3752482Y1274381D01*
X3752762Y1275256D01*
X3752575Y1276131D01*
X3752109Y1276881D01*
X3751269Y1277381D01*
X3750149Y1277631D01*
X3749495Y1278131D01*
X3749215Y1279006D01*
X3749402Y1279881D01*
X3749869Y1280506D01*
X3750522Y1280881D01*
X3751175D01*
X3751829Y1280631D01*
X3752389Y1280006D01*
G01X3757182Y1280881D02*
X3759422D01*
G01X3758302D02*
Y1273381D01*
G01X3757182D02*
X3759422D01*
G01X3764029Y1280881D02*
X3767575D01*
X3764029Y1273381D01*
X3767575D01*
G01X3775169D02*
X3771435D01*
Y1280881D01*
X3775169D01*
G01X3773675Y1277256D02*
X3771435D01*
G01X3786529Y1273381D02*
Y1280881D01*
X3790075D01*
G01X3788769Y1277256D02*
X3786529D01*
G01X3795802Y1273381D02*
X3795055Y1273506D01*
X3794402Y1274006D01*
X3793842Y1274756D01*
X3793469Y1275631D01*
X3793282Y1276631D01*
Y1277631D01*
X3793469Y1278631D01*
X3793842Y1279506D01*
X3794402Y1280256D01*
X3795055Y1280756D01*
X3795802Y1280881D01*
X3796549Y1280756D01*
X3797202Y1280256D01*
X3797762Y1279506D01*
X3798135Y1278631D01*
X3798322Y1277631D01*
Y1276631D01*
X3798135Y1275631D01*
X3797762Y1274756D01*
X3797202Y1274006D01*
X3796549Y1273506D01*
X3795802Y1273381D01*
G01X3801435D02*
Y1280881D01*
X3803769D01*
X3804515Y1280506D01*
X3804982Y1280006D01*
X3805169Y1279006D01*
X3804982Y1278006D01*
X3804422Y1277381D01*
X3803769Y1277006D01*
X3801435D01*
G01X3803769D02*
X3805169Y1273381D01*
G01X3818302Y1280881D02*
X3817555Y1280631D01*
X3816995Y1280006D01*
X3816622Y1279256D01*
X3816342Y1278256D01*
X3816249Y1277131D01*
X3816342Y1276006D01*
X3816622Y1275006D01*
X3816995Y1274256D01*
X3817555Y1273631D01*
X3818302Y1273381D01*
X3819049Y1273631D01*
X3819609Y1274256D01*
X3819982Y1275006D01*
X3820262Y1276006D01*
X3820355Y1277131D01*
X3820262Y1278256D01*
X3819982Y1279256D01*
X3819609Y1280006D01*
X3819049Y1280631D01*
X3818302Y1280881D01*
G01X3825802Y1273131D02*
X3825615Y1273256D01*
Y1273506D01*
X3825802Y1273631D01*
X3825989Y1273506D01*
Y1273256D01*
X3825802Y1273131D01*
G01X3831249Y1274881D02*
X3831809Y1274006D01*
X3832555Y1273506D01*
X3833395Y1273381D01*
X3834142Y1273506D01*
X3834889Y1274131D01*
X3835355Y1274881D01*
X3835449Y1275631D01*
X3835262Y1276506D01*
X3834609Y1277131D01*
X3833955Y1277381D01*
X3833115D01*
G01X3833955D02*
X3834515Y1277756D01*
X3834982Y1278381D01*
X3835169Y1279131D01*
X3834982Y1279881D01*
X3834515Y1280506D01*
X3833675Y1280881D01*
X3832835Y1280756D01*
X3831995Y1280256D01*
G01X3839029Y1276506D02*
X3839682Y1277381D01*
X3840242Y1277881D01*
X3840989Y1278131D01*
X3841642Y1277881D01*
X3842109Y1277381D01*
X3842482Y1276631D01*
X3842575Y1275756D01*
X3842482Y1275006D01*
X3842109Y1274256D01*
X3841549Y1273631D01*
X3840895Y1273381D01*
X3840149Y1273631D01*
X3839495Y1274381D01*
X3839122Y1275506D01*
X3839029Y1276756D01*
X3839215Y1278381D01*
X3839495Y1279256D01*
X3839962Y1280131D01*
X3840615Y1280756D01*
X3841269Y1280881D01*
X3841922Y1280631D01*
X3842389Y1280006D01*
G01X3845875Y1273381D02*
Y1280881D01*
X3848302Y1274631D01*
X3850729Y1280881D01*
Y1273381D01*
G01X3853375D02*
Y1280881D01*
X3855802Y1274631D01*
X3858229Y1280881D01*
Y1273381D01*
G01X3869029D02*
Y1280881D01*
X3872575D01*
G01X3871269Y1277256D02*
X3869029D01*
G01X3877182Y1280881D02*
X3879422D01*
G01X3878302D02*
Y1273381D01*
G01X3877182D02*
X3879422D01*
G01X3883655D02*
Y1280881D01*
X3887949Y1273381D01*
Y1280881D01*
G01X3892182D02*
X3894422D01*
G01X3893302D02*
Y1273381D01*
G01X3892182D02*
X3894422D01*
G01X3898842Y1274381D02*
X3899589Y1273756D01*
X3900429Y1273381D01*
X3901175D01*
X3901922Y1273756D01*
X3902482Y1274381D01*
X3902762Y1275256D01*
X3902575Y1276131D01*
X3902109Y1276881D01*
X3901269Y1277381D01*
X3900149Y1277631D01*
X3899495Y1278131D01*
X3899215Y1279006D01*
X3899402Y1279881D01*
X3899869Y1280506D01*
X3900522Y1280881D01*
X3901175D01*
X3901829Y1280631D01*
X3902389Y1280006D01*
G01X3906342Y1273381D02*
Y1280881D01*
G01X3910262D02*
Y1273381D01*
G01Y1277131D02*
X3906342D01*
G01X3917669Y1273381D02*
X3913935D01*
Y1280881D01*
X3917669D01*
G01X3916175Y1277256D02*
X3913935D01*
G01X3921249Y1273381D02*
Y1280881D01*
X3923115D01*
X3923862Y1280506D01*
X3924422Y1280006D01*
X3924889Y1279256D01*
X3925262Y1278381D01*
X3925355Y1277131D01*
X3925262Y1275881D01*
X3924889Y1275006D01*
X3924422Y1274256D01*
X3923862Y1273756D01*
X3923115Y1273381D01*
X3921249D01*
G01X3936435D02*
Y1280881D01*
X3938675D01*
X3939422Y1280506D01*
X3939982Y1279631D01*
X3940169Y1278631D01*
X3939982Y1277631D01*
X3939515Y1276881D01*
X3938675Y1276506D01*
X3936435D01*
G01X3945802Y1280881D02*
Y1273381D01*
G01X3943655Y1280881D02*
X3947949D01*
G01X3951342Y1273381D02*
Y1280881D01*
G01X3955262D02*
Y1273381D01*
G01Y1277131D02*
X3951342D01*
G01X3967182Y1280881D02*
X3969422D01*
G01X3968302D02*
Y1273381D01*
G01X3967182D02*
X3969422D01*
G01X3973842Y1274381D02*
X3974589Y1273756D01*
X3975429Y1273381D01*
X3976175D01*
X3976922Y1273756D01*
X3977482Y1274381D01*
X3977762Y1275256D01*
X3977575Y1276131D01*
X3977109Y1276881D01*
X3976269Y1277381D01*
X3975149Y1277631D01*
X3974495Y1278131D01*
X3974215Y1279006D01*
X3974402Y1279881D01*
X3974869Y1280506D01*
X3975522Y1280881D01*
X3976175D01*
X3976829Y1280631D01*
X3977389Y1280006D01*
G01X3990802Y1280881D02*
X3990055Y1280631D01*
X3989495Y1280006D01*
X3989122Y1279256D01*
X3988842Y1278256D01*
X3988749Y1277131D01*
X3988842Y1276006D01*
X3989122Y1275006D01*
X3989495Y1274256D01*
X3990055Y1273631D01*
X3990802Y1273381D01*
X3991549Y1273631D01*
X3992109Y1274256D01*
X3992482Y1275006D01*
X3992762Y1276006D01*
X3992855Y1277131D01*
X3992762Y1278256D01*
X3992482Y1279256D01*
X3992109Y1280006D01*
X3991549Y1280631D01*
X3990802Y1280881D01*
G01X3998302Y1273131D02*
X3998115Y1273256D01*
Y1273506D01*
X3998302Y1273631D01*
X3998489Y1273506D01*
Y1273256D01*
X3998302Y1273131D01*
G01X4006922Y1273381D02*
Y1280881D01*
X4003469Y1275506D01*
X4008135D01*
G01X4011249Y1274506D02*
X4011809Y1273881D01*
X4012462Y1273506D01*
X4013302Y1273381D01*
X4014142Y1273631D01*
X4014795Y1274131D01*
X4015262Y1275006D01*
X4015355Y1276006D01*
X4015169Y1277006D01*
X4014702Y1277631D01*
X4014049Y1278131D01*
X4013395Y1278256D01*
X4012742Y1278131D01*
X4011902Y1277631D01*
X4012182Y1280881D01*
X4014702D01*
G01X4018375Y1273381D02*
Y1280881D01*
X4020802Y1274631D01*
X4023229Y1280881D01*
Y1273381D01*
G01X4025875D02*
Y1280881D01*
X4028302Y1274631D01*
X4030729Y1280881D01*
Y1273381D01*
G01X4040875D02*
Y1280881D01*
X4043302Y1274631D01*
X4045729Y1280881D01*
Y1273381D01*
G01X4052669D02*
X4048935D01*
Y1280881D01*
X4052669D01*
G01X4051175Y1277256D02*
X4048935D01*
G01X4058302Y1280881D02*
Y1273381D01*
G01X4056155Y1280881D02*
X4060449D01*
G01X4063935Y1273381D02*
Y1280881D01*
X4066269D01*
X4067015Y1280506D01*
X4067482Y1280006D01*
X4067669Y1279006D01*
X4067482Y1278006D01*
X4066922Y1277381D01*
X4066269Y1277006D01*
X4063935D01*
G01X4066269D02*
X4067669Y1273381D01*
G01X4072182Y1280881D02*
X4074422D01*
G01X4073302D02*
Y1273381D01*
G01X4072182D02*
X4074422D01*
G01X4082855Y1280256D02*
X4082295Y1280631D01*
X4081642Y1280881D01*
X4080895D01*
X4080055Y1280506D01*
X4079402Y1279881D01*
X4078935Y1279131D01*
X4078562Y1277881D01*
X4078469Y1276756D01*
X4078655Y1275631D01*
X4078935Y1274881D01*
X4079495Y1274131D01*
X4080149Y1273631D01*
X4080802Y1273381D01*
X4081455D01*
X4082109Y1273631D01*
X4082669Y1274006D01*
X4083135Y1274506D01*
G01X4093749Y1273381D02*
Y1280881D01*
X4095615D01*
X4096362Y1280506D01*
X4096922Y1280006D01*
X4097389Y1279256D01*
X4097762Y1278381D01*
X4097855Y1277131D01*
X4097762Y1275881D01*
X4097389Y1275006D01*
X4096922Y1274256D01*
X4096362Y1273756D01*
X4095615Y1273381D01*
X4093749D01*
G01X4101435D02*
Y1280881D01*
X4103769D01*
X4104515Y1280506D01*
X4104982Y1280006D01*
X4105169Y1279006D01*
X4104982Y1278006D01*
X4104422Y1277381D01*
X4103769Y1277006D01*
X4101435D01*
G01X4103769D02*
X4105169Y1273381D01*
G01X4109682Y1280881D02*
X4111922D01*
G01X4110802D02*
Y1273381D01*
G01X4109682D02*
X4111922D01*
G01X4116435Y1280881D02*
Y1273381D01*
X4120169D01*
G01X4123935Y1280881D02*
Y1273381D01*
X4127669D01*
G01X4132835Y1270881D02*
X4131902Y1272131D01*
X4131435Y1273381D01*
Y1278381D01*
X4131902Y1279631D01*
X4132835Y1280881D01*
G01X4140802D02*
X4140055Y1280631D01*
X4139495Y1280006D01*
X4139122Y1279256D01*
X4138842Y1278256D01*
X4138749Y1277131D01*
X4138842Y1276006D01*
X4139122Y1275006D01*
X4139495Y1274256D01*
X4140055Y1273631D01*
X4140802Y1273381D01*
X4141549Y1273631D01*
X4142109Y1274256D01*
X4142482Y1275006D01*
X4142762Y1276006D01*
X4142855Y1277131D01*
X4142762Y1278256D01*
X4142482Y1279256D01*
X4142109Y1280006D01*
X4141549Y1280631D01*
X4140802Y1280881D01*
G01X4148302Y1273131D02*
X4148115Y1273256D01*
Y1273506D01*
X4148302Y1273631D01*
X4148489Y1273506D01*
Y1273256D01*
X4148302Y1273131D01*
G01X4155802Y1280881D02*
X4155055Y1280631D01*
X4154495Y1280006D01*
X4154122Y1279256D01*
X4153842Y1278256D01*
X4153749Y1277131D01*
X4153842Y1276006D01*
X4154122Y1275006D01*
X4154495Y1274256D01*
X4155055Y1273631D01*
X4155802Y1273381D01*
X4156549Y1273631D01*
X4157109Y1274256D01*
X4157482Y1275006D01*
X4157762Y1276006D01*
X4157855Y1277131D01*
X4157762Y1278256D01*
X4157482Y1279256D01*
X4157109Y1280006D01*
X4156549Y1280631D01*
X4155802Y1280881D01*
G01X4163302Y1273381D02*
Y1280881D01*
X4162182Y1279381D01*
G01Y1273381D02*
X4164422D01*
G01X4170615D02*
X4170802Y1275006D01*
X4171082Y1276381D01*
X4171455Y1277631D01*
X4171922Y1279006D01*
X4172669Y1280881D01*
X4168935D01*
G01X4178115Y1273381D02*
X4178302Y1275006D01*
X4178582Y1276381D01*
X4178955Y1277631D01*
X4179422Y1279006D01*
X4180169Y1280881D01*
X4176435D01*
G01X4184962Y1279256D02*
X4185429Y1280881D01*
G01X4186642D02*
X4186175Y1279256D01*
G01X4193769Y1270881D02*
X4194702Y1272131D01*
X4195169Y1273381D01*
Y1278381D01*
X4194702Y1279631D01*
X4193769Y1280881D01*
G01X4200802Y1273131D02*
X4200615Y1273256D01*
Y1273506D01*
X4200802Y1273631D01*
X4200989Y1273506D01*
Y1273256D01*
X4200802Y1273131D01*
G01X3426840Y1202651D02*
X3427587Y1202026D01*
X3428427Y1201651D01*
X3429173D01*
X3429920Y1202026D01*
X3430480Y1202651D01*
X3430760Y1203526D01*
X3430573Y1204401D01*
X3430107Y1205151D01*
X3429267Y1205651D01*
X3428147Y1205901D01*
X3427493Y1206401D01*
X3427213Y1207276D01*
X3427400Y1208151D01*
X3427867Y1208776D01*
X3428520Y1209151D01*
X3429173D01*
X3429827Y1208901D01*
X3430387Y1208276D01*
G01X3435180Y1209151D02*
X3437420D01*
G01X3436300D02*
Y1201651D01*
G01X3435180D02*
X3437420D01*
G01X3441933Y1209151D02*
Y1201651D01*
X3445667D01*
G01X3448967Y1209151D02*
X3451300Y1201651D01*
X3453633Y1209151D01*
G01X3460667Y1201651D02*
X3456933D01*
Y1209151D01*
X3460667D01*
G01X3459173Y1205526D02*
X3456933D01*
G01X3464433Y1201651D02*
Y1209151D01*
X3466767D01*
X3467513Y1208776D01*
X3467980Y1208276D01*
X3468167Y1207276D01*
X3467980Y1206276D01*
X3467420Y1205651D01*
X3466767Y1205276D01*
X3464433D01*
G01X3466767D02*
X3468167Y1201651D01*
G01X3473333Y1199151D02*
X3472400Y1200401D01*
X3471933Y1201651D01*
Y1206651D01*
X3472400Y1207901D01*
X3473333Y1209151D01*
G01X3480180D02*
X3482420D01*
G01X3481300D02*
Y1201651D01*
G01X3480180D02*
X3482420D01*
G01X3486373D02*
Y1209151D01*
X3488800Y1202901D01*
X3491227Y1209151D01*
Y1201651D01*
G01X3493873D02*
Y1209151D01*
X3496300Y1202901D01*
X3498727Y1209151D01*
Y1201651D01*
G01X3505667D02*
X3501933D01*
Y1209151D01*
X3505667D01*
G01X3504173Y1205526D02*
X3501933D01*
G01X3509433Y1201651D02*
Y1209151D01*
X3511767D01*
X3512513Y1208776D01*
X3512980Y1208276D01*
X3513167Y1207276D01*
X3512980Y1206276D01*
X3512420Y1205651D01*
X3511767Y1205276D01*
X3509433D01*
G01X3511767D02*
X3513167Y1201651D01*
G01X3516840Y1202651D02*
X3517587Y1202026D01*
X3518427Y1201651D01*
X3519173D01*
X3519920Y1202026D01*
X3520480Y1202651D01*
X3520760Y1203526D01*
X3520573Y1204401D01*
X3520107Y1205151D01*
X3519267Y1205651D01*
X3518147Y1205901D01*
X3517493Y1206401D01*
X3517213Y1207276D01*
X3517400Y1208151D01*
X3517867Y1208776D01*
X3518520Y1209151D01*
X3519173D01*
X3519827Y1208901D01*
X3520387Y1208276D01*
G01X3525180Y1209151D02*
X3527420D01*
G01X3526300D02*
Y1201651D01*
G01X3525180D02*
X3527420D01*
G01X3533800D02*
X3533053Y1201776D01*
X3532400Y1202276D01*
X3531840Y1203026D01*
X3531467Y1203901D01*
X3531280Y1204901D01*
Y1205901D01*
X3531467Y1206901D01*
X3531840Y1207776D01*
X3532400Y1208526D01*
X3533053Y1209026D01*
X3533800Y1209151D01*
X3534547Y1209026D01*
X3535200Y1208526D01*
X3535760Y1207776D01*
X3536133Y1206901D01*
X3536320Y1205901D01*
Y1204901D01*
X3536133Y1203901D01*
X3535760Y1203026D01*
X3535200Y1202276D01*
X3534547Y1201776D01*
X3533800Y1201651D01*
G01X3539153D02*
Y1209151D01*
X3543447Y1201651D01*
Y1209151D01*
G01X3549267Y1199151D02*
X3550200Y1200401D01*
X3550667Y1201651D01*
Y1206651D01*
X3550200Y1207901D01*
X3549267Y1209151D01*
G01X3556300Y1201401D02*
X3556113Y1201526D01*
Y1201776D01*
X3556300Y1201901D01*
X3556487Y1201776D01*
Y1201526D01*
X3556300Y1201401D01*
G01Y1204776D02*
X3556113Y1204901D01*
Y1205151D01*
X3556300Y1205276D01*
X3556487Y1205151D01*
Y1204901D01*
X3556300Y1204776D01*
G01X3561933Y1201651D02*
Y1209151D01*
X3564267D01*
X3565013Y1208776D01*
X3565480Y1208276D01*
X3565667Y1207276D01*
X3565480Y1206276D01*
X3564920Y1205651D01*
X3564267Y1205276D01*
X3561933D01*
G01X3564267D02*
X3565667Y1201651D01*
G01X3573167D02*
X3569433D01*
Y1209151D01*
X3573167D01*
G01X3571673Y1205526D02*
X3569433D01*
G01X3580853Y1208526D02*
X3580293Y1208901D01*
X3579640Y1209151D01*
X3578893D01*
X3578053Y1208776D01*
X3577400Y1208151D01*
X3576933Y1207401D01*
X3576560Y1206151D01*
X3576467Y1205026D01*
X3576653Y1203901D01*
X3576933Y1203151D01*
X3577493Y1202401D01*
X3578147Y1201901D01*
X3578800Y1201651D01*
X3579453D01*
X3580107Y1201901D01*
X3580667Y1202276D01*
X3581133Y1202776D01*
G01X3586300Y1201651D02*
X3585553Y1201776D01*
X3584900Y1202276D01*
X3584340Y1203026D01*
X3583967Y1203901D01*
X3583780Y1204901D01*
Y1205901D01*
X3583967Y1206901D01*
X3584340Y1207776D01*
X3584900Y1208526D01*
X3585553Y1209026D01*
X3586300Y1209151D01*
X3587047Y1209026D01*
X3587700Y1208526D01*
X3588260Y1207776D01*
X3588633Y1206901D01*
X3588820Y1205901D01*
Y1204901D01*
X3588633Y1203901D01*
X3588260Y1203026D01*
X3587700Y1202276D01*
X3587047Y1201776D01*
X3586300Y1201651D01*
G01X3591373D02*
Y1209151D01*
X3593800Y1202901D01*
X3596227Y1209151D01*
Y1201651D01*
G01X3598873D02*
Y1209151D01*
X3601300Y1202901D01*
X3603727Y1209151D01*
Y1201651D01*
G01X3610667D02*
X3606933D01*
Y1209151D01*
X3610667D01*
G01X3609173Y1205526D02*
X3606933D01*
G01X3614153Y1201651D02*
Y1209151D01*
X3618447Y1201651D01*
Y1209151D01*
G01X3621747Y1201651D02*
Y1209151D01*
X3623613D01*
X3624360Y1208776D01*
X3624920Y1208276D01*
X3625387Y1207526D01*
X3625760Y1206651D01*
X3625853Y1205401D01*
X3625760Y1204151D01*
X3625387Y1203276D01*
X3624920Y1202526D01*
X3624360Y1202026D01*
X3623613Y1201651D01*
X3621747D01*
G01X3633167D02*
X3629433D01*
Y1209151D01*
X3633167D01*
G01X3631673Y1205526D02*
X3629433D01*
G01X3636747Y1201651D02*
Y1209151D01*
X3638613D01*
X3639360Y1208776D01*
X3639920Y1208276D01*
X3640387Y1207526D01*
X3640760Y1206651D01*
X3640853Y1205401D01*
X3640760Y1204151D01*
X3640387Y1203276D01*
X3639920Y1202526D01*
X3639360Y1202026D01*
X3638613Y1201651D01*
X3636747D01*
G01X3651747D02*
Y1209151D01*
X3653613D01*
X3654360Y1208776D01*
X3654920Y1208276D01*
X3655387Y1207526D01*
X3655760Y1206651D01*
X3655853Y1205401D01*
X3655760Y1204151D01*
X3655387Y1203276D01*
X3654920Y1202526D01*
X3654360Y1202026D01*
X3653613Y1201651D01*
X3651747D01*
G01X3659433D02*
Y1209151D01*
X3661767D01*
X3662513Y1208776D01*
X3662980Y1208276D01*
X3663167Y1207276D01*
X3662980Y1206276D01*
X3662420Y1205651D01*
X3661767Y1205276D01*
X3659433D01*
G01X3661767D02*
X3663167Y1201651D01*
G01X3667680Y1209151D02*
X3669920D01*
G01X3668800D02*
Y1201651D01*
G01X3667680D02*
X3669920D01*
G01X3674433Y1209151D02*
Y1201651D01*
X3678167D01*
G01X3681933Y1209151D02*
Y1201651D01*
X3685667D01*
G01X3696840Y1202651D02*
X3697587Y1202026D01*
X3698427Y1201651D01*
X3699173D01*
X3699920Y1202026D01*
X3700480Y1202651D01*
X3700760Y1203526D01*
X3700573Y1204401D01*
X3700107Y1205151D01*
X3699267Y1205651D01*
X3698147Y1205901D01*
X3697493Y1206401D01*
X3697213Y1207276D01*
X3697400Y1208151D01*
X3697867Y1208776D01*
X3698520Y1209151D01*
X3699173D01*
X3699827Y1208901D01*
X3700387Y1208276D01*
G01X3705180Y1209151D02*
X3707420D01*
G01X3706300D02*
Y1201651D01*
G01X3705180D02*
X3707420D01*
G01X3712027Y1209151D02*
X3715573D01*
X3712027Y1201651D01*
X3715573D01*
G01X3723167D02*
X3719433D01*
Y1209151D01*
X3723167D01*
G01X3721673Y1205526D02*
X3719433D01*
G01X3734527Y1201651D02*
Y1209151D01*
X3738073D01*
G01X3736767Y1205526D02*
X3734527D01*
G01X3743800Y1201651D02*
X3743053Y1201776D01*
X3742400Y1202276D01*
X3741840Y1203026D01*
X3741467Y1203901D01*
X3741280Y1204901D01*
Y1205901D01*
X3741467Y1206901D01*
X3741840Y1207776D01*
X3742400Y1208526D01*
X3743053Y1209026D01*
X3743800Y1209151D01*
X3744547Y1209026D01*
X3745200Y1208526D01*
X3745760Y1207776D01*
X3746133Y1206901D01*
X3746320Y1205901D01*
Y1204901D01*
X3746133Y1203901D01*
X3745760Y1203026D01*
X3745200Y1202276D01*
X3744547Y1201776D01*
X3743800Y1201651D01*
G01X3749433D02*
Y1209151D01*
X3751767D01*
X3752513Y1208776D01*
X3752980Y1208276D01*
X3753167Y1207276D01*
X3752980Y1206276D01*
X3752420Y1205651D01*
X3751767Y1205276D01*
X3749433D01*
G01X3751767D02*
X3753167Y1201651D01*
G01X3766300Y1209151D02*
X3765553Y1208901D01*
X3764993Y1208276D01*
X3764620Y1207526D01*
X3764340Y1206526D01*
X3764247Y1205401D01*
X3764340Y1204276D01*
X3764620Y1203276D01*
X3764993Y1202526D01*
X3765553Y1201901D01*
X3766300Y1201651D01*
X3767047Y1201901D01*
X3767607Y1202526D01*
X3767980Y1203276D01*
X3768260Y1204276D01*
X3768353Y1205401D01*
X3768260Y1206526D01*
X3767980Y1207526D01*
X3767607Y1208276D01*
X3767047Y1208901D01*
X3766300Y1209151D01*
G01X3773800Y1201401D02*
X3773613Y1201526D01*
Y1201776D01*
X3773800Y1201901D01*
X3773987Y1201776D01*
Y1201526D01*
X3773800Y1201401D01*
G01X3779247Y1202776D02*
X3779807Y1202151D01*
X3780460Y1201776D01*
X3781300Y1201651D01*
X3782140Y1201901D01*
X3782793Y1202401D01*
X3783260Y1203276D01*
X3783353Y1204276D01*
X3783167Y1205276D01*
X3782700Y1205901D01*
X3782047Y1206401D01*
X3781393Y1206526D01*
X3780740Y1206401D01*
X3779900Y1205901D01*
X3780180Y1209151D01*
X3782700D01*
G01X3786373Y1201651D02*
Y1209151D01*
X3788800Y1202901D01*
X3791227Y1209151D01*
Y1201651D01*
G01X3793873D02*
Y1209151D01*
X3796300Y1202901D01*
X3798727Y1209151D01*
Y1201651D01*
G01X3809527D02*
Y1209151D01*
X3813073D01*
G01X3811767Y1205526D02*
X3809527D01*
G01X3817680Y1209151D02*
X3819920D01*
G01X3818800D02*
Y1201651D01*
G01X3817680D02*
X3819920D01*
G01X3824153D02*
Y1209151D01*
X3828447Y1201651D01*
Y1209151D01*
G01X3832680D02*
X3834920D01*
G01X3833800D02*
Y1201651D01*
G01X3832680D02*
X3834920D01*
G01X3839340Y1202651D02*
X3840087Y1202026D01*
X3840927Y1201651D01*
X3841673D01*
X3842420Y1202026D01*
X3842980Y1202651D01*
X3843260Y1203526D01*
X3843073Y1204401D01*
X3842607Y1205151D01*
X3841767Y1205651D01*
X3840647Y1205901D01*
X3839993Y1206401D01*
X3839713Y1207276D01*
X3839900Y1208151D01*
X3840367Y1208776D01*
X3841020Y1209151D01*
X3841673D01*
X3842327Y1208901D01*
X3842887Y1208276D01*
G01X3846840Y1201651D02*
Y1209151D01*
G01X3850760D02*
Y1201651D01*
G01Y1205401D02*
X3846840D01*
G01X3858167Y1201651D02*
X3854433D01*
Y1209151D01*
X3858167D01*
G01X3856673Y1205526D02*
X3854433D01*
G01X3861747Y1201651D02*
Y1209151D01*
X3863613D01*
X3864360Y1208776D01*
X3864920Y1208276D01*
X3865387Y1207526D01*
X3865760Y1206651D01*
X3865853Y1205401D01*
X3865760Y1204151D01*
X3865387Y1203276D01*
X3864920Y1202526D01*
X3864360Y1202026D01*
X3863613Y1201651D01*
X3861747D01*
G01X3876933D02*
Y1209151D01*
X3879173D01*
X3879920Y1208776D01*
X3880480Y1207901D01*
X3880667Y1206901D01*
X3880480Y1205901D01*
X3880013Y1205151D01*
X3879173Y1204776D01*
X3876933D01*
G01X3886300Y1209151D02*
Y1201651D01*
G01X3884153Y1209151D02*
X3888447D01*
G01X3891840Y1201651D02*
Y1209151D01*
G01X3895760D02*
Y1201651D01*
G01Y1205401D02*
X3891840D01*
G01X3907680Y1209151D02*
X3909920D01*
G01X3908800D02*
Y1201651D01*
G01X3907680D02*
X3909920D01*
G01X3914340Y1202651D02*
X3915087Y1202026D01*
X3915927Y1201651D01*
X3916673D01*
X3917420Y1202026D01*
X3917980Y1202651D01*
X3918260Y1203526D01*
X3918073Y1204401D01*
X3917607Y1205151D01*
X3916767Y1205651D01*
X3915647Y1205901D01*
X3914993Y1206401D01*
X3914713Y1207276D01*
X3914900Y1208151D01*
X3915367Y1208776D01*
X3916020Y1209151D01*
X3916673D01*
X3917327Y1208901D01*
X3917887Y1208276D01*
G01X3931300Y1209151D02*
X3930553Y1208901D01*
X3929993Y1208276D01*
X3929620Y1207526D01*
X3929340Y1206526D01*
X3929247Y1205401D01*
X3929340Y1204276D01*
X3929620Y1203276D01*
X3929993Y1202526D01*
X3930553Y1201901D01*
X3931300Y1201651D01*
X3932047Y1201901D01*
X3932607Y1202526D01*
X3932980Y1203276D01*
X3933260Y1204276D01*
X3933353Y1205401D01*
X3933260Y1206526D01*
X3932980Y1207526D01*
X3932607Y1208276D01*
X3932047Y1208901D01*
X3931300Y1209151D01*
G01X3938800Y1201401D02*
X3938613Y1201526D01*
Y1201776D01*
X3938800Y1201901D01*
X3938987Y1201776D01*
Y1201526D01*
X3938800Y1201401D01*
G01X3944527Y1204776D02*
X3945180Y1205651D01*
X3945740Y1206151D01*
X3946487Y1206401D01*
X3947140Y1206151D01*
X3947607Y1205651D01*
X3947980Y1204901D01*
X3948073Y1204026D01*
X3947980Y1203276D01*
X3947607Y1202526D01*
X3947047Y1201901D01*
X3946393Y1201651D01*
X3945647Y1201901D01*
X3944993Y1202651D01*
X3944620Y1203776D01*
X3944527Y1205026D01*
X3944713Y1206651D01*
X3944993Y1207526D01*
X3945460Y1208401D01*
X3946113Y1209026D01*
X3946767Y1209151D01*
X3947420Y1208901D01*
X3947887Y1208276D01*
G01X3951373Y1201651D02*
Y1209151D01*
X3953800Y1202901D01*
X3956227Y1209151D01*
Y1201651D01*
G01X3958873D02*
Y1209151D01*
X3961300Y1202901D01*
X3963727Y1209151D01*
Y1201651D01*
G01X3973873D02*
Y1209151D01*
X3976300Y1202901D01*
X3978727Y1209151D01*
Y1201651D01*
G01X3985667D02*
X3981933D01*
Y1209151D01*
X3985667D01*
G01X3984173Y1205526D02*
X3981933D01*
G01X3991300Y1209151D02*
Y1201651D01*
G01X3989153Y1209151D02*
X3993447D01*
G01X3996933Y1201651D02*
Y1209151D01*
X3999267D01*
X4000013Y1208776D01*
X4000480Y1208276D01*
X4000667Y1207276D01*
X4000480Y1206276D01*
X3999920Y1205651D01*
X3999267Y1205276D01*
X3996933D01*
G01X3999267D02*
X4000667Y1201651D01*
G01X4005180Y1209151D02*
X4007420D01*
G01X4006300D02*
Y1201651D01*
G01X4005180D02*
X4007420D01*
G01X4015853Y1208526D02*
X4015293Y1208901D01*
X4014640Y1209151D01*
X4013893D01*
X4013053Y1208776D01*
X4012400Y1208151D01*
X4011933Y1207401D01*
X4011560Y1206151D01*
X4011467Y1205026D01*
X4011653Y1203901D01*
X4011933Y1203151D01*
X4012493Y1202401D01*
X4013147Y1201901D01*
X4013800Y1201651D01*
X4014453D01*
X4015107Y1201901D01*
X4015667Y1202276D01*
X4016133Y1202776D01*
G01X4026747Y1201651D02*
Y1209151D01*
X4028613D01*
X4029360Y1208776D01*
X4029920Y1208276D01*
X4030387Y1207526D01*
X4030760Y1206651D01*
X4030853Y1205401D01*
X4030760Y1204151D01*
X4030387Y1203276D01*
X4029920Y1202526D01*
X4029360Y1202026D01*
X4028613Y1201651D01*
X4026747D01*
G01X4034433D02*
Y1209151D01*
X4036767D01*
X4037513Y1208776D01*
X4037980Y1208276D01*
X4038167Y1207276D01*
X4037980Y1206276D01*
X4037420Y1205651D01*
X4036767Y1205276D01*
X4034433D01*
G01X4036767D02*
X4038167Y1201651D01*
G01X4042680Y1209151D02*
X4044920D01*
G01X4043800D02*
Y1201651D01*
G01X4042680D02*
X4044920D01*
G01X4049433Y1209151D02*
Y1201651D01*
X4053167D01*
G01X4056933Y1209151D02*
Y1201651D01*
X4060667D01*
G01X4065833Y1199151D02*
X4064900Y1200401D01*
X4064433Y1201651D01*
Y1206651D01*
X4064900Y1207901D01*
X4065833Y1209151D01*
G01X4073800D02*
X4073053Y1208901D01*
X4072493Y1208276D01*
X4072120Y1207526D01*
X4071840Y1206526D01*
X4071747Y1205401D01*
X4071840Y1204276D01*
X4072120Y1203276D01*
X4072493Y1202526D01*
X4073053Y1201901D01*
X4073800Y1201651D01*
X4074547Y1201901D01*
X4075107Y1202526D01*
X4075480Y1203276D01*
X4075760Y1204276D01*
X4075853Y1205401D01*
X4075760Y1206526D01*
X4075480Y1207526D01*
X4075107Y1208276D01*
X4074547Y1208901D01*
X4073800Y1209151D01*
G01X4081300Y1201401D02*
X4081113Y1201526D01*
Y1201776D01*
X4081300Y1201901D01*
X4081487Y1201776D01*
Y1201526D01*
X4081300Y1201401D01*
G01X4088800Y1209151D02*
X4088053Y1208901D01*
X4087493Y1208276D01*
X4087120Y1207526D01*
X4086840Y1206526D01*
X4086747Y1205401D01*
X4086840Y1204276D01*
X4087120Y1203276D01*
X4087493Y1202526D01*
X4088053Y1201901D01*
X4088800Y1201651D01*
X4089547Y1201901D01*
X4090107Y1202526D01*
X4090480Y1203276D01*
X4090760Y1204276D01*
X4090853Y1205401D01*
X4090760Y1206526D01*
X4090480Y1207526D01*
X4090107Y1208276D01*
X4089547Y1208901D01*
X4088800Y1209151D01*
G01X4094527Y1207901D02*
X4095087Y1208651D01*
X4095740Y1209026D01*
X4096487Y1209151D01*
X4097420Y1208901D01*
X4098073Y1208276D01*
X4098260Y1207526D01*
X4098167Y1206776D01*
X4097793Y1206151D01*
X4095927Y1204901D01*
X4095087Y1204026D01*
X4094527Y1202776D01*
X4094340Y1201651D01*
X4098260D01*
G01X4101747Y1203151D02*
X4102307Y1202276D01*
X4103053Y1201776D01*
X4103893Y1201651D01*
X4104640Y1201776D01*
X4105387Y1202401D01*
X4105853Y1203151D01*
X4105947Y1203901D01*
X4105760Y1204776D01*
X4105107Y1205401D01*
X4104453Y1205651D01*
X4103613D01*
G01X4104453D02*
X4105013Y1206026D01*
X4105480Y1206651D01*
X4105667Y1207401D01*
X4105480Y1208151D01*
X4105013Y1208776D01*
X4104173Y1209151D01*
X4103333Y1209026D01*
X4102493Y1208526D01*
G01X4109527Y1204776D02*
X4110180Y1205651D01*
X4110740Y1206151D01*
X4111487Y1206401D01*
X4112140Y1206151D01*
X4112607Y1205651D01*
X4112980Y1204901D01*
X4113073Y1204026D01*
X4112980Y1203276D01*
X4112607Y1202526D01*
X4112047Y1201901D01*
X4111393Y1201651D01*
X4110647Y1201901D01*
X4109993Y1202651D01*
X4109620Y1203776D01*
X4109527Y1205026D01*
X4109713Y1206651D01*
X4109993Y1207526D01*
X4110460Y1208401D01*
X4111113Y1209026D01*
X4111767Y1209151D01*
X4112420Y1208901D01*
X4112887Y1208276D01*
G01X4117960Y1207526D02*
X4118427Y1209151D01*
G01X4119640D02*
X4119173Y1207526D01*
G01X4126767Y1199151D02*
X4127700Y1200401D01*
X4128167Y1201651D01*
Y1206651D01*
X4127700Y1207901D01*
X4126767Y1209151D01*
G01X4133800Y1201401D02*
X4133613Y1201526D01*
Y1201776D01*
X4133800Y1201901D01*
X4133987Y1201776D01*
Y1201526D01*
X4133800Y1201401D01*
G01X3430853Y1221426D02*
X3430293Y1221801D01*
X3429640Y1222051D01*
X3428893D01*
X3428053Y1221676D01*
X3427400Y1221051D01*
X3426933Y1220301D01*
X3426560Y1219051D01*
X3426467Y1217926D01*
X3426653Y1216801D01*
X3426933Y1216051D01*
X3427493Y1215301D01*
X3428147Y1214801D01*
X3428800Y1214551D01*
X3429453D01*
X3430107Y1214801D01*
X3430667Y1215176D01*
X3431133Y1215676D01*
G01X3436300Y1214551D02*
X3435553Y1214676D01*
X3434900Y1215176D01*
X3434340Y1215926D01*
X3433967Y1216801D01*
X3433780Y1217801D01*
Y1218801D01*
X3433967Y1219801D01*
X3434340Y1220676D01*
X3434900Y1221426D01*
X3435553Y1221926D01*
X3436300Y1222051D01*
X3437047Y1221926D01*
X3437700Y1221426D01*
X3438260Y1220676D01*
X3438633Y1219801D01*
X3438820Y1218801D01*
Y1217801D01*
X3438633Y1216801D01*
X3438260Y1215926D01*
X3437700Y1215176D01*
X3437047Y1214676D01*
X3436300Y1214551D01*
G01X3441933D02*
Y1222051D01*
X3444173D01*
X3444920Y1221676D01*
X3445480Y1220801D01*
X3445667Y1219801D01*
X3445480Y1218801D01*
X3445013Y1218051D01*
X3444173Y1217676D01*
X3441933D01*
G01X3449433Y1214551D02*
Y1222051D01*
X3451673D01*
X3452420Y1221676D01*
X3452980Y1220801D01*
X3453167Y1219801D01*
X3452980Y1218801D01*
X3452513Y1218051D01*
X3451673Y1217676D01*
X3449433D01*
G01X3460667Y1214551D02*
X3456933D01*
Y1222051D01*
X3460667D01*
G01X3459173Y1218426D02*
X3456933D01*
G01X3464433Y1214551D02*
Y1222051D01*
X3466767D01*
X3467513Y1221676D01*
X3467980Y1221176D01*
X3468167Y1220176D01*
X3467980Y1219176D01*
X3467420Y1218551D01*
X3466767Y1218176D01*
X3464433D01*
G01X3466767D02*
X3468167Y1214551D01*
G01X3481300D02*
X3480553Y1214676D01*
X3479900Y1215176D01*
X3479340Y1215926D01*
X3478967Y1216801D01*
X3478780Y1217801D01*
Y1218801D01*
X3478967Y1219801D01*
X3479340Y1220676D01*
X3479900Y1221426D01*
X3480553Y1221926D01*
X3481300Y1222051D01*
X3482047Y1221926D01*
X3482700Y1221426D01*
X3483260Y1220676D01*
X3483633Y1219801D01*
X3483820Y1218801D01*
Y1217801D01*
X3483633Y1216801D01*
X3483260Y1215926D01*
X3482700Y1215176D01*
X3482047Y1214676D01*
X3481300Y1214551D01*
G01X3486840Y1215551D02*
X3487587Y1214926D01*
X3488427Y1214551D01*
X3489173D01*
X3489920Y1214926D01*
X3490480Y1215551D01*
X3490760Y1216426D01*
X3490573Y1217301D01*
X3490107Y1218051D01*
X3489267Y1218551D01*
X3488147Y1218801D01*
X3487493Y1219301D01*
X3487213Y1220176D01*
X3487400Y1221051D01*
X3487867Y1221676D01*
X3488520Y1222051D01*
X3489173D01*
X3489827Y1221801D01*
X3490387Y1221176D01*
G01X3494433Y1214551D02*
Y1222051D01*
X3496673D01*
X3497420Y1221676D01*
X3497980Y1220801D01*
X3498167Y1219801D01*
X3497980Y1218801D01*
X3497513Y1218051D01*
X3496673Y1217676D01*
X3494433D01*
G01X3502120Y1214301D02*
X3505480Y1222051D01*
G01X3511300D02*
Y1214551D01*
G01X3509153Y1222051D02*
X3513447D01*
G01X3517680D02*
X3519920D01*
G01X3518800D02*
Y1214551D01*
G01X3517680D02*
X3519920D01*
G01X3524153D02*
Y1222051D01*
X3528447Y1214551D01*
Y1222051D01*
G01X3533333Y1212051D02*
X3532400Y1213301D01*
X3531933Y1214551D01*
Y1219551D01*
X3532400Y1220801D01*
X3533333Y1222051D01*
G01X3540180D02*
X3542420D01*
G01X3541300D02*
Y1214551D01*
G01X3540180D02*
X3542420D01*
G01X3546373D02*
Y1222051D01*
X3548800Y1215801D01*
X3551227Y1222051D01*
Y1214551D01*
G01X3553873D02*
Y1222051D01*
X3556300Y1215801D01*
X3558727Y1222051D01*
Y1214551D01*
G01X3565667D02*
X3561933D01*
Y1222051D01*
X3565667D01*
G01X3564173Y1218426D02*
X3561933D01*
G01X3569433Y1214551D02*
Y1222051D01*
X3571767D01*
X3572513Y1221676D01*
X3572980Y1221176D01*
X3573167Y1220176D01*
X3572980Y1219176D01*
X3572420Y1218551D01*
X3571767Y1218176D01*
X3569433D01*
G01X3571767D02*
X3573167Y1214551D01*
G01X3576840Y1215551D02*
X3577587Y1214926D01*
X3578427Y1214551D01*
X3579173D01*
X3579920Y1214926D01*
X3580480Y1215551D01*
X3580760Y1216426D01*
X3580573Y1217301D01*
X3580107Y1218051D01*
X3579267Y1218551D01*
X3578147Y1218801D01*
X3577493Y1219301D01*
X3577213Y1220176D01*
X3577400Y1221051D01*
X3577867Y1221676D01*
X3578520Y1222051D01*
X3579173D01*
X3579827Y1221801D01*
X3580387Y1221176D01*
G01X3585180Y1222051D02*
X3587420D01*
G01X3586300D02*
Y1214551D01*
G01X3585180D02*
X3587420D01*
G01X3593800D02*
X3593053Y1214676D01*
X3592400Y1215176D01*
X3591840Y1215926D01*
X3591467Y1216801D01*
X3591280Y1217801D01*
Y1218801D01*
X3591467Y1219801D01*
X3591840Y1220676D01*
X3592400Y1221426D01*
X3593053Y1221926D01*
X3593800Y1222051D01*
X3594547Y1221926D01*
X3595200Y1221426D01*
X3595760Y1220676D01*
X3596133Y1219801D01*
X3596320Y1218801D01*
Y1217801D01*
X3596133Y1216801D01*
X3595760Y1215926D01*
X3595200Y1215176D01*
X3594547Y1214676D01*
X3593800Y1214551D01*
G01X3599153D02*
Y1222051D01*
X3603447Y1214551D01*
Y1222051D01*
G01X3609267Y1212051D02*
X3610200Y1213301D01*
X3610667Y1214551D01*
Y1219551D01*
X3610200Y1220801D01*
X3609267Y1222051D01*
G01X3616300Y1214301D02*
X3616113Y1214426D01*
Y1214676D01*
X3616300Y1214801D01*
X3616487Y1214676D01*
Y1214426D01*
X3616300Y1214301D01*
G01Y1217676D02*
X3616113Y1217801D01*
Y1218051D01*
X3616300Y1218176D01*
X3616487Y1218051D01*
Y1217801D01*
X3616300Y1217676D01*
G01X3621933Y1214551D02*
Y1222051D01*
X3624267D01*
X3625013Y1221676D01*
X3625480Y1221176D01*
X3625667Y1220176D01*
X3625480Y1219176D01*
X3624920Y1218551D01*
X3624267Y1218176D01*
X3621933D01*
G01X3624267D02*
X3625667Y1214551D01*
G01X3633167D02*
X3629433D01*
Y1222051D01*
X3633167D01*
G01X3631673Y1218426D02*
X3629433D01*
G01X3640853Y1221426D02*
X3640293Y1221801D01*
X3639640Y1222051D01*
X3638893D01*
X3638053Y1221676D01*
X3637400Y1221051D01*
X3636933Y1220301D01*
X3636560Y1219051D01*
X3636467Y1217926D01*
X3636653Y1216801D01*
X3636933Y1216051D01*
X3637493Y1215301D01*
X3638147Y1214801D01*
X3638800Y1214551D01*
X3639453D01*
X3640107Y1214801D01*
X3640667Y1215176D01*
X3641133Y1215676D01*
G01X3646300Y1214551D02*
X3645553Y1214676D01*
X3644900Y1215176D01*
X3644340Y1215926D01*
X3643967Y1216801D01*
X3643780Y1217801D01*
Y1218801D01*
X3643967Y1219801D01*
X3644340Y1220676D01*
X3644900Y1221426D01*
X3645553Y1221926D01*
X3646300Y1222051D01*
X3647047Y1221926D01*
X3647700Y1221426D01*
X3648260Y1220676D01*
X3648633Y1219801D01*
X3648820Y1218801D01*
Y1217801D01*
X3648633Y1216801D01*
X3648260Y1215926D01*
X3647700Y1215176D01*
X3647047Y1214676D01*
X3646300Y1214551D01*
G01X3651373D02*
Y1222051D01*
X3653800Y1215801D01*
X3656227Y1222051D01*
Y1214551D01*
G01X3658873D02*
Y1222051D01*
X3661300Y1215801D01*
X3663727Y1222051D01*
Y1214551D01*
G01X3670667D02*
X3666933D01*
Y1222051D01*
X3670667D01*
G01X3669173Y1218426D02*
X3666933D01*
G01X3674153Y1214551D02*
Y1222051D01*
X3678447Y1214551D01*
Y1222051D01*
G01X3681747Y1214551D02*
Y1222051D01*
X3683613D01*
X3684360Y1221676D01*
X3684920Y1221176D01*
X3685387Y1220426D01*
X3685760Y1219551D01*
X3685853Y1218301D01*
X3685760Y1217051D01*
X3685387Y1216176D01*
X3684920Y1215426D01*
X3684360Y1214926D01*
X3683613Y1214551D01*
X3681747D01*
G01X3693167D02*
X3689433D01*
Y1222051D01*
X3693167D01*
G01X3691673Y1218426D02*
X3689433D01*
G01X3696747Y1214551D02*
Y1222051D01*
X3698613D01*
X3699360Y1221676D01*
X3699920Y1221176D01*
X3700387Y1220426D01*
X3700760Y1219551D01*
X3700853Y1218301D01*
X3700760Y1217051D01*
X3700387Y1216176D01*
X3699920Y1215426D01*
X3699360Y1214926D01*
X3698613Y1214551D01*
X3696747D01*
G01X3711747D02*
Y1222051D01*
X3713613D01*
X3714360Y1221676D01*
X3714920Y1221176D01*
X3715387Y1220426D01*
X3715760Y1219551D01*
X3715853Y1218301D01*
X3715760Y1217051D01*
X3715387Y1216176D01*
X3714920Y1215426D01*
X3714360Y1214926D01*
X3713613Y1214551D01*
X3711747D01*
G01X3719433D02*
Y1222051D01*
X3721767D01*
X3722513Y1221676D01*
X3722980Y1221176D01*
X3723167Y1220176D01*
X3722980Y1219176D01*
X3722420Y1218551D01*
X3721767Y1218176D01*
X3719433D01*
G01X3721767D02*
X3723167Y1214551D01*
G01X3727680Y1222051D02*
X3729920D01*
G01X3728800D02*
Y1214551D01*
G01X3727680D02*
X3729920D01*
G01X3734433Y1222051D02*
Y1214551D01*
X3738167D01*
G01X3741933Y1222051D02*
Y1214551D01*
X3745667D01*
G01X3756840Y1215551D02*
X3757587Y1214926D01*
X3758427Y1214551D01*
X3759173D01*
X3759920Y1214926D01*
X3760480Y1215551D01*
X3760760Y1216426D01*
X3760573Y1217301D01*
X3760107Y1218051D01*
X3759267Y1218551D01*
X3758147Y1218801D01*
X3757493Y1219301D01*
X3757213Y1220176D01*
X3757400Y1221051D01*
X3757867Y1221676D01*
X3758520Y1222051D01*
X3759173D01*
X3759827Y1221801D01*
X3760387Y1221176D01*
G01X3765180Y1222051D02*
X3767420D01*
G01X3766300D02*
Y1214551D01*
G01X3765180D02*
X3767420D01*
G01X3772027Y1222051D02*
X3775573D01*
X3772027Y1214551D01*
X3775573D01*
G01X3783167D02*
X3779433D01*
Y1222051D01*
X3783167D01*
G01X3781673Y1218426D02*
X3779433D01*
G01X3794527Y1214551D02*
Y1222051D01*
X3798073D01*
G01X3796767Y1218426D02*
X3794527D01*
G01X3803800Y1214551D02*
X3803053Y1214676D01*
X3802400Y1215176D01*
X3801840Y1215926D01*
X3801467Y1216801D01*
X3801280Y1217801D01*
Y1218801D01*
X3801467Y1219801D01*
X3801840Y1220676D01*
X3802400Y1221426D01*
X3803053Y1221926D01*
X3803800Y1222051D01*
X3804547Y1221926D01*
X3805200Y1221426D01*
X3805760Y1220676D01*
X3806133Y1219801D01*
X3806320Y1218801D01*
Y1217801D01*
X3806133Y1216801D01*
X3805760Y1215926D01*
X3805200Y1215176D01*
X3804547Y1214676D01*
X3803800Y1214551D01*
G01X3809433D02*
Y1222051D01*
X3811767D01*
X3812513Y1221676D01*
X3812980Y1221176D01*
X3813167Y1220176D01*
X3812980Y1219176D01*
X3812420Y1218551D01*
X3811767Y1218176D01*
X3809433D01*
G01X3811767D02*
X3813167Y1214551D01*
G01X3826300Y1222051D02*
X3825553Y1221801D01*
X3824993Y1221176D01*
X3824620Y1220426D01*
X3824340Y1219426D01*
X3824247Y1218301D01*
X3824340Y1217176D01*
X3824620Y1216176D01*
X3824993Y1215426D01*
X3825553Y1214801D01*
X3826300Y1214551D01*
X3827047Y1214801D01*
X3827607Y1215426D01*
X3827980Y1216176D01*
X3828260Y1217176D01*
X3828353Y1218301D01*
X3828260Y1219426D01*
X3827980Y1220426D01*
X3827607Y1221176D01*
X3827047Y1221801D01*
X3826300Y1222051D01*
G01X3833800Y1214301D02*
X3833613Y1214426D01*
Y1214676D01*
X3833800Y1214801D01*
X3833987Y1214676D01*
Y1214426D01*
X3833800Y1214301D01*
G01X3839247Y1215676D02*
X3839807Y1215051D01*
X3840460Y1214676D01*
X3841300Y1214551D01*
X3842140Y1214801D01*
X3842793Y1215301D01*
X3843260Y1216176D01*
X3843353Y1217176D01*
X3843167Y1218176D01*
X3842700Y1218801D01*
X3842047Y1219301D01*
X3841393Y1219426D01*
X3840740Y1219301D01*
X3839900Y1218801D01*
X3840180Y1222051D01*
X3842700D01*
G01X3846373Y1214551D02*
Y1222051D01*
X3848800Y1215801D01*
X3851227Y1222051D01*
Y1214551D01*
G01X3853873D02*
Y1222051D01*
X3856300Y1215801D01*
X3858727Y1222051D01*
Y1214551D01*
G01X3869527D02*
Y1222051D01*
X3873073D01*
G01X3871767Y1218426D02*
X3869527D01*
G01X3877680Y1222051D02*
X3879920D01*
G01X3878800D02*
Y1214551D01*
G01X3877680D02*
X3879920D01*
G01X3884153D02*
Y1222051D01*
X3888447Y1214551D01*
Y1222051D01*
G01X3892680D02*
X3894920D01*
G01X3893800D02*
Y1214551D01*
G01X3892680D02*
X3894920D01*
G01X3899340Y1215551D02*
X3900087Y1214926D01*
X3900927Y1214551D01*
X3901673D01*
X3902420Y1214926D01*
X3902980Y1215551D01*
X3903260Y1216426D01*
X3903073Y1217301D01*
X3902607Y1218051D01*
X3901767Y1218551D01*
X3900647Y1218801D01*
X3899993Y1219301D01*
X3899713Y1220176D01*
X3899900Y1221051D01*
X3900367Y1221676D01*
X3901020Y1222051D01*
X3901673D01*
X3902327Y1221801D01*
X3902887Y1221176D01*
G01X3906840Y1214551D02*
Y1222051D01*
G01X3910760D02*
Y1214551D01*
G01Y1218301D02*
X3906840D01*
G01X3918167Y1214551D02*
X3914433D01*
Y1222051D01*
X3918167D01*
G01X3916673Y1218426D02*
X3914433D01*
G01X3921747Y1214551D02*
Y1222051D01*
X3923613D01*
X3924360Y1221676D01*
X3924920Y1221176D01*
X3925387Y1220426D01*
X3925760Y1219551D01*
X3925853Y1218301D01*
X3925760Y1217051D01*
X3925387Y1216176D01*
X3924920Y1215426D01*
X3924360Y1214926D01*
X3923613Y1214551D01*
X3921747D01*
G01X3936933D02*
Y1222051D01*
X3939173D01*
X3939920Y1221676D01*
X3940480Y1220801D01*
X3940667Y1219801D01*
X3940480Y1218801D01*
X3940013Y1218051D01*
X3939173Y1217676D01*
X3936933D01*
G01X3946300Y1222051D02*
Y1214551D01*
G01X3944153Y1222051D02*
X3948447D01*
G01X3951840Y1214551D02*
Y1222051D01*
G01X3955760D02*
Y1214551D01*
G01Y1218301D02*
X3951840D01*
G01X3967680Y1222051D02*
X3969920D01*
G01X3968800D02*
Y1214551D01*
G01X3967680D02*
X3969920D01*
G01X3974340Y1215551D02*
X3975087Y1214926D01*
X3975927Y1214551D01*
X3976673D01*
X3977420Y1214926D01*
X3977980Y1215551D01*
X3978260Y1216426D01*
X3978073Y1217301D01*
X3977607Y1218051D01*
X3976767Y1218551D01*
X3975647Y1218801D01*
X3974993Y1219301D01*
X3974713Y1220176D01*
X3974900Y1221051D01*
X3975367Y1221676D01*
X3976020Y1222051D01*
X3976673D01*
X3977327Y1221801D01*
X3977887Y1221176D01*
G01X3991300Y1222051D02*
X3990553Y1221801D01*
X3989993Y1221176D01*
X3989620Y1220426D01*
X3989340Y1219426D01*
X3989247Y1218301D01*
X3989340Y1217176D01*
X3989620Y1216176D01*
X3989993Y1215426D01*
X3990553Y1214801D01*
X3991300Y1214551D01*
X3992047Y1214801D01*
X3992607Y1215426D01*
X3992980Y1216176D01*
X3993260Y1217176D01*
X3993353Y1218301D01*
X3993260Y1219426D01*
X3992980Y1220426D01*
X3992607Y1221176D01*
X3992047Y1221801D01*
X3991300Y1222051D01*
G01X3998800Y1214301D02*
X3998613Y1214426D01*
Y1214676D01*
X3998800Y1214801D01*
X3998987Y1214676D01*
Y1214426D01*
X3998800Y1214301D01*
G01X4004527Y1217676D02*
X4005180Y1218551D01*
X4005740Y1219051D01*
X4006487Y1219301D01*
X4007140Y1219051D01*
X4007607Y1218551D01*
X4007980Y1217801D01*
X4008073Y1216926D01*
X4007980Y1216176D01*
X4007607Y1215426D01*
X4007047Y1214801D01*
X4006393Y1214551D01*
X4005647Y1214801D01*
X4004993Y1215551D01*
X4004620Y1216676D01*
X4004527Y1217926D01*
X4004713Y1219551D01*
X4004993Y1220426D01*
X4005460Y1221301D01*
X4006113Y1221926D01*
X4006767Y1222051D01*
X4007420Y1221801D01*
X4007887Y1221176D01*
G01X4011373Y1214551D02*
Y1222051D01*
X4013800Y1215801D01*
X4016227Y1222051D01*
Y1214551D01*
G01X4018873D02*
Y1222051D01*
X4021300Y1215801D01*
X4023727Y1222051D01*
Y1214551D01*
G01X4033873D02*
Y1222051D01*
X4036300Y1215801D01*
X4038727Y1222051D01*
Y1214551D01*
G01X4045667D02*
X4041933D01*
Y1222051D01*
X4045667D01*
G01X4044173Y1218426D02*
X4041933D01*
G01X4051300Y1222051D02*
Y1214551D01*
G01X4049153Y1222051D02*
X4053447D01*
G01X4056933Y1214551D02*
Y1222051D01*
X4059267D01*
X4060013Y1221676D01*
X4060480Y1221176D01*
X4060667Y1220176D01*
X4060480Y1219176D01*
X4059920Y1218551D01*
X4059267Y1218176D01*
X4056933D01*
G01X4059267D02*
X4060667Y1214551D01*
G01X4065180Y1222051D02*
X4067420D01*
G01X4066300D02*
Y1214551D01*
G01X4065180D02*
X4067420D01*
G01X4075853Y1221426D02*
X4075293Y1221801D01*
X4074640Y1222051D01*
X4073893D01*
X4073053Y1221676D01*
X4072400Y1221051D01*
X4071933Y1220301D01*
X4071560Y1219051D01*
X4071467Y1217926D01*
X4071653Y1216801D01*
X4071933Y1216051D01*
X4072493Y1215301D01*
X4073147Y1214801D01*
X4073800Y1214551D01*
X4074453D01*
X4075107Y1214801D01*
X4075667Y1215176D01*
X4076133Y1215676D01*
G01X4086747Y1214551D02*
Y1222051D01*
X4088613D01*
X4089360Y1221676D01*
X4089920Y1221176D01*
X4090387Y1220426D01*
X4090760Y1219551D01*
X4090853Y1218301D01*
X4090760Y1217051D01*
X4090387Y1216176D01*
X4089920Y1215426D01*
X4089360Y1214926D01*
X4088613Y1214551D01*
X4086747D01*
G01X4094433D02*
Y1222051D01*
X4096767D01*
X4097513Y1221676D01*
X4097980Y1221176D01*
X4098167Y1220176D01*
X4097980Y1219176D01*
X4097420Y1218551D01*
X4096767Y1218176D01*
X4094433D01*
G01X4096767D02*
X4098167Y1214551D01*
G01X4102680Y1222051D02*
X4104920D01*
G01X4103800D02*
Y1214551D01*
G01X4102680D02*
X4104920D01*
G01X4109433Y1222051D02*
Y1214551D01*
X4113167D01*
G01X4116933Y1222051D02*
Y1214551D01*
X4120667D01*
G01X4125833Y1212051D02*
X4124900Y1213301D01*
X4124433Y1214551D01*
Y1219551D01*
X4124900Y1220801D01*
X4125833Y1222051D01*
G01X4133800D02*
X4133053Y1221801D01*
X4132493Y1221176D01*
X4132120Y1220426D01*
X4131840Y1219426D01*
X4131747Y1218301D01*
X4131840Y1217176D01*
X4132120Y1216176D01*
X4132493Y1215426D01*
X4133053Y1214801D01*
X4133800Y1214551D01*
X4134547Y1214801D01*
X4135107Y1215426D01*
X4135480Y1216176D01*
X4135760Y1217176D01*
X4135853Y1218301D01*
X4135760Y1219426D01*
X4135480Y1220426D01*
X4135107Y1221176D01*
X4134547Y1221801D01*
X4133800Y1222051D01*
G01X4141300Y1214301D02*
X4141113Y1214426D01*
Y1214676D01*
X4141300Y1214801D01*
X4141487Y1214676D01*
Y1214426D01*
X4141300Y1214301D01*
G01X4148800Y1222051D02*
X4148053Y1221801D01*
X4147493Y1221176D01*
X4147120Y1220426D01*
X4146840Y1219426D01*
X4146747Y1218301D01*
X4146840Y1217176D01*
X4147120Y1216176D01*
X4147493Y1215426D01*
X4148053Y1214801D01*
X4148800Y1214551D01*
X4149547Y1214801D01*
X4150107Y1215426D01*
X4150480Y1216176D01*
X4150760Y1217176D01*
X4150853Y1218301D01*
X4150760Y1219426D01*
X4150480Y1220426D01*
X4150107Y1221176D01*
X4149547Y1221801D01*
X4148800Y1222051D01*
G01X4154527Y1220801D02*
X4155087Y1221551D01*
X4155740Y1221926D01*
X4156487Y1222051D01*
X4157420Y1221801D01*
X4158073Y1221176D01*
X4158260Y1220426D01*
X4158167Y1219676D01*
X4157793Y1219051D01*
X4155927Y1217801D01*
X4155087Y1216926D01*
X4154527Y1215676D01*
X4154340Y1214551D01*
X4158260D01*
G01X4161747Y1216051D02*
X4162307Y1215176D01*
X4163053Y1214676D01*
X4163893Y1214551D01*
X4164640Y1214676D01*
X4165387Y1215301D01*
X4165853Y1216051D01*
X4165947Y1216801D01*
X4165760Y1217676D01*
X4165107Y1218301D01*
X4164453Y1218551D01*
X4163613D01*
G01X4164453D02*
X4165013Y1218926D01*
X4165480Y1219551D01*
X4165667Y1220301D01*
X4165480Y1221051D01*
X4165013Y1221676D01*
X4164173Y1222051D01*
X4163333Y1221926D01*
X4162493Y1221426D01*
G01X4169527Y1217676D02*
X4170180Y1218551D01*
X4170740Y1219051D01*
X4171487Y1219301D01*
X4172140Y1219051D01*
X4172607Y1218551D01*
X4172980Y1217801D01*
X4173073Y1216926D01*
X4172980Y1216176D01*
X4172607Y1215426D01*
X4172047Y1214801D01*
X4171393Y1214551D01*
X4170647Y1214801D01*
X4169993Y1215551D01*
X4169620Y1216676D01*
X4169527Y1217926D01*
X4169713Y1219551D01*
X4169993Y1220426D01*
X4170460Y1221301D01*
X4171113Y1221926D01*
X4171767Y1222051D01*
X4172420Y1221801D01*
X4172887Y1221176D01*
G01X4177960Y1220426D02*
X4178427Y1222051D01*
G01X4179640D02*
X4179173Y1220426D01*
G01X4186767Y1212051D02*
X4187700Y1213301D01*
X4188167Y1214551D01*
Y1219551D01*
X4187700Y1220801D01*
X4186767Y1222051D01*
G01X4193800Y1214301D02*
X4193613Y1214426D01*
Y1214676D01*
X4193800Y1214801D01*
X4193987Y1214676D01*
Y1214426D01*
X4193800Y1214301D01*
G01X4421060Y7773D02*
X4421680Y8398D01*
X4422145Y9439D01*
X4422455Y10898D01*
X4422145Y12148D01*
X4421525Y12981D01*
X4420440Y13606D01*
X4416255D01*
Y1106D01*
X4421370D01*
X4422455Y1939D01*
X4423075Y3189D01*
X4423385Y4648D01*
X4423075Y6106D01*
X4422145Y7356D01*
X4421060Y7773D01*
X4416255D01*
G01X4428345Y1106D02*
X4432220Y13606D01*
X4436095Y1106D01*
G01X4434700Y5481D02*
X4429740D01*
G01X4448030Y12564D02*
X4447100Y13189D01*
X4446015Y13606D01*
X4444775D01*
X4443380Y12981D01*
X4442295Y11939D01*
X4441520Y10689D01*
X4440900Y8606D01*
X4440745Y6731D01*
X4441055Y4856D01*
X4441520Y3606D01*
X4442450Y2356D01*
X4443535Y1523D01*
X4444620Y1106D01*
X4445705D01*
X4446790Y1523D01*
X4447720Y2147D01*
X4448495Y2981D01*
G01X4453610Y1106D02*
Y13606D01*
G01X4459500D02*
X4453610Y5897D01*
G01X4460430Y1106D02*
X4456245Y9439D01*
G01X4466010Y1106D02*
Y13606D01*
X4469110D01*
X4470350Y12981D01*
X4471280Y12148D01*
X4472055Y10898D01*
X4472675Y9439D01*
X4472830Y7356D01*
X4472675Y5273D01*
X4472055Y3814D01*
X4471280Y2564D01*
X4470350Y1731D01*
X4469110Y1106D01*
X4466010D01*
G01X4478720D02*
Y13606D01*
X4482595D01*
X4483835Y12981D01*
X4484610Y12148D01*
X4484920Y10481D01*
X4484610Y8814D01*
X4483680Y7773D01*
X4482595Y7148D01*
X4478720D01*
G01X4482595D02*
X4484920Y1106D01*
G01X4492360Y13606D02*
X4496080D01*
G01X4494220D02*
Y1106D01*
G01X4492360D02*
X4496080D01*
G01X4503520Y13606D02*
Y1106D01*
X4509720D01*
G01X4515920Y13606D02*
Y1106D01*
X4522120D01*
G01X4540565Y2772D02*
X4541805Y1731D01*
X4543200Y1106D01*
X4544440D01*
X4545680Y1731D01*
X4546610Y2772D01*
X4547075Y4231D01*
X4546765Y5689D01*
X4545990Y6939D01*
X4544595Y7773D01*
X4542735Y8189D01*
X4541650Y9023D01*
X4541185Y10481D01*
X4541495Y11939D01*
X4542270Y12981D01*
X4543355Y13606D01*
X4544440D01*
X4545525Y13189D01*
X4546455Y12148D01*
G01X4556220Y13606D02*
Y1106D01*
G01X4552655Y13606D02*
X4559785D01*
G01X4565210D02*
Y4648D01*
X4565830Y2772D01*
X4567070Y1523D01*
X4568620Y1106D01*
X4570170Y1523D01*
X4571410Y2772D01*
X4572030Y4648D01*
Y13606D01*
G01X4582260Y7773D02*
X4582880Y8398D01*
X4583345Y9439D01*
X4583655Y10898D01*
X4583345Y12148D01*
X4582725Y12981D01*
X4581640Y13606D01*
X4577455D01*
Y1106D01*
X4582570D01*
X4583655Y1939D01*
X4584275Y3189D01*
X4584585Y4648D01*
X4584275Y6106D01*
X4583345Y7356D01*
X4582260Y7773D01*
X4577455D01*
G01X4602720Y13606D02*
Y1106D01*
X4608920D01*
G01X4621320D02*
X4615120D01*
Y13606D01*
X4621320D01*
G01X4618840Y7564D02*
X4615120D01*
G01X4627055Y1106D02*
Y13606D01*
X4634185Y1106D01*
Y13606D01*
G01X4643950Y7356D02*
X4647050D01*
Y3606D01*
X4646120Y2356D01*
X4645035Y1523D01*
X4643485Y1106D01*
X4641935Y1523D01*
X4640850Y2356D01*
X4639920Y3606D01*
X4639300Y5064D01*
X4638990Y6731D01*
Y8189D01*
X4639300Y9439D01*
X4639920Y10898D01*
X4640850Y12148D01*
X4641780Y12981D01*
X4643020Y13606D01*
X4644105D01*
X4645345Y13189D01*
X4646275Y12356D01*
G01X4655420Y13606D02*
Y1106D01*
G01X4651855Y13606D02*
X4658985D01*
G01X4664565Y1106D02*
Y13606D01*
G01X4671075D02*
Y1106D01*
G01Y7356D02*
X4664565D01*
G01X4692620Y13606D02*
Y1106D01*
G01X4689055Y13606D02*
X4696185D01*
G01X4705020Y1106D02*
X4703780Y1314D01*
X4702695Y2147D01*
X4701765Y3398D01*
X4701145Y4856D01*
X4700835Y6523D01*
Y8189D01*
X4701145Y9856D01*
X4701765Y11314D01*
X4702695Y12564D01*
X4703780Y13398D01*
X4705020Y13606D01*
X4706260Y13398D01*
X4707345Y12564D01*
X4708275Y11314D01*
X4708895Y9856D01*
X4709205Y8189D01*
Y6523D01*
X4708895Y4856D01*
X4708275Y3398D01*
X4707345Y2147D01*
X4706260Y1314D01*
X4705020Y1106D01*
G01X4714320Y13606D02*
Y1106D01*
X4720520D01*
G01X4732920D02*
X4726720D01*
Y13606D01*
X4732920D01*
G01X4730440Y7564D02*
X4726720D01*
G01X4739120Y1106D02*
Y13606D01*
X4742995D01*
X4744235Y12981D01*
X4745010Y12148D01*
X4745320Y10481D01*
X4745010Y8814D01*
X4744080Y7773D01*
X4742995Y7148D01*
X4739120D01*
G01X4742995D02*
X4745320Y1106D01*
G01X4750745D02*
X4754620Y13606D01*
X4758495Y1106D01*
G01X4757100Y5481D02*
X4752140D01*
G01X4763455Y1106D02*
Y13606D01*
X4770585Y1106D01*
Y13606D01*
G01X4782830Y12564D02*
X4781900Y13189D01*
X4780815Y13606D01*
X4779575D01*
X4778180Y12981D01*
X4777095Y11939D01*
X4776320Y10689D01*
X4775700Y8606D01*
X4775545Y6731D01*
X4775855Y4856D01*
X4776320Y3606D01*
X4777250Y2356D01*
X4778335Y1523D01*
X4779420Y1106D01*
X4780505D01*
X4781590Y1523D01*
X4782520Y2147D01*
X4783295Y2981D01*
G01X4794920Y1106D02*
X4788720D01*
Y13606D01*
X4794920D01*
G01X4792440Y7564D02*
X4788720D01*
G01X4816620Y13606D02*
Y1106D01*
G01X4813055Y13606D02*
X4820185D01*
G01X4829020Y1106D02*
X4827780Y1314D01*
X4826695Y2147D01*
X4825765Y3398D01*
X4825145Y4856D01*
X4824835Y6523D01*
Y8189D01*
X4825145Y9856D01*
X4825765Y11314D01*
X4826695Y12564D01*
X4827780Y13398D01*
X4829020Y13606D01*
X4830260Y13398D01*
X4831345Y12564D01*
X4832275Y11314D01*
X4832895Y9856D01*
X4833205Y8189D01*
Y6523D01*
X4832895Y4856D01*
X4832275Y3398D01*
X4831345Y2147D01*
X4830260Y1314D01*
X4829020Y1106D01*
G01X4855060Y7773D02*
X4855680Y8398D01*
X4856145Y9439D01*
X4856455Y10898D01*
X4856145Y12148D01*
X4855525Y12981D01*
X4854440Y13606D01*
X4850255D01*
Y1106D01*
X4855370D01*
X4856455Y1939D01*
X4857075Y3189D01*
X4857385Y4648D01*
X4857075Y6106D01*
X4856145Y7356D01*
X4855060Y7773D01*
X4850255D01*
G01X4869320Y1106D02*
X4863120D01*
Y13606D01*
X4869320D01*
G01X4866840Y7564D02*
X4863120D01*
G01X4890710Y1106D02*
X4891020Y3814D01*
X4891485Y6106D01*
X4892105Y8189D01*
X4892880Y10481D01*
X4894120Y13606D01*
X4887920D01*
G01X4914115Y5273D02*
X4917835D01*
G01X4915820Y7981D02*
Y2564D01*
G01X4925430Y689D02*
X4931010Y13606D01*
G01X4938605Y5273D02*
X4942635D01*
G01X4949610Y2981D02*
X4950540Y1939D01*
X4951625Y1314D01*
X4953020Y1106D01*
X4954415Y1523D01*
X4955500Y2356D01*
X4956275Y3814D01*
X4956430Y5481D01*
X4956120Y7148D01*
X4955345Y8189D01*
X4954260Y9023D01*
X4953175Y9231D01*
X4952090Y9023D01*
X4950695Y8189D01*
X4951160Y13606D01*
X4955345D01*
G01X4973790Y1106D02*
Y13606D01*
X4977820Y3189D01*
X4981850Y13606D01*
Y1106D01*
G01X4988360Y13606D02*
X4992080D01*
G01X4990220D02*
Y1106D01*
G01X4988360D02*
X4992080D01*
G01X4999520Y13606D02*
Y1106D01*
X5005720D01*
G01X5011765Y2772D02*
X5013005Y1731D01*
X5014400Y1106D01*
X5015640D01*
X5016880Y1731D01*
X5017810Y2772D01*
X5018275Y4231D01*
X5017965Y5689D01*
X5017190Y6939D01*
X5015795Y7773D01*
X5013935Y8189D01*
X5012850Y9023D01*
X5012385Y10481D01*
X5012695Y11939D01*
X5013470Y12981D01*
X5014555Y13606D01*
X5015640D01*
X5016725Y13189D01*
X5017655Y12148D01*
G01X4256605Y24023D02*
X4260635D01*
G01X4279390Y19856D02*
Y32356D01*
X4283420Y21939D01*
X4287450Y32356D01*
Y19856D01*
G01X4292875D02*
Y32356D01*
X4298765D01*
G01X4296595Y26314D02*
X4292875D01*
G01X4309150Y26106D02*
X4312250D01*
Y22356D01*
X4311320Y21106D01*
X4310235Y20273D01*
X4308685Y19856D01*
X4307135Y20273D01*
X4306050Y21106D01*
X4305120Y22356D01*
X4304500Y23814D01*
X4304190Y25481D01*
Y26939D01*
X4304500Y28189D01*
X4305120Y29648D01*
X4306050Y30898D01*
X4306980Y31731D01*
X4308220Y32356D01*
X4309305D01*
X4310545Y31939D01*
X4311475Y31106D01*
G01X4315970Y15689D02*
X4325270D01*
G01X4329765Y21522D02*
X4331005Y20481D01*
X4332400Y19856D01*
X4333640D01*
X4334880Y20481D01*
X4335810Y21522D01*
X4336275Y22981D01*
X4335965Y24439D01*
X4335190Y25689D01*
X4333795Y26523D01*
X4331935Y26939D01*
X4330850Y27773D01*
X4330385Y29231D01*
X4330695Y30689D01*
X4331470Y31731D01*
X4332555Y32356D01*
X4333640D01*
X4334725Y31939D01*
X4335655Y30898D01*
G01X4345420Y32356D02*
Y19856D01*
G01X4341855Y32356D02*
X4348985D01*
G01X4354410D02*
Y23398D01*
X4355030Y21522D01*
X4356270Y20273D01*
X4357820Y19856D01*
X4359370Y20273D01*
X4360610Y21522D01*
X4361230Y23398D01*
Y32356D01*
G01X4371460Y26523D02*
X4372080Y27148D01*
X4372545Y28189D01*
X4372855Y29648D01*
X4372545Y30898D01*
X4371925Y31731D01*
X4370840Y32356D01*
X4366655D01*
Y19856D01*
X4371770D01*
X4372855Y20689D01*
X4373475Y21939D01*
X4373785Y23398D01*
X4373475Y24856D01*
X4372545Y26106D01*
X4371460Y26523D01*
X4366655D01*
G01X4395020Y19439D02*
X4394710Y19648D01*
Y20064D01*
X4395020Y20273D01*
X4395330Y20064D01*
Y19648D01*
X4395020Y19439D01*
G01Y25064D02*
X4394710Y25273D01*
Y25689D01*
X4395020Y25898D01*
X4395330Y25689D01*
Y25273D01*
X4395020Y25064D01*
G01X4415790Y19856D02*
Y32356D01*
X4419820Y21939D01*
X4423850Y32356D01*
Y19856D01*
G01X4428345D02*
X4432220Y32356D01*
X4436095Y19856D01*
G01X4434700Y24231D02*
X4429740D01*
G01X4441055Y19856D02*
Y32356D01*
X4448185Y19856D01*
Y32356D01*
G01X4453610D02*
Y23398D01*
X4454230Y21522D01*
X4455470Y20273D01*
X4457020Y19856D01*
X4458570Y20273D01*
X4459810Y21522D01*
X4460430Y23398D01*
Y32356D01*
G01X4466475Y19856D02*
Y32356D01*
X4472365D01*
G01X4470195Y26314D02*
X4466475D01*
G01X4477945Y19856D02*
X4481820Y32356D01*
X4485695Y19856D01*
G01X4484300Y24231D02*
X4479340D01*
G01X4497630Y31314D02*
X4496700Y31939D01*
X4495615Y32356D01*
X4494375D01*
X4492980Y31731D01*
X4491895Y30689D01*
X4491120Y29439D01*
X4490500Y27356D01*
X4490345Y25481D01*
X4490655Y23606D01*
X4491120Y22356D01*
X4492050Y21106D01*
X4493135Y20273D01*
X4494220Y19856D01*
X4495305D01*
X4496390Y20273D01*
X4497320Y20897D01*
X4498095Y21731D01*
G01X4506620Y32356D02*
Y19856D01*
G01X4503055Y32356D02*
X4510185D01*
G01X4515610D02*
Y23398D01*
X4516230Y21522D01*
X4517470Y20273D01*
X4519020Y19856D01*
X4520570Y20273D01*
X4521810Y21522D01*
X4522430Y23398D01*
Y32356D01*
G01X4528320Y19856D02*
Y32356D01*
X4532195D01*
X4533435Y31731D01*
X4534210Y30898D01*
X4534520Y29231D01*
X4534210Y27564D01*
X4533280Y26523D01*
X4532195Y25898D01*
X4528320D01*
G01X4532195D02*
X4534520Y19856D01*
G01X4541960Y32356D02*
X4545680D01*
G01X4543820D02*
Y19856D01*
G01X4541960D02*
X4545680D01*
G01X4552655D02*
Y32356D01*
X4559785Y19856D01*
Y32356D01*
G01X4569550Y26106D02*
X4572650D01*
Y22356D01*
X4571720Y21106D01*
X4570635Y20273D01*
X4569085Y19856D01*
X4567535Y20273D01*
X4566450Y21106D01*
X4565520Y22356D01*
X4564900Y23814D01*
X4564590Y25481D01*
Y26939D01*
X4564900Y28189D01*
X4565520Y29648D01*
X4566450Y30898D01*
X4567380Y31731D01*
X4568620Y32356D01*
X4569705D01*
X4570945Y31939D01*
X4571875Y31106D01*
G01X4590165Y21522D02*
X4591405Y20481D01*
X4592800Y19856D01*
X4594040D01*
X4595280Y20481D01*
X4596210Y21522D01*
X4596675Y22981D01*
X4596365Y24439D01*
X4595590Y25689D01*
X4594195Y26523D01*
X4592335Y26939D01*
X4591250Y27773D01*
X4590785Y29231D01*
X4591095Y30689D01*
X4591870Y31731D01*
X4592955Y32356D01*
X4594040D01*
X4595125Y31939D01*
X4596055Y30898D01*
G01X4605820Y32356D02*
Y19856D01*
G01X4602255Y32356D02*
X4609385D01*
G01X4614810D02*
Y23398D01*
X4615430Y21522D01*
X4616670Y20273D01*
X4618220Y19856D01*
X4619770Y20273D01*
X4621010Y21522D01*
X4621630Y23398D01*
Y32356D01*
G01X4631860Y26523D02*
X4632480Y27148D01*
X4632945Y28189D01*
X4633255Y29648D01*
X4632945Y30898D01*
X4632325Y31731D01*
X4631240Y32356D01*
X4627055D01*
Y19856D01*
X4632170D01*
X4633255Y20689D01*
X4633875Y21939D01*
X4634185Y23398D01*
X4633875Y24856D01*
X4632945Y26106D01*
X4631860Y26523D01*
X4627055D01*
G01X4652320Y32356D02*
Y19856D01*
X4658520D01*
G01X4670920D02*
X4664720D01*
Y32356D01*
X4670920D01*
G01X4668440Y26314D02*
X4664720D01*
G01X4676655Y19856D02*
Y32356D01*
X4683785Y19856D01*
Y32356D01*
G01X4693550Y26106D02*
X4696650D01*
Y22356D01*
X4695720Y21106D01*
X4694635Y20273D01*
X4693085Y19856D01*
X4691535Y20273D01*
X4690450Y21106D01*
X4689520Y22356D01*
X4688900Y23814D01*
X4688590Y25481D01*
Y26939D01*
X4688900Y28189D01*
X4689520Y29648D01*
X4690450Y30898D01*
X4691380Y31731D01*
X4692620Y32356D01*
X4693705D01*
X4694945Y31939D01*
X4695875Y31106D01*
G01X4705020Y32356D02*
Y19856D01*
G01X4701455Y32356D02*
X4708585D01*
G01X4714165Y19856D02*
Y32356D01*
G01X4720675D02*
Y19856D01*
G01Y26106D02*
X4714165D01*
G01X4416565Y40272D02*
X4417805Y39231D01*
X4419200Y38606D01*
X4420440D01*
X4421680Y39231D01*
X4422610Y40272D01*
X4423075Y41731D01*
X4422765Y43189D01*
X4421990Y44439D01*
X4420595Y45273D01*
X4418735Y45689D01*
X4417650Y46523D01*
X4417185Y47981D01*
X4417495Y49439D01*
X4418270Y50481D01*
X4419355Y51106D01*
X4420440D01*
X4421525Y50689D01*
X4422455Y49648D01*
G01X4428810Y51106D02*
Y42148D01*
X4429430Y40272D01*
X4430670Y39023D01*
X4432220Y38606D01*
X4433770Y39023D01*
X4435010Y40272D01*
X4435630Y42148D01*
Y51106D01*
G01X4441520Y38606D02*
Y51106D01*
X4445395D01*
X4446635Y50481D01*
X4447410Y49648D01*
X4447720Y47981D01*
X4447410Y46314D01*
X4446480Y45273D01*
X4445395Y44648D01*
X4441520D01*
G01X4445395D02*
X4447720Y38606D01*
G01X4454075D02*
Y51106D01*
X4459965D01*
G01X4457795Y45064D02*
X4454075D01*
G01X4465545Y38606D02*
X4469420Y51106D01*
X4473295Y38606D01*
G01X4471900Y42981D02*
X4466940D01*
G01X4485230Y50064D02*
X4484300Y50689D01*
X4483215Y51106D01*
X4481975D01*
X4480580Y50481D01*
X4479495Y49439D01*
X4478720Y48189D01*
X4478100Y46106D01*
X4477945Y44231D01*
X4478255Y42356D01*
X4478720Y41106D01*
X4479650Y39856D01*
X4480735Y39023D01*
X4481820Y38606D01*
X4482905D01*
X4483990Y39023D01*
X4484920Y39647D01*
X4485695Y40481D01*
G01X4497320Y38606D02*
X4491120D01*
Y51106D01*
X4497320D01*
G01X4494840Y45064D02*
X4491120D01*
G01X4519020Y38606D02*
X4517780Y38814D01*
X4516695Y39647D01*
X4515765Y40898D01*
X4515145Y42356D01*
X4514835Y44023D01*
Y45689D01*
X4515145Y47356D01*
X4515765Y48814D01*
X4516695Y50064D01*
X4517780Y50898D01*
X4519020Y51106D01*
X4520260Y50898D01*
X4521345Y50064D01*
X4522275Y48814D01*
X4522895Y47356D01*
X4523205Y45689D01*
Y44023D01*
X4522895Y42356D01*
X4522275Y40898D01*
X4521345Y39647D01*
X4520260Y38814D01*
X4519020Y38606D01*
G01X4528475D02*
Y51106D01*
X4534365D01*
G01X4532195Y45064D02*
X4528475D01*
G01X4552190Y38606D02*
Y51106D01*
X4556220Y40689D01*
X4560250Y51106D01*
Y38606D01*
G01X4565210Y51106D02*
Y42148D01*
X4565830Y40272D01*
X4567070Y39023D01*
X4568620Y38606D01*
X4570170Y39023D01*
X4571410Y40272D01*
X4572030Y42148D01*
Y51106D01*
G01X4577765Y40272D02*
X4579005Y39231D01*
X4580400Y38606D01*
X4581640D01*
X4582880Y39231D01*
X4583810Y40272D01*
X4584275Y41731D01*
X4583965Y43189D01*
X4583190Y44439D01*
X4581795Y45273D01*
X4579935Y45689D01*
X4578850Y46523D01*
X4578385Y47981D01*
X4578695Y49439D01*
X4579470Y50481D01*
X4580555Y51106D01*
X4581640D01*
X4582725Y50689D01*
X4583655Y49648D01*
G01X4593420Y51106D02*
Y38606D01*
G01X4589855Y51106D02*
X4596985D01*
G01X4603805Y42773D02*
X4607835D01*
G01X4614655Y38606D02*
Y51106D01*
X4621785Y38606D01*
Y51106D01*
G01X4630620Y38606D02*
X4629380Y38814D01*
X4628295Y39647D01*
X4627365Y40898D01*
X4626745Y42356D01*
X4626435Y44023D01*
Y45689D01*
X4626745Y47356D01*
X4627365Y48814D01*
X4628295Y50064D01*
X4629380Y50898D01*
X4630620Y51106D01*
X4631860Y50898D01*
X4632945Y50064D01*
X4633875Y48814D01*
X4634495Y47356D01*
X4634805Y45689D01*
Y44023D01*
X4634495Y42356D01*
X4633875Y40898D01*
X4632945Y39647D01*
X4631860Y38814D01*
X4630620Y38606D01*
G01X4643020Y51106D02*
Y38606D01*
G01X4639455Y51106D02*
X4646585D01*
G01X4653405Y42773D02*
X4657435D01*
G01X4671230Y50064D02*
X4670300Y50689D01*
X4669215Y51106D01*
X4667975D01*
X4666580Y50481D01*
X4665495Y49439D01*
X4664720Y48189D01*
X4664100Y46106D01*
X4663945Y44231D01*
X4664255Y42356D01*
X4664720Y41106D01*
X4665650Y39856D01*
X4666735Y39023D01*
X4667820Y38606D01*
X4668905D01*
X4669990Y39023D01*
X4670920Y39647D01*
X4671695Y40481D01*
G01X4676810Y51106D02*
Y42148D01*
X4677430Y40272D01*
X4678670Y39023D01*
X4680220Y38606D01*
X4681770Y39023D01*
X4683010Y40272D01*
X4683630Y42148D01*
Y51106D01*
G01X4692620D02*
Y38606D01*
G01X4689055Y51106D02*
X4696185D01*
G01X4703005Y42773D02*
X4707035D01*
G01X4714320Y51106D02*
Y38606D01*
X4720520D01*
G01X4725945D02*
X4729820Y51106D01*
X4733695Y38606D01*
G01X4732300Y42981D02*
X4727340D01*
G01X4742220Y38606D02*
Y44231D01*
X4739120Y51106D01*
G01X4745320D02*
X4742220Y44231D01*
G01X4757720Y38606D02*
X4751520D01*
Y51106D01*
X4757720D01*
G01X4755240Y45064D02*
X4751520D01*
G01X4763920Y38606D02*
Y51106D01*
X4767795D01*
X4769035Y50481D01*
X4769810Y49648D01*
X4770120Y47981D01*
X4769810Y46314D01*
X4768880Y45273D01*
X4767795Y44648D01*
X4763920D01*
G01X4767795D02*
X4770120Y38606D01*
G01X4256605Y61523D02*
X4260635D01*
G01X4279390Y57356D02*
Y69856D01*
X4283420Y59439D01*
X4287450Y69856D01*
Y57356D01*
G01X4291945D02*
X4295820Y69856D01*
X4299695Y57356D01*
G01X4298300Y61731D02*
X4293340D01*
G01X4304965Y57356D02*
X4311475Y69856D01*
G01X4304965D02*
X4311475Y57356D01*
G01X4315970Y53189D02*
X4325270D01*
G01X4329610Y57356D02*
Y69856D01*
X4332710D01*
X4333950Y69231D01*
X4334880Y68398D01*
X4335655Y67148D01*
X4336275Y65689D01*
X4336430Y63606D01*
X4336275Y61523D01*
X4335655Y60064D01*
X4334880Y58814D01*
X4333950Y57981D01*
X4332710Y57356D01*
X4329610D01*
G01X4348520D02*
X4342320D01*
Y69856D01*
X4348520D01*
G01X4346040Y63814D02*
X4342320D01*
G01X4354720Y57356D02*
Y69856D01*
X4358440D01*
X4359680Y69231D01*
X4360610Y67773D01*
X4360920Y66106D01*
X4360610Y64439D01*
X4359835Y63189D01*
X4358440Y62564D01*
X4354720D01*
G01X4370220Y69856D02*
Y57356D01*
G01X4366655Y69856D02*
X4373785D01*
G01X4379365Y57356D02*
Y69856D01*
G01X4385875D02*
Y57356D01*
G01Y63606D02*
X4379365D01*
G01X4395020Y56939D02*
X4394710Y57148D01*
Y57564D01*
X4395020Y57773D01*
X4395330Y57564D01*
Y57148D01*
X4395020Y56939D01*
G01Y62564D02*
X4394710Y62773D01*
Y63189D01*
X4395020Y63398D01*
X4395330Y63189D01*
Y62773D01*
X4395020Y62564D01*
G01X4416410Y57356D02*
Y69856D01*
X4419510D01*
X4420750Y69231D01*
X4421680Y68398D01*
X4422455Y67148D01*
X4423075Y65689D01*
X4423230Y63606D01*
X4423075Y61523D01*
X4422455Y60064D01*
X4421680Y58814D01*
X4420750Y57981D01*
X4419510Y57356D01*
X4416410D01*
G01X4435320D02*
X4429120D01*
Y69856D01*
X4435320D01*
G01X4432840Y63814D02*
X4429120D01*
G01X4441520Y57356D02*
Y69856D01*
X4445240D01*
X4446480Y69231D01*
X4447410Y67773D01*
X4447720Y66106D01*
X4447410Y64439D01*
X4446635Y63189D01*
X4445240Y62564D01*
X4441520D01*
G01X4457020Y69856D02*
Y57356D01*
G01X4453455Y69856D02*
X4460585D01*
G01X4466165Y57356D02*
Y69856D01*
G01X4472675D02*
Y57356D01*
G01Y63606D02*
X4466165D01*
G01X4491275Y57356D02*
Y69856D01*
X4497165D01*
G01X4494995Y63814D02*
X4491275D01*
G01X4503520Y57356D02*
Y69856D01*
X4507395D01*
X4508635Y69231D01*
X4509410Y68398D01*
X4509720Y66731D01*
X4509410Y65064D01*
X4508480Y64023D01*
X4507395Y63398D01*
X4503520D01*
G01X4507395D02*
X4509720Y57356D01*
G01X4519020D02*
X4517780Y57564D01*
X4516695Y58397D01*
X4515765Y59648D01*
X4515145Y61106D01*
X4514835Y62773D01*
Y64439D01*
X4515145Y66106D01*
X4515765Y67564D01*
X4516695Y68814D01*
X4517780Y69648D01*
X4519020Y69856D01*
X4520260Y69648D01*
X4521345Y68814D01*
X4522275Y67564D01*
X4522895Y66106D01*
X4523205Y64439D01*
Y62773D01*
X4522895Y61106D01*
X4522275Y59648D01*
X4521345Y58397D01*
X4520260Y57564D01*
X4519020Y57356D01*
G01X4527390D02*
Y69856D01*
X4531420Y59439D01*
X4535450Y69856D01*
Y57356D01*
G01X4552965Y59022D02*
X4554205Y57981D01*
X4555600Y57356D01*
X4556840D01*
X4558080Y57981D01*
X4559010Y59022D01*
X4559475Y60481D01*
X4559165Y61939D01*
X4558390Y63189D01*
X4556995Y64023D01*
X4555135Y64439D01*
X4554050Y65273D01*
X4553585Y66731D01*
X4553895Y68189D01*
X4554670Y69231D01*
X4555755Y69856D01*
X4556840D01*
X4557925Y69439D01*
X4558855Y68398D01*
G01X4568620Y69856D02*
Y57356D01*
G01X4565055Y69856D02*
X4572185D01*
G01X4577145Y57356D02*
X4581020Y69856D01*
X4584895Y57356D01*
G01X4583500Y61731D02*
X4578540D01*
G01X4590320Y57356D02*
Y69856D01*
X4594195D01*
X4595435Y69231D01*
X4596210Y68398D01*
X4596520Y66731D01*
X4596210Y65064D01*
X4595280Y64023D01*
X4594195Y63398D01*
X4590320D01*
G01X4594195D02*
X4596520Y57356D01*
G01X4605820Y69856D02*
Y57356D01*
G01X4602255Y69856D02*
X4609385D01*
G01X4627520D02*
Y57356D01*
X4633720D01*
G01X4639145D02*
X4643020Y69856D01*
X4646895Y57356D01*
G01X4645500Y61731D02*
X4640540D01*
G01X4655420Y57356D02*
Y62981D01*
X4652320Y69856D01*
G01X4658520D02*
X4655420Y62981D01*
G01X4670920Y57356D02*
X4664720D01*
Y69856D01*
X4670920D01*
G01X4668440Y63814D02*
X4664720D01*
G01X4677120Y57356D02*
Y69856D01*
X4680995D01*
X4682235Y69231D01*
X4683010Y68398D01*
X4683320Y66731D01*
X4683010Y65064D01*
X4682080Y64023D01*
X4680995Y63398D01*
X4677120D01*
G01X4680995D02*
X4683320Y57356D01*
G01X4705020Y69856D02*
Y57356D01*
G01X4701455Y69856D02*
X4708585D01*
G01X4717420Y57356D02*
X4716180Y57564D01*
X4715095Y58397D01*
X4714165Y59648D01*
X4713545Y61106D01*
X4713235Y62773D01*
Y64439D01*
X4713545Y66106D01*
X4714165Y67564D01*
X4715095Y68814D01*
X4716180Y69648D01*
X4717420Y69856D01*
X4718660Y69648D01*
X4719745Y68814D01*
X4720675Y67564D01*
X4721295Y66106D01*
X4721605Y64439D01*
Y62773D01*
X4721295Y61106D01*
X4720675Y59648D01*
X4719745Y58397D01*
X4718660Y57564D01*
X4717420Y57356D01*
G01X4742220Y69856D02*
Y57356D01*
G01X4738655Y69856D02*
X4745785D01*
G01X4751365Y57356D02*
Y69856D01*
G01X4757875D02*
Y57356D01*
G01Y63606D02*
X4751365D01*
G01X4770120Y57356D02*
X4763920D01*
Y69856D01*
X4770120D01*
G01X4767640Y63814D02*
X4763920D01*
G01X4256605Y80273D02*
X4260635D01*
G01X4279390Y76106D02*
Y88606D01*
X4283420Y78189D01*
X4287450Y88606D01*
Y76106D01*
G01X4292255D02*
Y88606D01*
X4299385Y76106D01*
Y88606D01*
G01X4311630Y87564D02*
X4310700Y88189D01*
X4309615Y88606D01*
X4308375D01*
X4306980Y87981D01*
X4305895Y86939D01*
X4305120Y85689D01*
X4304500Y83606D01*
X4304345Y81731D01*
X4304655Y79856D01*
X4305120Y78606D01*
X4306050Y77356D01*
X4307135Y76523D01*
X4308220Y76106D01*
X4309305D01*
X4310390Y76523D01*
X4311320Y77147D01*
X4312095Y77981D01*
G01X4315970Y71939D02*
X4325270D01*
G01X4329920Y88606D02*
Y76106D01*
X4336120D01*
G01X4341545D02*
X4345420Y88606D01*
X4349295Y76106D01*
G01X4347900Y80481D02*
X4342940D01*
G01X4357820Y76106D02*
Y81731D01*
X4354720Y88606D01*
G01X4360920D02*
X4357820Y81731D01*
G01X4373320Y76106D02*
X4367120D01*
Y88606D01*
X4373320D01*
G01X4370840Y82564D02*
X4367120D01*
G01X4379520Y76106D02*
Y88606D01*
X4383395D01*
X4384635Y87981D01*
X4385410Y87148D01*
X4385720Y85481D01*
X4385410Y83814D01*
X4384480Y82773D01*
X4383395Y82148D01*
X4379520D01*
G01X4383395D02*
X4385720Y76106D01*
G01X4395020Y75689D02*
X4394710Y75898D01*
Y76314D01*
X4395020Y76523D01*
X4395330Y76314D01*
Y75898D01*
X4395020Y75689D01*
G01Y81314D02*
X4394710Y81523D01*
Y81939D01*
X4395020Y82148D01*
X4395330Y81939D01*
Y81523D01*
X4395020Y81314D01*
G01X4415790Y76106D02*
Y88606D01*
X4419820Y78189D01*
X4423850Y88606D01*
Y76106D01*
G01X4428810Y88606D02*
Y79648D01*
X4429430Y77772D01*
X4430670Y76523D01*
X4432220Y76106D01*
X4433770Y76523D01*
X4435010Y77772D01*
X4435630Y79648D01*
Y88606D01*
G01X4441365Y77772D02*
X4442605Y76731D01*
X4444000Y76106D01*
X4445240D01*
X4446480Y76731D01*
X4447410Y77772D01*
X4447875Y79231D01*
X4447565Y80689D01*
X4446790Y81939D01*
X4445395Y82773D01*
X4443535Y83189D01*
X4442450Y84023D01*
X4441985Y85481D01*
X4442295Y86939D01*
X4443070Y87981D01*
X4444155Y88606D01*
X4445240D01*
X4446325Y88189D01*
X4447255Y87148D01*
G01X4457020Y88606D02*
Y76106D01*
G01X4453455Y88606D02*
X4460585D01*
G01X4467405Y80273D02*
X4471435D01*
G01X4478255Y76106D02*
Y88606D01*
X4485385Y76106D01*
Y88606D01*
G01X4494220Y76106D02*
X4492980Y76314D01*
X4491895Y77147D01*
X4490965Y78398D01*
X4490345Y79856D01*
X4490035Y81523D01*
Y83189D01*
X4490345Y84856D01*
X4490965Y86314D01*
X4491895Y87564D01*
X4492980Y88398D01*
X4494220Y88606D01*
X4495460Y88398D01*
X4496545Y87564D01*
X4497475Y86314D01*
X4498095Y84856D01*
X4498405Y83189D01*
Y81523D01*
X4498095Y79856D01*
X4497475Y78398D01*
X4496545Y77147D01*
X4495460Y76314D01*
X4494220Y76106D01*
G01X4506620Y88606D02*
Y76106D01*
G01X4503055Y88606D02*
X4510185D01*
G01X4517005Y80273D02*
X4521035D01*
G01X4534830Y87564D02*
X4533900Y88189D01*
X4532815Y88606D01*
X4531575D01*
X4530180Y87981D01*
X4529095Y86939D01*
X4528320Y85689D01*
X4527700Y83606D01*
X4527545Y81731D01*
X4527855Y79856D01*
X4528320Y78606D01*
X4529250Y77356D01*
X4530335Y76523D01*
X4531420Y76106D01*
X4532505D01*
X4533590Y76523D01*
X4534520Y77147D01*
X4535295Y77981D01*
G01X4540410Y88606D02*
Y79648D01*
X4541030Y77772D01*
X4542270Y76523D01*
X4543820Y76106D01*
X4545370Y76523D01*
X4546610Y77772D01*
X4547230Y79648D01*
Y88606D01*
G01X4556220D02*
Y76106D01*
G01X4552655Y88606D02*
X4559785D01*
G01X4566605Y80273D02*
X4570635D01*
G01X4577920Y88606D02*
Y76106D01*
X4584120D01*
G01X4589545D02*
X4593420Y88606D01*
X4597295Y76106D01*
G01X4595900Y80481D02*
X4590940D01*
G01X4605820Y76106D02*
Y81731D01*
X4602720Y88606D01*
G01X4608920D02*
X4605820Y81731D01*
G01X4621320Y76106D02*
X4615120D01*
Y88606D01*
X4621320D01*
G01X4618840Y82564D02*
X4615120D01*
G01X4627520Y76106D02*
Y88606D01*
X4631395D01*
X4632635Y87981D01*
X4633410Y87148D01*
X4633720Y85481D01*
X4633410Y83814D01*
X4632480Y82773D01*
X4631395Y82148D01*
X4627520D01*
G01X4631395D02*
X4633720Y76106D01*
G01X4255055Y94856D02*
Y107356D01*
X4262185Y94856D01*
Y107356D01*
G01X4271020Y94856D02*
X4269780Y95064D01*
X4268695Y95897D01*
X4267765Y97148D01*
X4267145Y98606D01*
X4266835Y100273D01*
Y101939D01*
X4267145Y103606D01*
X4267765Y105064D01*
X4268695Y106314D01*
X4269780Y107148D01*
X4271020Y107356D01*
X4272260Y107148D01*
X4273345Y106314D01*
X4274275Y105064D01*
X4274895Y103606D01*
X4275205Y101939D01*
Y100273D01*
X4274895Y98606D01*
X4274275Y97148D01*
X4273345Y95897D01*
X4272260Y95064D01*
X4271020Y94856D01*
G01X4283420Y107356D02*
Y94856D01*
G01X4279855Y107356D02*
X4286985D01*
G01X4298920Y94856D02*
X4292720D01*
Y107356D01*
X4298920D01*
G01X4296440Y101314D02*
X4292720D01*
G01X4304965Y96522D02*
X4306205Y95481D01*
X4307600Y94856D01*
X4308840D01*
X4310080Y95481D01*
X4311010Y96522D01*
X4311475Y97981D01*
X4311165Y99439D01*
X4310390Y100689D01*
X4308995Y101523D01*
X4307135Y101939D01*
X4306050Y102773D01*
X4305585Y104231D01*
X4305895Y105689D01*
X4306670Y106731D01*
X4307755Y107356D01*
X4308840D01*
X4309925Y106939D01*
X4310855Y105898D01*
G01X4320620Y94439D02*
X4320310Y94648D01*
Y95064D01*
X4320620Y95273D01*
X4320930Y95064D01*
Y94648D01*
X4320620Y94439D01*
G01Y100064D02*
X4320310Y100273D01*
Y100689D01*
X4320620Y100898D01*
X4320930Y100689D01*
Y100273D01*
X4320620Y100064D01*
G01X4426847Y-249168D02*
X4427467Y-248543D01*
X4427932Y-247502D01*
X4428242Y-246043D01*
X4427932Y-244793D01*
X4427312Y-243960D01*
X4426227Y-243335D01*
X4422042D01*
Y-255835D01*
X4427157D01*
X4428242Y-255002D01*
X4428862Y-253752D01*
X4429172Y-252293D01*
X4428862Y-250835D01*
X4427932Y-249585D01*
X4426847Y-249168D01*
X4422042D01*
G01X4434132Y-255835D02*
X4438007Y-243335D01*
X4441882Y-255835D01*
G01X4440487Y-251460D02*
X4435527D01*
G01X4453817Y-244377D02*
X4452887Y-243752D01*
X4451802Y-243335D01*
X4450562D01*
X4449167Y-243960D01*
X4448082Y-245002D01*
X4447307Y-246252D01*
X4446687Y-248335D01*
X4446532Y-250210D01*
X4446842Y-252085D01*
X4447307Y-253335D01*
X4448237Y-254585D01*
X4449322Y-255418D01*
X4450407Y-255835D01*
X4451492D01*
X4452577Y-255418D01*
X4453507Y-254794D01*
X4454282Y-253960D01*
G01X4459397Y-255835D02*
Y-243335D01*
G01X4465287D02*
X4459397Y-251044D01*
G01X4466217Y-255835D02*
X4462032Y-247502D01*
G01X4471797Y-255835D02*
Y-243335D01*
X4474897D01*
X4476137Y-243960D01*
X4477067Y-244793D01*
X4477842Y-246043D01*
X4478462Y-247502D01*
X4478617Y-249585D01*
X4478462Y-251668D01*
X4477842Y-253127D01*
X4477067Y-254377D01*
X4476137Y-255210D01*
X4474897Y-255835D01*
X4471797D01*
G01X4484507D02*
Y-243335D01*
X4488382D01*
X4489622Y-243960D01*
X4490397Y-244793D01*
X4490707Y-246460D01*
X4490397Y-248127D01*
X4489467Y-249168D01*
X4488382Y-249793D01*
X4484507D01*
G01X4488382D02*
X4490707Y-255835D01*
G01X4498147Y-243335D02*
X4501867D01*
G01X4500007D02*
Y-255835D01*
G01X4498147D02*
X4501867D01*
G01X4509307Y-243335D02*
Y-255835D01*
X4515507D01*
G01X4521707Y-243335D02*
Y-255835D01*
X4527907D01*
G01X4546352Y-254169D02*
X4547592Y-255210D01*
X4548987Y-255835D01*
X4550227D01*
X4551467Y-255210D01*
X4552397Y-254169D01*
X4552862Y-252710D01*
X4552552Y-251252D01*
X4551777Y-250002D01*
X4550382Y-249168D01*
X4548522Y-248752D01*
X4547437Y-247918D01*
X4546972Y-246460D01*
X4547282Y-245002D01*
X4548057Y-243960D01*
X4549142Y-243335D01*
X4550227D01*
X4551312Y-243752D01*
X4552242Y-244793D01*
G01X4562007Y-243335D02*
Y-255835D01*
G01X4558442Y-243335D02*
X4565572D01*
G01X4570997D02*
Y-252293D01*
X4571617Y-254169D01*
X4572857Y-255418D01*
X4574407Y-255835D01*
X4575957Y-255418D01*
X4577197Y-254169D01*
X4577817Y-252293D01*
Y-243335D01*
G01X4588047Y-249168D02*
X4588667Y-248543D01*
X4589132Y-247502D01*
X4589442Y-246043D01*
X4589132Y-244793D01*
X4588512Y-243960D01*
X4587427Y-243335D01*
X4583242D01*
Y-255835D01*
X4588357D01*
X4589442Y-255002D01*
X4590062Y-253752D01*
X4590372Y-252293D01*
X4590062Y-250835D01*
X4589132Y-249585D01*
X4588047Y-249168D01*
X4583242D01*
G01X4608507Y-243335D02*
Y-255835D01*
X4614707D01*
G01X4627107D02*
X4620907D01*
Y-243335D01*
X4627107D01*
G01X4624627Y-249377D02*
X4620907D01*
G01X4632842Y-255835D02*
Y-243335D01*
X4639972Y-255835D01*
Y-243335D01*
G01X4649737Y-249585D02*
X4652837D01*
Y-253335D01*
X4651907Y-254585D01*
X4650822Y-255418D01*
X4649272Y-255835D01*
X4647722Y-255418D01*
X4646637Y-254585D01*
X4645707Y-253335D01*
X4645087Y-251877D01*
X4644777Y-250210D01*
Y-248752D01*
X4645087Y-247502D01*
X4645707Y-246043D01*
X4646637Y-244793D01*
X4647567Y-243960D01*
X4648807Y-243335D01*
X4649892D01*
X4651132Y-243752D01*
X4652062Y-244585D01*
G01X4661207Y-243335D02*
Y-255835D01*
G01X4657642Y-243335D02*
X4664772D01*
G01X4670352Y-255835D02*
Y-243335D01*
G01X4676862D02*
Y-255835D01*
G01Y-249585D02*
X4670352D01*
G01X4698407Y-243335D02*
Y-255835D01*
G01X4694842Y-243335D02*
X4701972D01*
G01X4710807Y-255835D02*
X4709567Y-255627D01*
X4708482Y-254794D01*
X4707552Y-253543D01*
X4706932Y-252085D01*
X4706622Y-250418D01*
Y-248752D01*
X4706932Y-247085D01*
X4707552Y-245627D01*
X4708482Y-244377D01*
X4709567Y-243543D01*
X4710807Y-243335D01*
X4712047Y-243543D01*
X4713132Y-244377D01*
X4714062Y-245627D01*
X4714682Y-247085D01*
X4714992Y-248752D01*
Y-250418D01*
X4714682Y-252085D01*
X4714062Y-253543D01*
X4713132Y-254794D01*
X4712047Y-255627D01*
X4710807Y-255835D01*
G01X4720107Y-243335D02*
Y-255835D01*
X4726307D01*
G01X4738707D02*
X4732507D01*
Y-243335D01*
X4738707D01*
G01X4736227Y-249377D02*
X4732507D01*
G01X4744907Y-255835D02*
Y-243335D01*
X4748782D01*
X4750022Y-243960D01*
X4750797Y-244793D01*
X4751107Y-246460D01*
X4750797Y-248127D01*
X4749867Y-249168D01*
X4748782Y-249793D01*
X4744907D01*
G01X4748782D02*
X4751107Y-255835D01*
G01X4756532D02*
X4760407Y-243335D01*
X4764282Y-255835D01*
G01X4762887Y-251460D02*
X4757927D01*
G01X4769242Y-255835D02*
Y-243335D01*
X4776372Y-255835D01*
Y-243335D01*
G01X4788617Y-244377D02*
X4787687Y-243752D01*
X4786602Y-243335D01*
X4785362D01*
X4783967Y-243960D01*
X4782882Y-245002D01*
X4782107Y-246252D01*
X4781487Y-248335D01*
X4781332Y-250210D01*
X4781642Y-252085D01*
X4782107Y-253335D01*
X4783037Y-254585D01*
X4784122Y-255418D01*
X4785207Y-255835D01*
X4786292D01*
X4787377Y-255418D01*
X4788307Y-254794D01*
X4789082Y-253960D01*
G01X4800707Y-255835D02*
X4794507D01*
Y-243335D01*
X4800707D01*
G01X4798227Y-249377D02*
X4794507D01*
G01X4822407Y-243335D02*
Y-255835D01*
G01X4818842Y-243335D02*
X4825972D01*
G01X4834807Y-255835D02*
X4833567Y-255627D01*
X4832482Y-254794D01*
X4831552Y-253543D01*
X4830932Y-252085D01*
X4830622Y-250418D01*
Y-248752D01*
X4830932Y-247085D01*
X4831552Y-245627D01*
X4832482Y-244377D01*
X4833567Y-243543D01*
X4834807Y-243335D01*
X4836047Y-243543D01*
X4837132Y-244377D01*
X4838062Y-245627D01*
X4838682Y-247085D01*
X4838992Y-248752D01*
Y-250418D01*
X4838682Y-252085D01*
X4838062Y-253543D01*
X4837132Y-254794D01*
X4836047Y-255627D01*
X4834807Y-255835D01*
G01X4860847Y-249168D02*
X4861467Y-248543D01*
X4861932Y-247502D01*
X4862242Y-246043D01*
X4861932Y-244793D01*
X4861312Y-243960D01*
X4860227Y-243335D01*
X4856042D01*
Y-255835D01*
X4861157D01*
X4862242Y-255002D01*
X4862862Y-253752D01*
X4863172Y-252293D01*
X4862862Y-250835D01*
X4861932Y-249585D01*
X4860847Y-249168D01*
X4856042D01*
G01X4875107Y-255835D02*
X4868907D01*
Y-243335D01*
X4875107D01*
G01X4872627Y-249377D02*
X4868907D01*
G01X4896497Y-255835D02*
X4896807Y-253127D01*
X4897272Y-250835D01*
X4897892Y-248752D01*
X4898667Y-246460D01*
X4899907Y-243335D01*
X4893707D01*
G01X4919902Y-251668D02*
X4923622D01*
G01X4921607Y-248960D02*
Y-254377D01*
G01X4931217Y-256252D02*
X4936797Y-243335D01*
G01X4944392Y-251668D02*
X4948422D01*
G01X4955397Y-253960D02*
X4956327Y-255002D01*
X4957412Y-255627D01*
X4958807Y-255835D01*
X4960202Y-255418D01*
X4961287Y-254585D01*
X4962062Y-253127D01*
X4962217Y-251460D01*
X4961907Y-249793D01*
X4961132Y-248752D01*
X4960047Y-247918D01*
X4958962Y-247710D01*
X4957877Y-247918D01*
X4956482Y-248752D01*
X4956947Y-243335D01*
X4961132D01*
G01X4979577Y-255835D02*
Y-243335D01*
X4983607Y-253752D01*
X4987637Y-243335D01*
Y-255835D01*
G01X4994147Y-243335D02*
X4997867D01*
G01X4996007D02*
Y-255835D01*
G01X4994147D02*
X4997867D01*
G01X5005307Y-243335D02*
Y-255835D01*
X5011507D01*
G01X5017552Y-254169D02*
X5018792Y-255210D01*
X5020187Y-255835D01*
X5021427D01*
X5022667Y-255210D01*
X5023597Y-254169D01*
X5024062Y-252710D01*
X5023752Y-251252D01*
X5022977Y-250002D01*
X5021582Y-249168D01*
X5019722Y-248752D01*
X5018637Y-247918D01*
X5018172Y-246460D01*
X5018482Y-245002D01*
X5019257Y-243960D01*
X5020342Y-243335D01*
X5021427D01*
X5022512Y-243752D01*
X5023442Y-244793D01*
G01X4262392Y-232918D02*
X4266422D01*
G01X4285177Y-237085D02*
Y-224585D01*
X4289207Y-235002D01*
X4293237Y-224585D01*
Y-237085D01*
G01X4298662D02*
Y-224585D01*
X4304552D01*
G01X4302382Y-230627D02*
X4298662D01*
G01X4314937Y-230835D02*
X4318037D01*
Y-234585D01*
X4317107Y-235835D01*
X4316022Y-236668D01*
X4314472Y-237085D01*
X4312922Y-236668D01*
X4311837Y-235835D01*
X4310907Y-234585D01*
X4310287Y-233127D01*
X4309977Y-231460D01*
Y-230002D01*
X4310287Y-228752D01*
X4310907Y-227293D01*
X4311837Y-226043D01*
X4312767Y-225210D01*
X4314007Y-224585D01*
X4315092D01*
X4316332Y-225002D01*
X4317262Y-225835D01*
G01X4321757Y-241252D02*
X4331057D01*
G01X4335552Y-235419D02*
X4336792Y-236460D01*
X4338187Y-237085D01*
X4339427D01*
X4340667Y-236460D01*
X4341597Y-235419D01*
X4342062Y-233960D01*
X4341752Y-232502D01*
X4340977Y-231252D01*
X4339582Y-230418D01*
X4337722Y-230002D01*
X4336637Y-229168D01*
X4336172Y-227710D01*
X4336482Y-226252D01*
X4337257Y-225210D01*
X4338342Y-224585D01*
X4339427D01*
X4340512Y-225002D01*
X4341442Y-226043D01*
G01X4351207Y-224585D02*
Y-237085D01*
G01X4347642Y-224585D02*
X4354772D01*
G01X4360197D02*
Y-233543D01*
X4360817Y-235419D01*
X4362057Y-236668D01*
X4363607Y-237085D01*
X4365157Y-236668D01*
X4366397Y-235419D01*
X4367017Y-233543D01*
Y-224585D01*
G01X4377247Y-230418D02*
X4377867Y-229793D01*
X4378332Y-228752D01*
X4378642Y-227293D01*
X4378332Y-226043D01*
X4377712Y-225210D01*
X4376627Y-224585D01*
X4372442D01*
Y-237085D01*
X4377557D01*
X4378642Y-236252D01*
X4379262Y-235002D01*
X4379572Y-233543D01*
X4379262Y-232085D01*
X4378332Y-230835D01*
X4377247Y-230418D01*
X4372442D01*
G01X4400807Y-237502D02*
X4400497Y-237293D01*
Y-236877D01*
X4400807Y-236668D01*
X4401117Y-236877D01*
Y-237293D01*
X4400807Y-237502D01*
G01Y-231877D02*
X4400497Y-231668D01*
Y-231252D01*
X4400807Y-231043D01*
X4401117Y-231252D01*
Y-231668D01*
X4400807Y-231877D01*
G01X4421577Y-237085D02*
Y-224585D01*
X4425607Y-235002D01*
X4429637Y-224585D01*
Y-237085D01*
G01X4434132D02*
X4438007Y-224585D01*
X4441882Y-237085D01*
G01X4440487Y-232710D02*
X4435527D01*
G01X4446842Y-237085D02*
Y-224585D01*
X4453972Y-237085D01*
Y-224585D01*
G01X4459397D02*
Y-233543D01*
X4460017Y-235419D01*
X4461257Y-236668D01*
X4462807Y-237085D01*
X4464357Y-236668D01*
X4465597Y-235419D01*
X4466217Y-233543D01*
Y-224585D01*
G01X4472262Y-237085D02*
Y-224585D01*
X4478152D01*
G01X4475982Y-230627D02*
X4472262D01*
G01X4483732Y-237085D02*
X4487607Y-224585D01*
X4491482Y-237085D01*
G01X4490087Y-232710D02*
X4485127D01*
G01X4503417Y-225627D02*
X4502487Y-225002D01*
X4501402Y-224585D01*
X4500162D01*
X4498767Y-225210D01*
X4497682Y-226252D01*
X4496907Y-227502D01*
X4496287Y-229585D01*
X4496132Y-231460D01*
X4496442Y-233335D01*
X4496907Y-234585D01*
X4497837Y-235835D01*
X4498922Y-236668D01*
X4500007Y-237085D01*
X4501092D01*
X4502177Y-236668D01*
X4503107Y-236044D01*
X4503882Y-235210D01*
G01X4512407Y-224585D02*
Y-237085D01*
G01X4508842Y-224585D02*
X4515972D01*
G01X4521397D02*
Y-233543D01*
X4522017Y-235419D01*
X4523257Y-236668D01*
X4524807Y-237085D01*
X4526357Y-236668D01*
X4527597Y-235419D01*
X4528217Y-233543D01*
Y-224585D01*
G01X4534107Y-237085D02*
Y-224585D01*
X4537982D01*
X4539222Y-225210D01*
X4539997Y-226043D01*
X4540307Y-227710D01*
X4539997Y-229377D01*
X4539067Y-230418D01*
X4537982Y-231043D01*
X4534107D01*
G01X4537982D02*
X4540307Y-237085D01*
G01X4547747Y-224585D02*
X4551467D01*
G01X4549607D02*
Y-237085D01*
G01X4547747D02*
X4551467D01*
G01X4558442D02*
Y-224585D01*
X4565572Y-237085D01*
Y-224585D01*
G01X4575337Y-230835D02*
X4578437D01*
Y-234585D01*
X4577507Y-235835D01*
X4576422Y-236668D01*
X4574872Y-237085D01*
X4573322Y-236668D01*
X4572237Y-235835D01*
X4571307Y-234585D01*
X4570687Y-233127D01*
X4570377Y-231460D01*
Y-230002D01*
X4570687Y-228752D01*
X4571307Y-227293D01*
X4572237Y-226043D01*
X4573167Y-225210D01*
X4574407Y-224585D01*
X4575492D01*
X4576732Y-225002D01*
X4577662Y-225835D01*
G01X4595952Y-235419D02*
X4597192Y-236460D01*
X4598587Y-237085D01*
X4599827D01*
X4601067Y-236460D01*
X4601997Y-235419D01*
X4602462Y-233960D01*
X4602152Y-232502D01*
X4601377Y-231252D01*
X4599982Y-230418D01*
X4598122Y-230002D01*
X4597037Y-229168D01*
X4596572Y-227710D01*
X4596882Y-226252D01*
X4597657Y-225210D01*
X4598742Y-224585D01*
X4599827D01*
X4600912Y-225002D01*
X4601842Y-226043D01*
G01X4611607Y-224585D02*
Y-237085D01*
G01X4608042Y-224585D02*
X4615172D01*
G01X4620597D02*
Y-233543D01*
X4621217Y-235419D01*
X4622457Y-236668D01*
X4624007Y-237085D01*
X4625557Y-236668D01*
X4626797Y-235419D01*
X4627417Y-233543D01*
Y-224585D01*
G01X4637647Y-230418D02*
X4638267Y-229793D01*
X4638732Y-228752D01*
X4639042Y-227293D01*
X4638732Y-226043D01*
X4638112Y-225210D01*
X4637027Y-224585D01*
X4632842D01*
Y-237085D01*
X4637957D01*
X4639042Y-236252D01*
X4639662Y-235002D01*
X4639972Y-233543D01*
X4639662Y-232085D01*
X4638732Y-230835D01*
X4637647Y-230418D01*
X4632842D01*
G01X4658107Y-224585D02*
Y-237085D01*
X4664307D01*
G01X4676707D02*
X4670507D01*
Y-224585D01*
X4676707D01*
G01X4674227Y-230627D02*
X4670507D01*
G01X4682442Y-237085D02*
Y-224585D01*
X4689572Y-237085D01*
Y-224585D01*
G01X4699337Y-230835D02*
X4702437D01*
Y-234585D01*
X4701507Y-235835D01*
X4700422Y-236668D01*
X4698872Y-237085D01*
X4697322Y-236668D01*
X4696237Y-235835D01*
X4695307Y-234585D01*
X4694687Y-233127D01*
X4694377Y-231460D01*
Y-230002D01*
X4694687Y-228752D01*
X4695307Y-227293D01*
X4696237Y-226043D01*
X4697167Y-225210D01*
X4698407Y-224585D01*
X4699492D01*
X4700732Y-225002D01*
X4701662Y-225835D01*
G01X4710807Y-224585D02*
Y-237085D01*
G01X4707242Y-224585D02*
X4714372D01*
G01X4719952Y-237085D02*
Y-224585D01*
G01X4726462D02*
Y-237085D01*
G01Y-230835D02*
X4719952D01*
G01X4422352Y-216669D02*
X4423592Y-217710D01*
X4424987Y-218335D01*
X4426227D01*
X4427467Y-217710D01*
X4428397Y-216669D01*
X4428862Y-215210D01*
X4428552Y-213752D01*
X4427777Y-212502D01*
X4426382Y-211668D01*
X4424522Y-211252D01*
X4423437Y-210418D01*
X4422972Y-208960D01*
X4423282Y-207502D01*
X4424057Y-206460D01*
X4425142Y-205835D01*
X4426227D01*
X4427312Y-206252D01*
X4428242Y-207293D01*
G01X4434597Y-205835D02*
Y-214793D01*
X4435217Y-216669D01*
X4436457Y-217918D01*
X4438007Y-218335D01*
X4439557Y-217918D01*
X4440797Y-216669D01*
X4441417Y-214793D01*
Y-205835D01*
G01X4447307Y-218335D02*
Y-205835D01*
X4451182D01*
X4452422Y-206460D01*
X4453197Y-207293D01*
X4453507Y-208960D01*
X4453197Y-210627D01*
X4452267Y-211668D01*
X4451182Y-212293D01*
X4447307D01*
G01X4451182D02*
X4453507Y-218335D01*
G01X4459862D02*
Y-205835D01*
X4465752D01*
G01X4463582Y-211877D02*
X4459862D01*
G01X4471332Y-218335D02*
X4475207Y-205835D01*
X4479082Y-218335D01*
G01X4477687Y-213960D02*
X4472727D01*
G01X4491017Y-206877D02*
X4490087Y-206252D01*
X4489002Y-205835D01*
X4487762D01*
X4486367Y-206460D01*
X4485282Y-207502D01*
X4484507Y-208752D01*
X4483887Y-210835D01*
X4483732Y-212710D01*
X4484042Y-214585D01*
X4484507Y-215835D01*
X4485437Y-217085D01*
X4486522Y-217918D01*
X4487607Y-218335D01*
X4488692D01*
X4489777Y-217918D01*
X4490707Y-217294D01*
X4491482Y-216460D01*
G01X4503107Y-218335D02*
X4496907D01*
Y-205835D01*
X4503107D01*
G01X4500627Y-211877D02*
X4496907D01*
G01X4524807Y-218335D02*
X4523567Y-218127D01*
X4522482Y-217294D01*
X4521552Y-216043D01*
X4520932Y-214585D01*
X4520622Y-212918D01*
Y-211252D01*
X4520932Y-209585D01*
X4521552Y-208127D01*
X4522482Y-206877D01*
X4523567Y-206043D01*
X4524807Y-205835D01*
X4526047Y-206043D01*
X4527132Y-206877D01*
X4528062Y-208127D01*
X4528682Y-209585D01*
X4528992Y-211252D01*
Y-212918D01*
X4528682Y-214585D01*
X4528062Y-216043D01*
X4527132Y-217294D01*
X4526047Y-218127D01*
X4524807Y-218335D01*
G01X4534262D02*
Y-205835D01*
X4540152D01*
G01X4537982Y-211877D02*
X4534262D01*
G01X4557977Y-218335D02*
Y-205835D01*
X4562007Y-216252D01*
X4566037Y-205835D01*
Y-218335D01*
G01X4570997Y-205835D02*
Y-214793D01*
X4571617Y-216669D01*
X4572857Y-217918D01*
X4574407Y-218335D01*
X4575957Y-217918D01*
X4577197Y-216669D01*
X4577817Y-214793D01*
Y-205835D01*
G01X4583552Y-216669D02*
X4584792Y-217710D01*
X4586187Y-218335D01*
X4587427D01*
X4588667Y-217710D01*
X4589597Y-216669D01*
X4590062Y-215210D01*
X4589752Y-213752D01*
X4588977Y-212502D01*
X4587582Y-211668D01*
X4585722Y-211252D01*
X4584637Y-210418D01*
X4584172Y-208960D01*
X4584482Y-207502D01*
X4585257Y-206460D01*
X4586342Y-205835D01*
X4587427D01*
X4588512Y-206252D01*
X4589442Y-207293D01*
G01X4599207Y-205835D02*
Y-218335D01*
G01X4595642Y-205835D02*
X4602772D01*
G01X4609592Y-214168D02*
X4613622D01*
G01X4620442Y-218335D02*
Y-205835D01*
X4627572Y-218335D01*
Y-205835D01*
G01X4636407Y-218335D02*
X4635167Y-218127D01*
X4634082Y-217294D01*
X4633152Y-216043D01*
X4632532Y-214585D01*
X4632222Y-212918D01*
Y-211252D01*
X4632532Y-209585D01*
X4633152Y-208127D01*
X4634082Y-206877D01*
X4635167Y-206043D01*
X4636407Y-205835D01*
X4637647Y-206043D01*
X4638732Y-206877D01*
X4639662Y-208127D01*
X4640282Y-209585D01*
X4640592Y-211252D01*
Y-212918D01*
X4640282Y-214585D01*
X4639662Y-216043D01*
X4638732Y-217294D01*
X4637647Y-218127D01*
X4636407Y-218335D01*
G01X4648807Y-205835D02*
Y-218335D01*
G01X4645242Y-205835D02*
X4652372D01*
G01X4659192Y-214168D02*
X4663222D01*
G01X4677017Y-206877D02*
X4676087Y-206252D01*
X4675002Y-205835D01*
X4673762D01*
X4672367Y-206460D01*
X4671282Y-207502D01*
X4670507Y-208752D01*
X4669887Y-210835D01*
X4669732Y-212710D01*
X4670042Y-214585D01*
X4670507Y-215835D01*
X4671437Y-217085D01*
X4672522Y-217918D01*
X4673607Y-218335D01*
X4674692D01*
X4675777Y-217918D01*
X4676707Y-217294D01*
X4677482Y-216460D01*
G01X4682597Y-205835D02*
Y-214793D01*
X4683217Y-216669D01*
X4684457Y-217918D01*
X4686007Y-218335D01*
X4687557Y-217918D01*
X4688797Y-216669D01*
X4689417Y-214793D01*
Y-205835D01*
G01X4698407D02*
Y-218335D01*
G01X4694842Y-205835D02*
X4701972D01*
G01X4708792Y-214168D02*
X4712822D01*
G01X4720107Y-205835D02*
Y-218335D01*
X4726307D01*
G01X4731732D02*
X4735607Y-205835D01*
X4739482Y-218335D01*
G01X4738087Y-213960D02*
X4733127D01*
G01X4748007Y-218335D02*
Y-212710D01*
X4744907Y-205835D01*
G01X4751107D02*
X4748007Y-212710D01*
G01X4763507Y-218335D02*
X4757307D01*
Y-205835D01*
X4763507D01*
G01X4761027Y-211877D02*
X4757307D01*
G01X4769707Y-218335D02*
Y-205835D01*
X4773582D01*
X4774822Y-206460D01*
X4775597Y-207293D01*
X4775907Y-208960D01*
X4775597Y-210627D01*
X4774667Y-211668D01*
X4773582Y-212293D01*
X4769707D01*
G01X4773582D02*
X4775907Y-218335D01*
G01X4262392Y-195418D02*
X4266422D01*
G01X4285177Y-199585D02*
Y-187085D01*
X4289207Y-197502D01*
X4293237Y-187085D01*
Y-199585D01*
G01X4297732D02*
X4301607Y-187085D01*
X4305482Y-199585D01*
G01X4304087Y-195210D02*
X4299127D01*
G01X4310752Y-199585D02*
X4317262Y-187085D01*
G01X4310752D02*
X4317262Y-199585D01*
G01X4321757Y-203752D02*
X4331057D01*
G01X4335397Y-199585D02*
Y-187085D01*
X4338497D01*
X4339737Y-187710D01*
X4340667Y-188543D01*
X4341442Y-189793D01*
X4342062Y-191252D01*
X4342217Y-193335D01*
X4342062Y-195418D01*
X4341442Y-196877D01*
X4340667Y-198127D01*
X4339737Y-198960D01*
X4338497Y-199585D01*
X4335397D01*
G01X4354307D02*
X4348107D01*
Y-187085D01*
X4354307D01*
G01X4351827Y-193127D02*
X4348107D01*
G01X4360507Y-199585D02*
Y-187085D01*
X4364227D01*
X4365467Y-187710D01*
X4366397Y-189168D01*
X4366707Y-190835D01*
X4366397Y-192502D01*
X4365622Y-193752D01*
X4364227Y-194377D01*
X4360507D01*
G01X4376007Y-187085D02*
Y-199585D01*
G01X4372442Y-187085D02*
X4379572D01*
G01X4385152Y-199585D02*
Y-187085D01*
G01X4391662D02*
Y-199585D01*
G01Y-193335D02*
X4385152D01*
G01X4400807Y-200002D02*
X4400497Y-199793D01*
Y-199377D01*
X4400807Y-199168D01*
X4401117Y-199377D01*
Y-199793D01*
X4400807Y-200002D01*
G01Y-194377D02*
X4400497Y-194168D01*
Y-193752D01*
X4400807Y-193543D01*
X4401117Y-193752D01*
Y-194168D01*
X4400807Y-194377D01*
G01X4422197Y-199585D02*
Y-187085D01*
X4425297D01*
X4426537Y-187710D01*
X4427467Y-188543D01*
X4428242Y-189793D01*
X4428862Y-191252D01*
X4429017Y-193335D01*
X4428862Y-195418D01*
X4428242Y-196877D01*
X4427467Y-198127D01*
X4426537Y-198960D01*
X4425297Y-199585D01*
X4422197D01*
G01X4441107D02*
X4434907D01*
Y-187085D01*
X4441107D01*
G01X4438627Y-193127D02*
X4434907D01*
G01X4447307Y-199585D02*
Y-187085D01*
X4451027D01*
X4452267Y-187710D01*
X4453197Y-189168D01*
X4453507Y-190835D01*
X4453197Y-192502D01*
X4452422Y-193752D01*
X4451027Y-194377D01*
X4447307D01*
G01X4462807Y-187085D02*
Y-199585D01*
G01X4459242Y-187085D02*
X4466372D01*
G01X4471952Y-199585D02*
Y-187085D01*
G01X4478462D02*
Y-199585D01*
G01Y-193335D02*
X4471952D01*
G01X4497062Y-199585D02*
Y-187085D01*
X4502952D01*
G01X4500782Y-193127D02*
X4497062D01*
G01X4509307Y-199585D02*
Y-187085D01*
X4513182D01*
X4514422Y-187710D01*
X4515197Y-188543D01*
X4515507Y-190210D01*
X4515197Y-191877D01*
X4514267Y-192918D01*
X4513182Y-193543D01*
X4509307D01*
G01X4513182D02*
X4515507Y-199585D01*
G01X4524807D02*
X4523567Y-199377D01*
X4522482Y-198544D01*
X4521552Y-197293D01*
X4520932Y-195835D01*
X4520622Y-194168D01*
Y-192502D01*
X4520932Y-190835D01*
X4521552Y-189377D01*
X4522482Y-188127D01*
X4523567Y-187293D01*
X4524807Y-187085D01*
X4526047Y-187293D01*
X4527132Y-188127D01*
X4528062Y-189377D01*
X4528682Y-190835D01*
X4528992Y-192502D01*
Y-194168D01*
X4528682Y-195835D01*
X4528062Y-197293D01*
X4527132Y-198544D01*
X4526047Y-199377D01*
X4524807Y-199585D01*
G01X4533177D02*
Y-187085D01*
X4537207Y-197502D01*
X4541237Y-187085D01*
Y-199585D01*
G01X4558752Y-197919D02*
X4559992Y-198960D01*
X4561387Y-199585D01*
X4562627D01*
X4563867Y-198960D01*
X4564797Y-197919D01*
X4565262Y-196460D01*
X4564952Y-195002D01*
X4564177Y-193752D01*
X4562782Y-192918D01*
X4560922Y-192502D01*
X4559837Y-191668D01*
X4559372Y-190210D01*
X4559682Y-188752D01*
X4560457Y-187710D01*
X4561542Y-187085D01*
X4562627D01*
X4563712Y-187502D01*
X4564642Y-188543D01*
G01X4574407Y-187085D02*
Y-199585D01*
G01X4570842Y-187085D02*
X4577972D01*
G01X4582932Y-199585D02*
X4586807Y-187085D01*
X4590682Y-199585D01*
G01X4589287Y-195210D02*
X4584327D01*
G01X4596107Y-199585D02*
Y-187085D01*
X4599982D01*
X4601222Y-187710D01*
X4601997Y-188543D01*
X4602307Y-190210D01*
X4601997Y-191877D01*
X4601067Y-192918D01*
X4599982Y-193543D01*
X4596107D01*
G01X4599982D02*
X4602307Y-199585D01*
G01X4611607Y-187085D02*
Y-199585D01*
G01X4608042Y-187085D02*
X4615172D01*
G01X4633307D02*
Y-199585D01*
X4639507D01*
G01X4644932D02*
X4648807Y-187085D01*
X4652682Y-199585D01*
G01X4651287Y-195210D02*
X4646327D01*
G01X4661207Y-199585D02*
Y-193960D01*
X4658107Y-187085D01*
G01X4664307D02*
X4661207Y-193960D01*
G01X4676707Y-199585D02*
X4670507D01*
Y-187085D01*
X4676707D01*
G01X4674227Y-193127D02*
X4670507D01*
G01X4682907Y-199585D02*
Y-187085D01*
X4686782D01*
X4688022Y-187710D01*
X4688797Y-188543D01*
X4689107Y-190210D01*
X4688797Y-191877D01*
X4687867Y-192918D01*
X4686782Y-193543D01*
X4682907D01*
G01X4686782D02*
X4689107Y-199585D01*
G01X4710807Y-187085D02*
Y-199585D01*
G01X4707242Y-187085D02*
X4714372D01*
G01X4723207Y-199585D02*
X4721967Y-199377D01*
X4720882Y-198544D01*
X4719952Y-197293D01*
X4719332Y-195835D01*
X4719022Y-194168D01*
Y-192502D01*
X4719332Y-190835D01*
X4719952Y-189377D01*
X4720882Y-188127D01*
X4721967Y-187293D01*
X4723207Y-187085D01*
X4724447Y-187293D01*
X4725532Y-188127D01*
X4726462Y-189377D01*
X4727082Y-190835D01*
X4727392Y-192502D01*
Y-194168D01*
X4727082Y-195835D01*
X4726462Y-197293D01*
X4725532Y-198544D01*
X4724447Y-199377D01*
X4723207Y-199585D01*
G01X4748007Y-187085D02*
Y-199585D01*
G01X4744442Y-187085D02*
X4751572D01*
G01X4757152Y-199585D02*
Y-187085D01*
G01X4763662D02*
Y-199585D01*
G01Y-193335D02*
X4757152D01*
G01X4775907Y-199585D02*
X4769707D01*
Y-187085D01*
X4775907D01*
G01X4773427Y-193127D02*
X4769707D01*
G01X4262392Y-176668D02*
X4266422D01*
G01X4285177Y-180835D02*
Y-168335D01*
X4289207Y-178752D01*
X4293237Y-168335D01*
Y-180835D01*
G01X4298042D02*
Y-168335D01*
X4305172Y-180835D01*
Y-168335D01*
G01X4317417Y-169377D02*
X4316487Y-168752D01*
X4315402Y-168335D01*
X4314162D01*
X4312767Y-168960D01*
X4311682Y-170002D01*
X4310907Y-171252D01*
X4310287Y-173335D01*
X4310132Y-175210D01*
X4310442Y-177085D01*
X4310907Y-178335D01*
X4311837Y-179585D01*
X4312922Y-180418D01*
X4314007Y-180835D01*
X4315092D01*
X4316177Y-180418D01*
X4317107Y-179794D01*
X4317882Y-178960D01*
G01X4321757Y-185002D02*
X4331057D01*
G01X4335707Y-168335D02*
Y-180835D01*
X4341907D01*
G01X4347332D02*
X4351207Y-168335D01*
X4355082Y-180835D01*
G01X4353687Y-176460D02*
X4348727D01*
G01X4363607Y-180835D02*
Y-175210D01*
X4360507Y-168335D01*
G01X4366707D02*
X4363607Y-175210D01*
G01X4379107Y-180835D02*
X4372907D01*
Y-168335D01*
X4379107D01*
G01X4376627Y-174377D02*
X4372907D01*
G01X4385307Y-180835D02*
Y-168335D01*
X4389182D01*
X4390422Y-168960D01*
X4391197Y-169793D01*
X4391507Y-171460D01*
X4391197Y-173127D01*
X4390267Y-174168D01*
X4389182Y-174793D01*
X4385307D01*
G01X4389182D02*
X4391507Y-180835D01*
G01X4400807Y-181252D02*
X4400497Y-181043D01*
Y-180627D01*
X4400807Y-180418D01*
X4401117Y-180627D01*
Y-181043D01*
X4400807Y-181252D01*
G01Y-175627D02*
X4400497Y-175418D01*
Y-175002D01*
X4400807Y-174793D01*
X4401117Y-175002D01*
Y-175418D01*
X4400807Y-175627D01*
G01X4421577Y-180835D02*
Y-168335D01*
X4425607Y-178752D01*
X4429637Y-168335D01*
Y-180835D01*
G01X4434597Y-168335D02*
Y-177293D01*
X4435217Y-179169D01*
X4436457Y-180418D01*
X4438007Y-180835D01*
X4439557Y-180418D01*
X4440797Y-179169D01*
X4441417Y-177293D01*
Y-168335D01*
G01X4447152Y-179169D02*
X4448392Y-180210D01*
X4449787Y-180835D01*
X4451027D01*
X4452267Y-180210D01*
X4453197Y-179169D01*
X4453662Y-177710D01*
X4453352Y-176252D01*
X4452577Y-175002D01*
X4451182Y-174168D01*
X4449322Y-173752D01*
X4448237Y-172918D01*
X4447772Y-171460D01*
X4448082Y-170002D01*
X4448857Y-168960D01*
X4449942Y-168335D01*
X4451027D01*
X4452112Y-168752D01*
X4453042Y-169793D01*
G01X4462807Y-168335D02*
Y-180835D01*
G01X4459242Y-168335D02*
X4466372D01*
G01X4473192Y-176668D02*
X4477222D01*
G01X4484042Y-180835D02*
Y-168335D01*
X4491172Y-180835D01*
Y-168335D01*
G01X4500007Y-180835D02*
X4498767Y-180627D01*
X4497682Y-179794D01*
X4496752Y-178543D01*
X4496132Y-177085D01*
X4495822Y-175418D01*
Y-173752D01*
X4496132Y-172085D01*
X4496752Y-170627D01*
X4497682Y-169377D01*
X4498767Y-168543D01*
X4500007Y-168335D01*
X4501247Y-168543D01*
X4502332Y-169377D01*
X4503262Y-170627D01*
X4503882Y-172085D01*
X4504192Y-173752D01*
Y-175418D01*
X4503882Y-177085D01*
X4503262Y-178543D01*
X4502332Y-179794D01*
X4501247Y-180627D01*
X4500007Y-180835D01*
G01X4512407Y-168335D02*
Y-180835D01*
G01X4508842Y-168335D02*
X4515972D01*
G01X4522792Y-176668D02*
X4526822D01*
G01X4540617Y-169377D02*
X4539687Y-168752D01*
X4538602Y-168335D01*
X4537362D01*
X4535967Y-168960D01*
X4534882Y-170002D01*
X4534107Y-171252D01*
X4533487Y-173335D01*
X4533332Y-175210D01*
X4533642Y-177085D01*
X4534107Y-178335D01*
X4535037Y-179585D01*
X4536122Y-180418D01*
X4537207Y-180835D01*
X4538292D01*
X4539377Y-180418D01*
X4540307Y-179794D01*
X4541082Y-178960D01*
G01X4546197Y-168335D02*
Y-177293D01*
X4546817Y-179169D01*
X4548057Y-180418D01*
X4549607Y-180835D01*
X4551157Y-180418D01*
X4552397Y-179169D01*
X4553017Y-177293D01*
Y-168335D01*
G01X4562007D02*
Y-180835D01*
G01X4558442Y-168335D02*
X4565572D01*
G01X4572392Y-176668D02*
X4576422D01*
G01X4583707Y-168335D02*
Y-180835D01*
X4589907D01*
G01X4595332D02*
X4599207Y-168335D01*
X4603082Y-180835D01*
G01X4601687Y-176460D02*
X4596727D01*
G01X4611607Y-180835D02*
Y-175210D01*
X4608507Y-168335D01*
G01X4614707D02*
X4611607Y-175210D01*
G01X4627107Y-180835D02*
X4620907D01*
Y-168335D01*
X4627107D01*
G01X4624627Y-174377D02*
X4620907D01*
G01X4633307Y-180835D02*
Y-168335D01*
X4637182D01*
X4638422Y-168960D01*
X4639197Y-169793D01*
X4639507Y-171460D01*
X4639197Y-173127D01*
X4638267Y-174168D01*
X4637182Y-174793D01*
X4633307D01*
G01X4637182D02*
X4639507Y-180835D01*
G01X4260842Y-162085D02*
Y-149585D01*
X4267972Y-162085D01*
Y-149585D01*
G01X4276807Y-162085D02*
X4275567Y-161877D01*
X4274482Y-161044D01*
X4273552Y-159793D01*
X4272932Y-158335D01*
X4272622Y-156668D01*
Y-155002D01*
X4272932Y-153335D01*
X4273552Y-151877D01*
X4274482Y-150627D01*
X4275567Y-149793D01*
X4276807Y-149585D01*
X4278047Y-149793D01*
X4279132Y-150627D01*
X4280062Y-151877D01*
X4280682Y-153335D01*
X4280992Y-155002D01*
Y-156668D01*
X4280682Y-158335D01*
X4280062Y-159793D01*
X4279132Y-161044D01*
X4278047Y-161877D01*
X4276807Y-162085D01*
G01X4289207Y-149585D02*
Y-162085D01*
G01X4285642Y-149585D02*
X4292772D01*
G01X4304707Y-162085D02*
X4298507D01*
Y-149585D01*
X4304707D01*
G01X4302227Y-155627D02*
X4298507D01*
G01X4310752Y-160419D02*
X4311992Y-161460D01*
X4313387Y-162085D01*
X4314627D01*
X4315867Y-161460D01*
X4316797Y-160419D01*
X4317262Y-158960D01*
X4316952Y-157502D01*
X4316177Y-156252D01*
X4314782Y-155418D01*
X4312922Y-155002D01*
X4311837Y-154168D01*
X4311372Y-152710D01*
X4311682Y-151252D01*
X4312457Y-150210D01*
X4313542Y-149585D01*
X4314627D01*
X4315712Y-150002D01*
X4316642Y-151043D01*
G01X4326407Y-162502D02*
X4326097Y-162293D01*
Y-161877D01*
X4326407Y-161668D01*
X4326717Y-161877D01*
Y-162293D01*
X4326407Y-162502D01*
G01Y-156877D02*
X4326097Y-156668D01*
Y-156252D01*
X4326407Y-156043D01*
X4326717Y-156252D01*
Y-156668D01*
X4326407Y-156877D01*
G01X4270762Y-93335D02*
Y-80835D01*
X4276652D01*
G01X4274482Y-86877D02*
X4270762D01*
G01X4284247Y-80835D02*
X4287967D01*
G01X4286107D02*
Y-93335D01*
G01X4284247D02*
X4287967D01*
G01X4299437Y-87085D02*
X4302537D01*
Y-90835D01*
X4301607Y-92085D01*
X4300522Y-92918D01*
X4298972Y-93335D01*
X4297422Y-92918D01*
X4296337Y-92085D01*
X4295407Y-90835D01*
X4294787Y-89377D01*
X4294477Y-87710D01*
Y-86252D01*
X4294787Y-85002D01*
X4295407Y-83543D01*
X4296337Y-82293D01*
X4297267Y-81460D01*
X4298507Y-80835D01*
X4299592D01*
X4300832Y-81252D01*
X4301762Y-82085D01*
G01X4307497Y-80835D02*
Y-89793D01*
X4308117Y-91669D01*
X4309357Y-92918D01*
X4310907Y-93335D01*
X4312457Y-92918D01*
X4313697Y-91669D01*
X4314317Y-89793D01*
Y-80835D01*
G01X4320207Y-93335D02*
Y-80835D01*
X4324082D01*
X4325322Y-81460D01*
X4326097Y-82293D01*
X4326407Y-83960D01*
X4326097Y-85627D01*
X4325167Y-86668D01*
X4324082Y-87293D01*
X4320207D01*
G01X4324082D02*
X4326407Y-93335D01*
G01X4338807D02*
X4332607D01*
Y-80835D01*
X4338807D01*
G01X4336327Y-86877D02*
X4332607D01*
G01X4264975Y163606D02*
Y176106D01*
X4270865D01*
G01X4268695Y170064D02*
X4264975D01*
G01X4278460Y176106D02*
X4282180D01*
G01X4280320D02*
Y163606D01*
G01X4278460D02*
X4282180D01*
G01X4293650Y169856D02*
X4296750D01*
Y166106D01*
X4295820Y164856D01*
X4294735Y164023D01*
X4293185Y163606D01*
X4291635Y164023D01*
X4290550Y164856D01*
X4289620Y166106D01*
X4289000Y167564D01*
X4288690Y169231D01*
Y170689D01*
X4289000Y171939D01*
X4289620Y173398D01*
X4290550Y174648D01*
X4291480Y175481D01*
X4292720Y176106D01*
X4293805D01*
X4295045Y175689D01*
X4295975Y174856D01*
G01X4301710Y176106D02*
Y167148D01*
X4302330Y165272D01*
X4303570Y164023D01*
X4305120Y163606D01*
X4306670Y164023D01*
X4307910Y165272D01*
X4308530Y167148D01*
Y176106D01*
G01X4314420Y163606D02*
Y176106D01*
X4318295D01*
X4319535Y175481D01*
X4320310Y174648D01*
X4320620Y172981D01*
X4320310Y171314D01*
X4319380Y170273D01*
X4318295Y169648D01*
X4314420D01*
G01X4318295D02*
X4320620Y163606D01*
G01X4333020D02*
X4326820D01*
Y176106D01*
X4333020D01*
G01X4330540Y170064D02*
X4326820D01*
G01X4424560Y278773D02*
X4425180Y279398D01*
X4425645Y280439D01*
X4425955Y281898D01*
X4425645Y283148D01*
X4425025Y283981D01*
X4423940Y284606D01*
X4419755D01*
Y272106D01*
X4424870D01*
X4425955Y272939D01*
X4426575Y274189D01*
X4426885Y275648D01*
X4426575Y277106D01*
X4425645Y278356D01*
X4424560Y278773D01*
X4419755D01*
G01X4431845Y272106D02*
X4435720Y284606D01*
X4439595Y272106D01*
G01X4438200Y276481D02*
X4433240D01*
G01X4451530Y283564D02*
X4450600Y284189D01*
X4449515Y284606D01*
X4448275D01*
X4446880Y283981D01*
X4445795Y282939D01*
X4445020Y281689D01*
X4444400Y279606D01*
X4444245Y277731D01*
X4444555Y275856D01*
X4445020Y274606D01*
X4445950Y273356D01*
X4447035Y272523D01*
X4448120Y272106D01*
X4449205D01*
X4450290Y272523D01*
X4451220Y273147D01*
X4451995Y273981D01*
G01X4457110Y272106D02*
Y284606D01*
G01X4463000D02*
X4457110Y276897D01*
G01X4463930Y272106D02*
X4459745Y280439D01*
G01X4469510Y272106D02*
Y284606D01*
X4472610D01*
X4473850Y283981D01*
X4474780Y283148D01*
X4475555Y281898D01*
X4476175Y280439D01*
X4476330Y278356D01*
X4476175Y276273D01*
X4475555Y274814D01*
X4474780Y273564D01*
X4473850Y272731D01*
X4472610Y272106D01*
X4469510D01*
G01X4482220D02*
Y284606D01*
X4486095D01*
X4487335Y283981D01*
X4488110Y283148D01*
X4488420Y281481D01*
X4488110Y279814D01*
X4487180Y278773D01*
X4486095Y278148D01*
X4482220D01*
G01X4486095D02*
X4488420Y272106D01*
G01X4495860Y284606D02*
X4499580D01*
G01X4497720D02*
Y272106D01*
G01X4495860D02*
X4499580D01*
G01X4507020Y284606D02*
Y272106D01*
X4513220D01*
G01X4519420Y284606D02*
Y272106D01*
X4525620D01*
G01X4544065Y273772D02*
X4545305Y272731D01*
X4546700Y272106D01*
X4547940D01*
X4549180Y272731D01*
X4550110Y273772D01*
X4550575Y275231D01*
X4550265Y276689D01*
X4549490Y277939D01*
X4548095Y278773D01*
X4546235Y279189D01*
X4545150Y280023D01*
X4544685Y281481D01*
X4544995Y282939D01*
X4545770Y283981D01*
X4546855Y284606D01*
X4547940D01*
X4549025Y284189D01*
X4549955Y283148D01*
G01X4559720Y284606D02*
Y272106D01*
G01X4556155Y284606D02*
X4563285D01*
G01X4568710D02*
Y275648D01*
X4569330Y273772D01*
X4570570Y272523D01*
X4572120Y272106D01*
X4573670Y272523D01*
X4574910Y273772D01*
X4575530Y275648D01*
Y284606D01*
G01X4585760Y278773D02*
X4586380Y279398D01*
X4586845Y280439D01*
X4587155Y281898D01*
X4586845Y283148D01*
X4586225Y283981D01*
X4585140Y284606D01*
X4580955D01*
Y272106D01*
X4586070D01*
X4587155Y272939D01*
X4587775Y274189D01*
X4588085Y275648D01*
X4587775Y277106D01*
X4586845Y278356D01*
X4585760Y278773D01*
X4580955D01*
G01X4606220Y284606D02*
Y272106D01*
X4612420D01*
G01X4624820D02*
X4618620D01*
Y284606D01*
X4624820D01*
G01X4622340Y278564D02*
X4618620D01*
G01X4630555Y272106D02*
Y284606D01*
X4637685Y272106D01*
Y284606D01*
G01X4647450Y278356D02*
X4650550D01*
Y274606D01*
X4649620Y273356D01*
X4648535Y272523D01*
X4646985Y272106D01*
X4645435Y272523D01*
X4644350Y273356D01*
X4643420Y274606D01*
X4642800Y276064D01*
X4642490Y277731D01*
Y279189D01*
X4642800Y280439D01*
X4643420Y281898D01*
X4644350Y283148D01*
X4645280Y283981D01*
X4646520Y284606D01*
X4647605D01*
X4648845Y284189D01*
X4649775Y283356D01*
G01X4658920Y284606D02*
Y272106D01*
G01X4655355Y284606D02*
X4662485D01*
G01X4668065Y272106D02*
Y284606D01*
G01X4674575D02*
Y272106D01*
G01Y278356D02*
X4668065D01*
G01X4696120Y284606D02*
Y272106D01*
G01X4692555Y284606D02*
X4699685D01*
G01X4708520Y272106D02*
X4707280Y272314D01*
X4706195Y273147D01*
X4705265Y274398D01*
X4704645Y275856D01*
X4704335Y277523D01*
Y279189D01*
X4704645Y280856D01*
X4705265Y282314D01*
X4706195Y283564D01*
X4707280Y284398D01*
X4708520Y284606D01*
X4709760Y284398D01*
X4710845Y283564D01*
X4711775Y282314D01*
X4712395Y280856D01*
X4712705Y279189D01*
Y277523D01*
X4712395Y275856D01*
X4711775Y274398D01*
X4710845Y273147D01*
X4709760Y272314D01*
X4708520Y272106D01*
G01X4717820Y284606D02*
Y272106D01*
X4724020D01*
G01X4736420D02*
X4730220D01*
Y284606D01*
X4736420D01*
G01X4733940Y278564D02*
X4730220D01*
G01X4742620Y272106D02*
Y284606D01*
X4746495D01*
X4747735Y283981D01*
X4748510Y283148D01*
X4748820Y281481D01*
X4748510Y279814D01*
X4747580Y278773D01*
X4746495Y278148D01*
X4742620D01*
G01X4746495D02*
X4748820Y272106D01*
G01X4754245D02*
X4758120Y284606D01*
X4761995Y272106D01*
G01X4760600Y276481D02*
X4755640D01*
G01X4766955Y272106D02*
Y284606D01*
X4774085Y272106D01*
Y284606D01*
G01X4786330Y283564D02*
X4785400Y284189D01*
X4784315Y284606D01*
X4783075D01*
X4781680Y283981D01*
X4780595Y282939D01*
X4779820Y281689D01*
X4779200Y279606D01*
X4779045Y277731D01*
X4779355Y275856D01*
X4779820Y274606D01*
X4780750Y273356D01*
X4781835Y272523D01*
X4782920Y272106D01*
X4784005D01*
X4785090Y272523D01*
X4786020Y273147D01*
X4786795Y273981D01*
G01X4798420Y272106D02*
X4792220D01*
Y284606D01*
X4798420D01*
G01X4795940Y278564D02*
X4792220D01*
G01X4820120Y284606D02*
Y272106D01*
G01X4816555Y284606D02*
X4823685D01*
G01X4832520Y272106D02*
X4831280Y272314D01*
X4830195Y273147D01*
X4829265Y274398D01*
X4828645Y275856D01*
X4828335Y277523D01*
Y279189D01*
X4828645Y280856D01*
X4829265Y282314D01*
X4830195Y283564D01*
X4831280Y284398D01*
X4832520Y284606D01*
X4833760Y284398D01*
X4834845Y283564D01*
X4835775Y282314D01*
X4836395Y280856D01*
X4836705Y279189D01*
Y277523D01*
X4836395Y275856D01*
X4835775Y274398D01*
X4834845Y273147D01*
X4833760Y272314D01*
X4832520Y272106D01*
G01X4858560Y278773D02*
X4859180Y279398D01*
X4859645Y280439D01*
X4859955Y281898D01*
X4859645Y283148D01*
X4859025Y283981D01*
X4857940Y284606D01*
X4853755D01*
Y272106D01*
X4858870D01*
X4859955Y272939D01*
X4860575Y274189D01*
X4860885Y275648D01*
X4860575Y277106D01*
X4859645Y278356D01*
X4858560Y278773D01*
X4853755D01*
G01X4872820Y272106D02*
X4866620D01*
Y284606D01*
X4872820D01*
G01X4870340Y278564D02*
X4866620D01*
G01X4894210Y272106D02*
X4894520Y274814D01*
X4894985Y277106D01*
X4895605Y279189D01*
X4896380Y281481D01*
X4897620Y284606D01*
X4891420D01*
G01X4917615Y276273D02*
X4921335D01*
G01X4919320Y278981D02*
Y273564D01*
G01X4928930Y271689D02*
X4934510Y284606D01*
G01X4942105Y276273D02*
X4946135D01*
G01X4953110Y273981D02*
X4954040Y272939D01*
X4955125Y272314D01*
X4956520Y272106D01*
X4957915Y272523D01*
X4959000Y273356D01*
X4959775Y274814D01*
X4959930Y276481D01*
X4959620Y278148D01*
X4958845Y279189D01*
X4957760Y280023D01*
X4956675Y280231D01*
X4955590Y280023D01*
X4954195Y279189D01*
X4954660Y284606D01*
X4958845D01*
G01X4977290Y272106D02*
Y284606D01*
X4981320Y274189D01*
X4985350Y284606D01*
Y272106D01*
G01X4991860Y284606D02*
X4995580D01*
G01X4993720D02*
Y272106D01*
G01X4991860D02*
X4995580D01*
G01X5003020Y284606D02*
Y272106D01*
X5009220D01*
G01X5015265Y273772D02*
X5016505Y272731D01*
X5017900Y272106D01*
X5019140D01*
X5020380Y272731D01*
X5021310Y273772D01*
X5021775Y275231D01*
X5021465Y276689D01*
X5020690Y277939D01*
X5019295Y278773D01*
X5017435Y279189D01*
X5016350Y280023D01*
X5015885Y281481D01*
X5016195Y282939D01*
X5016970Y283981D01*
X5018055Y284606D01*
X5019140D01*
X5020225Y284189D01*
X5021155Y283148D01*
G01X4260105Y295023D02*
X4264135D01*
G01X4282890Y290856D02*
Y303356D01*
X4286920Y292939D01*
X4290950Y303356D01*
Y290856D01*
G01X4296375D02*
Y303356D01*
X4302265D01*
G01X4300095Y297314D02*
X4296375D01*
G01X4312650Y297106D02*
X4315750D01*
Y293356D01*
X4314820Y292106D01*
X4313735Y291273D01*
X4312185Y290856D01*
X4310635Y291273D01*
X4309550Y292106D01*
X4308620Y293356D01*
X4308000Y294814D01*
X4307690Y296481D01*
Y297939D01*
X4308000Y299189D01*
X4308620Y300648D01*
X4309550Y301898D01*
X4310480Y302731D01*
X4311720Y303356D01*
X4312805D01*
X4314045Y302939D01*
X4314975Y302106D01*
G01X4319470Y286689D02*
X4328770D01*
G01X4333265Y292522D02*
X4334505Y291481D01*
X4335900Y290856D01*
X4337140D01*
X4338380Y291481D01*
X4339310Y292522D01*
X4339775Y293981D01*
X4339465Y295439D01*
X4338690Y296689D01*
X4337295Y297523D01*
X4335435Y297939D01*
X4334350Y298773D01*
X4333885Y300231D01*
X4334195Y301689D01*
X4334970Y302731D01*
X4336055Y303356D01*
X4337140D01*
X4338225Y302939D01*
X4339155Y301898D01*
G01X4348920Y303356D02*
Y290856D01*
G01X4345355Y303356D02*
X4352485D01*
G01X4357910D02*
Y294398D01*
X4358530Y292522D01*
X4359770Y291273D01*
X4361320Y290856D01*
X4362870Y291273D01*
X4364110Y292522D01*
X4364730Y294398D01*
Y303356D01*
G01X4374960Y297523D02*
X4375580Y298148D01*
X4376045Y299189D01*
X4376355Y300648D01*
X4376045Y301898D01*
X4375425Y302731D01*
X4374340Y303356D01*
X4370155D01*
Y290856D01*
X4375270D01*
X4376355Y291689D01*
X4376975Y292939D01*
X4377285Y294398D01*
X4376975Y295856D01*
X4376045Y297106D01*
X4374960Y297523D01*
X4370155D01*
G01X4398520Y290439D02*
X4398210Y290648D01*
Y291064D01*
X4398520Y291273D01*
X4398830Y291064D01*
Y290648D01*
X4398520Y290439D01*
G01Y296064D02*
X4398210Y296273D01*
Y296689D01*
X4398520Y296898D01*
X4398830Y296689D01*
Y296273D01*
X4398520Y296064D01*
G01X4419290Y290856D02*
Y303356D01*
X4423320Y292939D01*
X4427350Y303356D01*
Y290856D01*
G01X4431845D02*
X4435720Y303356D01*
X4439595Y290856D01*
G01X4438200Y295231D02*
X4433240D01*
G01X4444555Y290856D02*
Y303356D01*
X4451685Y290856D01*
Y303356D01*
G01X4457110D02*
Y294398D01*
X4457730Y292522D01*
X4458970Y291273D01*
X4460520Y290856D01*
X4462070Y291273D01*
X4463310Y292522D01*
X4463930Y294398D01*
Y303356D01*
G01X4469975Y290856D02*
Y303356D01*
X4475865D01*
G01X4473695Y297314D02*
X4469975D01*
G01X4481445Y290856D02*
X4485320Y303356D01*
X4489195Y290856D01*
G01X4487800Y295231D02*
X4482840D01*
G01X4501130Y302314D02*
X4500200Y302939D01*
X4499115Y303356D01*
X4497875D01*
X4496480Y302731D01*
X4495395Y301689D01*
X4494620Y300439D01*
X4494000Y298356D01*
X4493845Y296481D01*
X4494155Y294606D01*
X4494620Y293356D01*
X4495550Y292106D01*
X4496635Y291273D01*
X4497720Y290856D01*
X4498805D01*
X4499890Y291273D01*
X4500820Y291897D01*
X4501595Y292731D01*
G01X4510120Y303356D02*
Y290856D01*
G01X4506555Y303356D02*
X4513685D01*
G01X4519110D02*
Y294398D01*
X4519730Y292522D01*
X4520970Y291273D01*
X4522520Y290856D01*
X4524070Y291273D01*
X4525310Y292522D01*
X4525930Y294398D01*
Y303356D01*
G01X4531820Y290856D02*
Y303356D01*
X4535695D01*
X4536935Y302731D01*
X4537710Y301898D01*
X4538020Y300231D01*
X4537710Y298564D01*
X4536780Y297523D01*
X4535695Y296898D01*
X4531820D01*
G01X4535695D02*
X4538020Y290856D01*
G01X4545460Y303356D02*
X4549180D01*
G01X4547320D02*
Y290856D01*
G01X4545460D02*
X4549180D01*
G01X4556155D02*
Y303356D01*
X4563285Y290856D01*
Y303356D01*
G01X4573050Y297106D02*
X4576150D01*
Y293356D01*
X4575220Y292106D01*
X4574135Y291273D01*
X4572585Y290856D01*
X4571035Y291273D01*
X4569950Y292106D01*
X4569020Y293356D01*
X4568400Y294814D01*
X4568090Y296481D01*
Y297939D01*
X4568400Y299189D01*
X4569020Y300648D01*
X4569950Y301898D01*
X4570880Y302731D01*
X4572120Y303356D01*
X4573205D01*
X4574445Y302939D01*
X4575375Y302106D01*
G01X4593665Y292522D02*
X4594905Y291481D01*
X4596300Y290856D01*
X4597540D01*
X4598780Y291481D01*
X4599710Y292522D01*
X4600175Y293981D01*
X4599865Y295439D01*
X4599090Y296689D01*
X4597695Y297523D01*
X4595835Y297939D01*
X4594750Y298773D01*
X4594285Y300231D01*
X4594595Y301689D01*
X4595370Y302731D01*
X4596455Y303356D01*
X4597540D01*
X4598625Y302939D01*
X4599555Y301898D01*
G01X4609320Y303356D02*
Y290856D01*
G01X4605755Y303356D02*
X4612885D01*
G01X4618310D02*
Y294398D01*
X4618930Y292522D01*
X4620170Y291273D01*
X4621720Y290856D01*
X4623270Y291273D01*
X4624510Y292522D01*
X4625130Y294398D01*
Y303356D01*
G01X4635360Y297523D02*
X4635980Y298148D01*
X4636445Y299189D01*
X4636755Y300648D01*
X4636445Y301898D01*
X4635825Y302731D01*
X4634740Y303356D01*
X4630555D01*
Y290856D01*
X4635670D01*
X4636755Y291689D01*
X4637375Y292939D01*
X4637685Y294398D01*
X4637375Y295856D01*
X4636445Y297106D01*
X4635360Y297523D01*
X4630555D01*
G01X4655820Y303356D02*
Y290856D01*
X4662020D01*
G01X4674420D02*
X4668220D01*
Y303356D01*
X4674420D01*
G01X4671940Y297314D02*
X4668220D01*
G01X4680155Y290856D02*
Y303356D01*
X4687285Y290856D01*
Y303356D01*
G01X4697050Y297106D02*
X4700150D01*
Y293356D01*
X4699220Y292106D01*
X4698135Y291273D01*
X4696585Y290856D01*
X4695035Y291273D01*
X4693950Y292106D01*
X4693020Y293356D01*
X4692400Y294814D01*
X4692090Y296481D01*
Y297939D01*
X4692400Y299189D01*
X4693020Y300648D01*
X4693950Y301898D01*
X4694880Y302731D01*
X4696120Y303356D01*
X4697205D01*
X4698445Y302939D01*
X4699375Y302106D01*
G01X4708520Y303356D02*
Y290856D01*
G01X4704955Y303356D02*
X4712085D01*
G01X4717665Y290856D02*
Y303356D01*
G01X4724175D02*
Y290856D01*
G01Y297106D02*
X4717665D01*
G01X4420065Y311272D02*
X4421305Y310231D01*
X4422700Y309606D01*
X4423940D01*
X4425180Y310231D01*
X4426110Y311272D01*
X4426575Y312731D01*
X4426265Y314189D01*
X4425490Y315439D01*
X4424095Y316273D01*
X4422235Y316689D01*
X4421150Y317523D01*
X4420685Y318981D01*
X4420995Y320439D01*
X4421770Y321481D01*
X4422855Y322106D01*
X4423940D01*
X4425025Y321689D01*
X4425955Y320648D01*
G01X4432310Y322106D02*
Y313148D01*
X4432930Y311272D01*
X4434170Y310023D01*
X4435720Y309606D01*
X4437270Y310023D01*
X4438510Y311272D01*
X4439130Y313148D01*
Y322106D01*
G01X4445020Y309606D02*
Y322106D01*
X4448895D01*
X4450135Y321481D01*
X4450910Y320648D01*
X4451220Y318981D01*
X4450910Y317314D01*
X4449980Y316273D01*
X4448895Y315648D01*
X4445020D01*
G01X4448895D02*
X4451220Y309606D01*
G01X4457575D02*
Y322106D01*
X4463465D01*
G01X4461295Y316064D02*
X4457575D01*
G01X4469045Y309606D02*
X4472920Y322106D01*
X4476795Y309606D01*
G01X4475400Y313981D02*
X4470440D01*
G01X4488730Y321064D02*
X4487800Y321689D01*
X4486715Y322106D01*
X4485475D01*
X4484080Y321481D01*
X4482995Y320439D01*
X4482220Y319189D01*
X4481600Y317106D01*
X4481445Y315231D01*
X4481755Y313356D01*
X4482220Y312106D01*
X4483150Y310856D01*
X4484235Y310023D01*
X4485320Y309606D01*
X4486405D01*
X4487490Y310023D01*
X4488420Y310647D01*
X4489195Y311481D01*
G01X4500820Y309606D02*
X4494620D01*
Y322106D01*
X4500820D01*
G01X4498340Y316064D02*
X4494620D01*
G01X4522520Y309606D02*
X4521280Y309814D01*
X4520195Y310647D01*
X4519265Y311898D01*
X4518645Y313356D01*
X4518335Y315023D01*
Y316689D01*
X4518645Y318356D01*
X4519265Y319814D01*
X4520195Y321064D01*
X4521280Y321898D01*
X4522520Y322106D01*
X4523760Y321898D01*
X4524845Y321064D01*
X4525775Y319814D01*
X4526395Y318356D01*
X4526705Y316689D01*
Y315023D01*
X4526395Y313356D01*
X4525775Y311898D01*
X4524845Y310647D01*
X4523760Y309814D01*
X4522520Y309606D01*
G01X4531975D02*
Y322106D01*
X4537865D01*
G01X4535695Y316064D02*
X4531975D01*
G01X4555690Y309606D02*
Y322106D01*
X4559720Y311689D01*
X4563750Y322106D01*
Y309606D01*
G01X4568710Y322106D02*
Y313148D01*
X4569330Y311272D01*
X4570570Y310023D01*
X4572120Y309606D01*
X4573670Y310023D01*
X4574910Y311272D01*
X4575530Y313148D01*
Y322106D01*
G01X4581265Y311272D02*
X4582505Y310231D01*
X4583900Y309606D01*
X4585140D01*
X4586380Y310231D01*
X4587310Y311272D01*
X4587775Y312731D01*
X4587465Y314189D01*
X4586690Y315439D01*
X4585295Y316273D01*
X4583435Y316689D01*
X4582350Y317523D01*
X4581885Y318981D01*
X4582195Y320439D01*
X4582970Y321481D01*
X4584055Y322106D01*
X4585140D01*
X4586225Y321689D01*
X4587155Y320648D01*
G01X4596920Y322106D02*
Y309606D01*
G01X4593355Y322106D02*
X4600485D01*
G01X4607305Y313773D02*
X4611335D01*
G01X4618155Y309606D02*
Y322106D01*
X4625285Y309606D01*
Y322106D01*
G01X4634120Y309606D02*
X4632880Y309814D01*
X4631795Y310647D01*
X4630865Y311898D01*
X4630245Y313356D01*
X4629935Y315023D01*
Y316689D01*
X4630245Y318356D01*
X4630865Y319814D01*
X4631795Y321064D01*
X4632880Y321898D01*
X4634120Y322106D01*
X4635360Y321898D01*
X4636445Y321064D01*
X4637375Y319814D01*
X4637995Y318356D01*
X4638305Y316689D01*
Y315023D01*
X4637995Y313356D01*
X4637375Y311898D01*
X4636445Y310647D01*
X4635360Y309814D01*
X4634120Y309606D01*
G01X4646520Y322106D02*
Y309606D01*
G01X4642955Y322106D02*
X4650085D01*
G01X4656905Y313773D02*
X4660935D01*
G01X4674730Y321064D02*
X4673800Y321689D01*
X4672715Y322106D01*
X4671475D01*
X4670080Y321481D01*
X4668995Y320439D01*
X4668220Y319189D01*
X4667600Y317106D01*
X4667445Y315231D01*
X4667755Y313356D01*
X4668220Y312106D01*
X4669150Y310856D01*
X4670235Y310023D01*
X4671320Y309606D01*
X4672405D01*
X4673490Y310023D01*
X4674420Y310647D01*
X4675195Y311481D01*
G01X4680310Y322106D02*
Y313148D01*
X4680930Y311272D01*
X4682170Y310023D01*
X4683720Y309606D01*
X4685270Y310023D01*
X4686510Y311272D01*
X4687130Y313148D01*
Y322106D01*
G01X4696120D02*
Y309606D01*
G01X4692555Y322106D02*
X4699685D01*
G01X4706505Y313773D02*
X4710535D01*
G01X4717820Y322106D02*
Y309606D01*
X4724020D01*
G01X4729445D02*
X4733320Y322106D01*
X4737195Y309606D01*
G01X4735800Y313981D02*
X4730840D01*
G01X4745720Y309606D02*
Y315231D01*
X4742620Y322106D01*
G01X4748820D02*
X4745720Y315231D01*
G01X4761220Y309606D02*
X4755020D01*
Y322106D01*
X4761220D01*
G01X4758740Y316064D02*
X4755020D01*
G01X4767420Y309606D02*
Y322106D01*
X4771295D01*
X4772535Y321481D01*
X4773310Y320648D01*
X4773620Y318981D01*
X4773310Y317314D01*
X4772380Y316273D01*
X4771295Y315648D01*
X4767420D01*
G01X4771295D02*
X4773620Y309606D01*
G01X4260105Y332523D02*
X4264135D01*
G01X4282890Y328356D02*
Y340856D01*
X4286920Y330439D01*
X4290950Y340856D01*
Y328356D01*
G01X4295445D02*
X4299320Y340856D01*
X4303195Y328356D01*
G01X4301800Y332731D02*
X4296840D01*
G01X4308465Y328356D02*
X4314975Y340856D01*
G01X4308465D02*
X4314975Y328356D01*
G01X4319470Y324189D02*
X4328770D01*
G01X4333110Y328356D02*
Y340856D01*
X4336210D01*
X4337450Y340231D01*
X4338380Y339398D01*
X4339155Y338148D01*
X4339775Y336689D01*
X4339930Y334606D01*
X4339775Y332523D01*
X4339155Y331064D01*
X4338380Y329814D01*
X4337450Y328981D01*
X4336210Y328356D01*
X4333110D01*
G01X4352020D02*
X4345820D01*
Y340856D01*
X4352020D01*
G01X4349540Y334814D02*
X4345820D01*
G01X4358220Y328356D02*
Y340856D01*
X4361940D01*
X4363180Y340231D01*
X4364110Y338773D01*
X4364420Y337106D01*
X4364110Y335439D01*
X4363335Y334189D01*
X4361940Y333564D01*
X4358220D01*
G01X4373720Y340856D02*
Y328356D01*
G01X4370155Y340856D02*
X4377285D01*
G01X4382865Y328356D02*
Y340856D01*
G01X4389375D02*
Y328356D01*
G01Y334606D02*
X4382865D01*
G01X4398520Y327939D02*
X4398210Y328148D01*
Y328564D01*
X4398520Y328773D01*
X4398830Y328564D01*
Y328148D01*
X4398520Y327939D01*
G01Y333564D02*
X4398210Y333773D01*
Y334189D01*
X4398520Y334398D01*
X4398830Y334189D01*
Y333773D01*
X4398520Y333564D01*
G01X4419910Y328356D02*
Y340856D01*
X4423010D01*
X4424250Y340231D01*
X4425180Y339398D01*
X4425955Y338148D01*
X4426575Y336689D01*
X4426730Y334606D01*
X4426575Y332523D01*
X4425955Y331064D01*
X4425180Y329814D01*
X4424250Y328981D01*
X4423010Y328356D01*
X4419910D01*
G01X4438820D02*
X4432620D01*
Y340856D01*
X4438820D01*
G01X4436340Y334814D02*
X4432620D01*
G01X4445020Y328356D02*
Y340856D01*
X4448740D01*
X4449980Y340231D01*
X4450910Y338773D01*
X4451220Y337106D01*
X4450910Y335439D01*
X4450135Y334189D01*
X4448740Y333564D01*
X4445020D01*
G01X4460520Y340856D02*
Y328356D01*
G01X4456955Y340856D02*
X4464085D01*
G01X4469665Y328356D02*
Y340856D01*
G01X4476175D02*
Y328356D01*
G01Y334606D02*
X4469665D01*
G01X4494775Y328356D02*
Y340856D01*
X4500665D01*
G01X4498495Y334814D02*
X4494775D01*
G01X4507020Y328356D02*
Y340856D01*
X4510895D01*
X4512135Y340231D01*
X4512910Y339398D01*
X4513220Y337731D01*
X4512910Y336064D01*
X4511980Y335023D01*
X4510895Y334398D01*
X4507020D01*
G01X4510895D02*
X4513220Y328356D01*
G01X4522520D02*
X4521280Y328564D01*
X4520195Y329397D01*
X4519265Y330648D01*
X4518645Y332106D01*
X4518335Y333773D01*
Y335439D01*
X4518645Y337106D01*
X4519265Y338564D01*
X4520195Y339814D01*
X4521280Y340648D01*
X4522520Y340856D01*
X4523760Y340648D01*
X4524845Y339814D01*
X4525775Y338564D01*
X4526395Y337106D01*
X4526705Y335439D01*
Y333773D01*
X4526395Y332106D01*
X4525775Y330648D01*
X4524845Y329397D01*
X4523760Y328564D01*
X4522520Y328356D01*
G01X4530890D02*
Y340856D01*
X4534920Y330439D01*
X4538950Y340856D01*
Y328356D01*
G01X4556465Y330022D02*
X4557705Y328981D01*
X4559100Y328356D01*
X4560340D01*
X4561580Y328981D01*
X4562510Y330022D01*
X4562975Y331481D01*
X4562665Y332939D01*
X4561890Y334189D01*
X4560495Y335023D01*
X4558635Y335439D01*
X4557550Y336273D01*
X4557085Y337731D01*
X4557395Y339189D01*
X4558170Y340231D01*
X4559255Y340856D01*
X4560340D01*
X4561425Y340439D01*
X4562355Y339398D01*
G01X4572120Y340856D02*
Y328356D01*
G01X4568555Y340856D02*
X4575685D01*
G01X4580645Y328356D02*
X4584520Y340856D01*
X4588395Y328356D01*
G01X4587000Y332731D02*
X4582040D01*
G01X4593820Y328356D02*
Y340856D01*
X4597695D01*
X4598935Y340231D01*
X4599710Y339398D01*
X4600020Y337731D01*
X4599710Y336064D01*
X4598780Y335023D01*
X4597695Y334398D01*
X4593820D01*
G01X4597695D02*
X4600020Y328356D01*
G01X4609320Y340856D02*
Y328356D01*
G01X4605755Y340856D02*
X4612885D01*
G01X4631020D02*
Y328356D01*
X4637220D01*
G01X4642645D02*
X4646520Y340856D01*
X4650395Y328356D01*
G01X4649000Y332731D02*
X4644040D01*
G01X4658920Y328356D02*
Y333981D01*
X4655820Y340856D01*
G01X4662020D02*
X4658920Y333981D01*
G01X4674420Y328356D02*
X4668220D01*
Y340856D01*
X4674420D01*
G01X4671940Y334814D02*
X4668220D01*
G01X4680620Y328356D02*
Y340856D01*
X4684495D01*
X4685735Y340231D01*
X4686510Y339398D01*
X4686820Y337731D01*
X4686510Y336064D01*
X4685580Y335023D01*
X4684495Y334398D01*
X4680620D01*
G01X4684495D02*
X4686820Y328356D01*
G01X4708520Y340856D02*
Y328356D01*
G01X4704955Y340856D02*
X4712085D01*
G01X4720920Y328356D02*
X4719680Y328564D01*
X4718595Y329397D01*
X4717665Y330648D01*
X4717045Y332106D01*
X4716735Y333773D01*
Y335439D01*
X4717045Y337106D01*
X4717665Y338564D01*
X4718595Y339814D01*
X4719680Y340648D01*
X4720920Y340856D01*
X4722160Y340648D01*
X4723245Y339814D01*
X4724175Y338564D01*
X4724795Y337106D01*
X4725105Y335439D01*
Y333773D01*
X4724795Y332106D01*
X4724175Y330648D01*
X4723245Y329397D01*
X4722160Y328564D01*
X4720920Y328356D01*
G01X4745720Y340856D02*
Y328356D01*
G01X4742155Y340856D02*
X4749285D01*
G01X4754865Y328356D02*
Y340856D01*
G01X4761375D02*
Y328356D01*
G01Y334606D02*
X4754865D01*
G01X4773620Y328356D02*
X4767420D01*
Y340856D01*
X4773620D01*
G01X4771140Y334814D02*
X4767420D01*
G01X4260105Y351273D02*
X4264135D01*
G01X4282890Y347106D02*
Y359606D01*
X4286920Y349189D01*
X4290950Y359606D01*
Y347106D01*
G01X4295755D02*
Y359606D01*
X4302885Y347106D01*
Y359606D01*
G01X4315130Y358564D02*
X4314200Y359189D01*
X4313115Y359606D01*
X4311875D01*
X4310480Y358981D01*
X4309395Y357939D01*
X4308620Y356689D01*
X4308000Y354606D01*
X4307845Y352731D01*
X4308155Y350856D01*
X4308620Y349606D01*
X4309550Y348356D01*
X4310635Y347523D01*
X4311720Y347106D01*
X4312805D01*
X4313890Y347523D01*
X4314820Y348147D01*
X4315595Y348981D01*
G01X4319470Y342939D02*
X4328770D01*
G01X4333420Y359606D02*
Y347106D01*
X4339620D01*
G01X4345045D02*
X4348920Y359606D01*
X4352795Y347106D01*
G01X4351400Y351481D02*
X4346440D01*
G01X4361320Y347106D02*
Y352731D01*
X4358220Y359606D01*
G01X4364420D02*
X4361320Y352731D01*
G01X4376820Y347106D02*
X4370620D01*
Y359606D01*
X4376820D01*
G01X4374340Y353564D02*
X4370620D01*
G01X4383020Y347106D02*
Y359606D01*
X4386895D01*
X4388135Y358981D01*
X4388910Y358148D01*
X4389220Y356481D01*
X4388910Y354814D01*
X4387980Y353773D01*
X4386895Y353148D01*
X4383020D01*
G01X4386895D02*
X4389220Y347106D01*
G01X4398520Y346689D02*
X4398210Y346898D01*
Y347314D01*
X4398520Y347523D01*
X4398830Y347314D01*
Y346898D01*
X4398520Y346689D01*
G01Y352314D02*
X4398210Y352523D01*
Y352939D01*
X4398520Y353148D01*
X4398830Y352939D01*
Y352523D01*
X4398520Y352314D01*
G01X4419290Y347106D02*
Y359606D01*
X4423320Y349189D01*
X4427350Y359606D01*
Y347106D01*
G01X4432310Y359606D02*
Y350648D01*
X4432930Y348772D01*
X4434170Y347523D01*
X4435720Y347106D01*
X4437270Y347523D01*
X4438510Y348772D01*
X4439130Y350648D01*
Y359606D01*
G01X4444865Y348772D02*
X4446105Y347731D01*
X4447500Y347106D01*
X4448740D01*
X4449980Y347731D01*
X4450910Y348772D01*
X4451375Y350231D01*
X4451065Y351689D01*
X4450290Y352939D01*
X4448895Y353773D01*
X4447035Y354189D01*
X4445950Y355023D01*
X4445485Y356481D01*
X4445795Y357939D01*
X4446570Y358981D01*
X4447655Y359606D01*
X4448740D01*
X4449825Y359189D01*
X4450755Y358148D01*
G01X4460520Y359606D02*
Y347106D01*
G01X4456955Y359606D02*
X4464085D01*
G01X4470905Y351273D02*
X4474935D01*
G01X4481755Y347106D02*
Y359606D01*
X4488885Y347106D01*
Y359606D01*
G01X4497720Y347106D02*
X4496480Y347314D01*
X4495395Y348147D01*
X4494465Y349398D01*
X4493845Y350856D01*
X4493535Y352523D01*
Y354189D01*
X4493845Y355856D01*
X4494465Y357314D01*
X4495395Y358564D01*
X4496480Y359398D01*
X4497720Y359606D01*
X4498960Y359398D01*
X4500045Y358564D01*
X4500975Y357314D01*
X4501595Y355856D01*
X4501905Y354189D01*
Y352523D01*
X4501595Y350856D01*
X4500975Y349398D01*
X4500045Y348147D01*
X4498960Y347314D01*
X4497720Y347106D01*
G01X4510120Y359606D02*
Y347106D01*
G01X4506555Y359606D02*
X4513685D01*
G01X4520505Y351273D02*
X4524535D01*
G01X4538330Y358564D02*
X4537400Y359189D01*
X4536315Y359606D01*
X4535075D01*
X4533680Y358981D01*
X4532595Y357939D01*
X4531820Y356689D01*
X4531200Y354606D01*
X4531045Y352731D01*
X4531355Y350856D01*
X4531820Y349606D01*
X4532750Y348356D01*
X4533835Y347523D01*
X4534920Y347106D01*
X4536005D01*
X4537090Y347523D01*
X4538020Y348147D01*
X4538795Y348981D01*
G01X4543910Y359606D02*
Y350648D01*
X4544530Y348772D01*
X4545770Y347523D01*
X4547320Y347106D01*
X4548870Y347523D01*
X4550110Y348772D01*
X4550730Y350648D01*
Y359606D01*
G01X4559720D02*
Y347106D01*
G01X4556155Y359606D02*
X4563285D01*
G01X4570105Y351273D02*
X4574135D01*
G01X4581420Y359606D02*
Y347106D01*
X4587620D01*
G01X4593045D02*
X4596920Y359606D01*
X4600795Y347106D01*
G01X4599400Y351481D02*
X4594440D01*
G01X4609320Y347106D02*
Y352731D01*
X4606220Y359606D01*
G01X4612420D02*
X4609320Y352731D01*
G01X4624820Y347106D02*
X4618620D01*
Y359606D01*
X4624820D01*
G01X4622340Y353564D02*
X4618620D01*
G01X4631020Y347106D02*
Y359606D01*
X4634895D01*
X4636135Y358981D01*
X4636910Y358148D01*
X4637220Y356481D01*
X4636910Y354814D01*
X4635980Y353773D01*
X4634895Y353148D01*
X4631020D01*
G01X4634895D02*
X4637220Y347106D01*
G01X4258555Y365856D02*
Y378356D01*
X4265685Y365856D01*
Y378356D01*
G01X4274520Y365856D02*
X4273280Y366064D01*
X4272195Y366897D01*
X4271265Y368148D01*
X4270645Y369606D01*
X4270335Y371273D01*
Y372939D01*
X4270645Y374606D01*
X4271265Y376064D01*
X4272195Y377314D01*
X4273280Y378148D01*
X4274520Y378356D01*
X4275760Y378148D01*
X4276845Y377314D01*
X4277775Y376064D01*
X4278395Y374606D01*
X4278705Y372939D01*
Y371273D01*
X4278395Y369606D01*
X4277775Y368148D01*
X4276845Y366897D01*
X4275760Y366064D01*
X4274520Y365856D01*
G01X4286920Y378356D02*
Y365856D01*
G01X4283355Y378356D02*
X4290485D01*
G01X4302420Y365856D02*
X4296220D01*
Y378356D01*
X4302420D01*
G01X4299940Y372314D02*
X4296220D01*
G01X4308465Y367522D02*
X4309705Y366481D01*
X4311100Y365856D01*
X4312340D01*
X4313580Y366481D01*
X4314510Y367522D01*
X4314975Y368981D01*
X4314665Y370439D01*
X4313890Y371689D01*
X4312495Y372523D01*
X4310635Y372939D01*
X4309550Y373773D01*
X4309085Y375231D01*
X4309395Y376689D01*
X4310170Y377731D01*
X4311255Y378356D01*
X4312340D01*
X4313425Y377939D01*
X4314355Y376898D01*
G01X4324120Y365439D02*
X4323810Y365648D01*
Y366064D01*
X4324120Y366273D01*
X4324430Y366064D01*
Y365648D01*
X4324120Y365439D01*
G01Y371064D02*
X4323810Y371273D01*
Y371689D01*
X4324120Y371898D01*
X4324430Y371689D01*
Y371273D01*
X4324120Y371064D01*
G01X4268475Y434606D02*
Y447106D01*
X4274365D01*
G01X4272195Y441064D02*
X4268475D01*
G01X4281960Y447106D02*
X4285680D01*
G01X4283820D02*
Y434606D01*
G01X4281960D02*
X4285680D01*
G01X4297150Y440856D02*
X4300250D01*
Y437106D01*
X4299320Y435856D01*
X4298235Y435023D01*
X4296685Y434606D01*
X4295135Y435023D01*
X4294050Y435856D01*
X4293120Y437106D01*
X4292500Y438564D01*
X4292190Y440231D01*
Y441689D01*
X4292500Y442939D01*
X4293120Y444398D01*
X4294050Y445648D01*
X4294980Y446481D01*
X4296220Y447106D01*
X4297305D01*
X4298545Y446689D01*
X4299475Y445856D01*
G01X4305210Y447106D02*
Y438148D01*
X4305830Y436272D01*
X4307070Y435023D01*
X4308620Y434606D01*
X4310170Y435023D01*
X4311410Y436272D01*
X4312030Y438148D01*
Y447106D01*
G01X4317920Y434606D02*
Y447106D01*
X4321795D01*
X4323035Y446481D01*
X4323810Y445648D01*
X4324120Y443981D01*
X4323810Y442314D01*
X4322880Y441273D01*
X4321795Y440648D01*
X4317920D01*
G01X4321795D02*
X4324120Y434606D01*
G01X4336520D02*
X4330320D01*
Y447106D01*
X4336520D01*
G01X4334040Y441064D02*
X4330320D01*
G01X4425560Y551273D02*
X4426180Y551898D01*
X4426645Y552939D01*
X4426955Y554398D01*
X4426645Y555648D01*
X4426025Y556481D01*
X4424940Y557106D01*
X4420755D01*
Y544606D01*
X4425870D01*
X4426955Y545439D01*
X4427575Y546689D01*
X4427885Y548148D01*
X4427575Y549606D01*
X4426645Y550856D01*
X4425560Y551273D01*
X4420755D01*
G01X4432845Y544606D02*
X4436720Y557106D01*
X4440595Y544606D01*
G01X4439200Y548981D02*
X4434240D01*
G01X4452530Y556064D02*
X4451600Y556689D01*
X4450515Y557106D01*
X4449275D01*
X4447880Y556481D01*
X4446795Y555439D01*
X4446020Y554189D01*
X4445400Y552106D01*
X4445245Y550231D01*
X4445555Y548356D01*
X4446020Y547106D01*
X4446950Y545856D01*
X4448035Y545023D01*
X4449120Y544606D01*
X4450205D01*
X4451290Y545023D01*
X4452220Y545647D01*
X4452995Y546481D01*
G01X4458110Y544606D02*
Y557106D01*
G01X4464000D02*
X4458110Y549397D01*
G01X4464930Y544606D02*
X4460745Y552939D01*
G01X4470510Y544606D02*
Y557106D01*
X4473610D01*
X4474850Y556481D01*
X4475780Y555648D01*
X4476555Y554398D01*
X4477175Y552939D01*
X4477330Y550856D01*
X4477175Y548773D01*
X4476555Y547314D01*
X4475780Y546064D01*
X4474850Y545231D01*
X4473610Y544606D01*
X4470510D01*
G01X4483220D02*
Y557106D01*
X4487095D01*
X4488335Y556481D01*
X4489110Y555648D01*
X4489420Y553981D01*
X4489110Y552314D01*
X4488180Y551273D01*
X4487095Y550648D01*
X4483220D01*
G01X4487095D02*
X4489420Y544606D01*
G01X4496860Y557106D02*
X4500580D01*
G01X4498720D02*
Y544606D01*
G01X4496860D02*
X4500580D01*
G01X4508020Y557106D02*
Y544606D01*
X4514220D01*
G01X4520420Y557106D02*
Y544606D01*
X4526620D01*
G01X4545065Y546272D02*
X4546305Y545231D01*
X4547700Y544606D01*
X4548940D01*
X4550180Y545231D01*
X4551110Y546272D01*
X4551575Y547731D01*
X4551265Y549189D01*
X4550490Y550439D01*
X4549095Y551273D01*
X4547235Y551689D01*
X4546150Y552523D01*
X4545685Y553981D01*
X4545995Y555439D01*
X4546770Y556481D01*
X4547855Y557106D01*
X4548940D01*
X4550025Y556689D01*
X4550955Y555648D01*
G01X4560720Y557106D02*
Y544606D01*
G01X4557155Y557106D02*
X4564285D01*
G01X4569710D02*
Y548148D01*
X4570330Y546272D01*
X4571570Y545023D01*
X4573120Y544606D01*
X4574670Y545023D01*
X4575910Y546272D01*
X4576530Y548148D01*
Y557106D01*
G01X4586760Y551273D02*
X4587380Y551898D01*
X4587845Y552939D01*
X4588155Y554398D01*
X4587845Y555648D01*
X4587225Y556481D01*
X4586140Y557106D01*
X4581955D01*
Y544606D01*
X4587070D01*
X4588155Y545439D01*
X4588775Y546689D01*
X4589085Y548148D01*
X4588775Y549606D01*
X4587845Y550856D01*
X4586760Y551273D01*
X4581955D01*
G01X4607220Y557106D02*
Y544606D01*
X4613420D01*
G01X4625820D02*
X4619620D01*
Y557106D01*
X4625820D01*
G01X4623340Y551064D02*
X4619620D01*
G01X4631555Y544606D02*
Y557106D01*
X4638685Y544606D01*
Y557106D01*
G01X4648450Y550856D02*
X4651550D01*
Y547106D01*
X4650620Y545856D01*
X4649535Y545023D01*
X4647985Y544606D01*
X4646435Y545023D01*
X4645350Y545856D01*
X4644420Y547106D01*
X4643800Y548564D01*
X4643490Y550231D01*
Y551689D01*
X4643800Y552939D01*
X4644420Y554398D01*
X4645350Y555648D01*
X4646280Y556481D01*
X4647520Y557106D01*
X4648605D01*
X4649845Y556689D01*
X4650775Y555856D01*
G01X4659920Y557106D02*
Y544606D01*
G01X4656355Y557106D02*
X4663485D01*
G01X4669065Y544606D02*
Y557106D01*
G01X4675575D02*
Y544606D01*
G01Y550856D02*
X4669065D01*
G01X4697120Y557106D02*
Y544606D01*
G01X4693555Y557106D02*
X4700685D01*
G01X4709520Y544606D02*
X4708280Y544814D01*
X4707195Y545647D01*
X4706265Y546898D01*
X4705645Y548356D01*
X4705335Y550023D01*
Y551689D01*
X4705645Y553356D01*
X4706265Y554814D01*
X4707195Y556064D01*
X4708280Y556898D01*
X4709520Y557106D01*
X4710760Y556898D01*
X4711845Y556064D01*
X4712775Y554814D01*
X4713395Y553356D01*
X4713705Y551689D01*
Y550023D01*
X4713395Y548356D01*
X4712775Y546898D01*
X4711845Y545647D01*
X4710760Y544814D01*
X4709520Y544606D01*
G01X4718820Y557106D02*
Y544606D01*
X4725020D01*
G01X4737420D02*
X4731220D01*
Y557106D01*
X4737420D01*
G01X4734940Y551064D02*
X4731220D01*
G01X4743620Y544606D02*
Y557106D01*
X4747495D01*
X4748735Y556481D01*
X4749510Y555648D01*
X4749820Y553981D01*
X4749510Y552314D01*
X4748580Y551273D01*
X4747495Y550648D01*
X4743620D01*
G01X4747495D02*
X4749820Y544606D01*
G01X4755245D02*
X4759120Y557106D01*
X4762995Y544606D01*
G01X4761600Y548981D02*
X4756640D01*
G01X4767955Y544606D02*
Y557106D01*
X4775085Y544606D01*
Y557106D01*
G01X4787330Y556064D02*
X4786400Y556689D01*
X4785315Y557106D01*
X4784075D01*
X4782680Y556481D01*
X4781595Y555439D01*
X4780820Y554189D01*
X4780200Y552106D01*
X4780045Y550231D01*
X4780355Y548356D01*
X4780820Y547106D01*
X4781750Y545856D01*
X4782835Y545023D01*
X4783920Y544606D01*
X4785005D01*
X4786090Y545023D01*
X4787020Y545647D01*
X4787795Y546481D01*
G01X4799420Y544606D02*
X4793220D01*
Y557106D01*
X4799420D01*
G01X4796940Y551064D02*
X4793220D01*
G01X4821120Y557106D02*
Y544606D01*
G01X4817555Y557106D02*
X4824685D01*
G01X4833520Y544606D02*
X4832280Y544814D01*
X4831195Y545647D01*
X4830265Y546898D01*
X4829645Y548356D01*
X4829335Y550023D01*
Y551689D01*
X4829645Y553356D01*
X4830265Y554814D01*
X4831195Y556064D01*
X4832280Y556898D01*
X4833520Y557106D01*
X4834760Y556898D01*
X4835845Y556064D01*
X4836775Y554814D01*
X4837395Y553356D01*
X4837705Y551689D01*
Y550023D01*
X4837395Y548356D01*
X4836775Y546898D01*
X4835845Y545647D01*
X4834760Y544814D01*
X4833520Y544606D01*
G01X4859560Y551273D02*
X4860180Y551898D01*
X4860645Y552939D01*
X4860955Y554398D01*
X4860645Y555648D01*
X4860025Y556481D01*
X4858940Y557106D01*
X4854755D01*
Y544606D01*
X4859870D01*
X4860955Y545439D01*
X4861575Y546689D01*
X4861885Y548148D01*
X4861575Y549606D01*
X4860645Y550856D01*
X4859560Y551273D01*
X4854755D01*
G01X4873820Y544606D02*
X4867620D01*
Y557106D01*
X4873820D01*
G01X4871340Y551064D02*
X4867620D01*
G01X4895210Y544606D02*
X4895520Y547314D01*
X4895985Y549606D01*
X4896605Y551689D01*
X4897380Y553981D01*
X4898620Y557106D01*
X4892420D01*
G01X4918615Y548773D02*
X4922335D01*
G01X4920320Y551481D02*
Y546064D01*
G01X4929930Y544189D02*
X4935510Y557106D01*
G01X4943105Y548773D02*
X4947135D01*
G01X4954110Y546481D02*
X4955040Y545439D01*
X4956125Y544814D01*
X4957520Y544606D01*
X4958915Y545023D01*
X4960000Y545856D01*
X4960775Y547314D01*
X4960930Y548981D01*
X4960620Y550648D01*
X4959845Y551689D01*
X4958760Y552523D01*
X4957675Y552731D01*
X4956590Y552523D01*
X4955195Y551689D01*
X4955660Y557106D01*
X4959845D01*
G01X4978290Y544606D02*
Y557106D01*
X4982320Y546689D01*
X4986350Y557106D01*
Y544606D01*
G01X4992860Y557106D02*
X4996580D01*
G01X4994720D02*
Y544606D01*
G01X4992860D02*
X4996580D01*
G01X5004020Y557106D02*
Y544606D01*
X5010220D01*
G01X5016265Y546272D02*
X5017505Y545231D01*
X5018900Y544606D01*
X5020140D01*
X5021380Y545231D01*
X5022310Y546272D01*
X5022775Y547731D01*
X5022465Y549189D01*
X5021690Y550439D01*
X5020295Y551273D01*
X5018435Y551689D01*
X5017350Y552523D01*
X5016885Y553981D01*
X5017195Y555439D01*
X5017970Y556481D01*
X5019055Y557106D01*
X5020140D01*
X5021225Y556689D01*
X5022155Y555648D01*
G01X4261105Y567523D02*
X4265135D01*
G01X4283890Y563356D02*
Y575856D01*
X4287920Y565439D01*
X4291950Y575856D01*
Y563356D01*
G01X4297375D02*
Y575856D01*
X4303265D01*
G01X4301095Y569814D02*
X4297375D01*
G01X4313650Y569606D02*
X4316750D01*
Y565856D01*
X4315820Y564606D01*
X4314735Y563773D01*
X4313185Y563356D01*
X4311635Y563773D01*
X4310550Y564606D01*
X4309620Y565856D01*
X4309000Y567314D01*
X4308690Y568981D01*
Y570439D01*
X4309000Y571689D01*
X4309620Y573148D01*
X4310550Y574398D01*
X4311480Y575231D01*
X4312720Y575856D01*
X4313805D01*
X4315045Y575439D01*
X4315975Y574606D01*
G01X4320470Y559189D02*
X4329770D01*
G01X4334265Y565022D02*
X4335505Y563981D01*
X4336900Y563356D01*
X4338140D01*
X4339380Y563981D01*
X4340310Y565022D01*
X4340775Y566481D01*
X4340465Y567939D01*
X4339690Y569189D01*
X4338295Y570023D01*
X4336435Y570439D01*
X4335350Y571273D01*
X4334885Y572731D01*
X4335195Y574189D01*
X4335970Y575231D01*
X4337055Y575856D01*
X4338140D01*
X4339225Y575439D01*
X4340155Y574398D01*
G01X4349920Y575856D02*
Y563356D01*
G01X4346355Y575856D02*
X4353485D01*
G01X4358910D02*
Y566898D01*
X4359530Y565022D01*
X4360770Y563773D01*
X4362320Y563356D01*
X4363870Y563773D01*
X4365110Y565022D01*
X4365730Y566898D01*
Y575856D01*
G01X4375960Y570023D02*
X4376580Y570648D01*
X4377045Y571689D01*
X4377355Y573148D01*
X4377045Y574398D01*
X4376425Y575231D01*
X4375340Y575856D01*
X4371155D01*
Y563356D01*
X4376270D01*
X4377355Y564189D01*
X4377975Y565439D01*
X4378285Y566898D01*
X4377975Y568356D01*
X4377045Y569606D01*
X4375960Y570023D01*
X4371155D01*
G01X4399520Y562939D02*
X4399210Y563148D01*
Y563564D01*
X4399520Y563773D01*
X4399830Y563564D01*
Y563148D01*
X4399520Y562939D01*
G01Y568564D02*
X4399210Y568773D01*
Y569189D01*
X4399520Y569398D01*
X4399830Y569189D01*
Y568773D01*
X4399520Y568564D01*
G01X4420290Y563356D02*
Y575856D01*
X4424320Y565439D01*
X4428350Y575856D01*
Y563356D01*
G01X4432845D02*
X4436720Y575856D01*
X4440595Y563356D01*
G01X4439200Y567731D02*
X4434240D01*
G01X4445555Y563356D02*
Y575856D01*
X4452685Y563356D01*
Y575856D01*
G01X4458110D02*
Y566898D01*
X4458730Y565022D01*
X4459970Y563773D01*
X4461520Y563356D01*
X4463070Y563773D01*
X4464310Y565022D01*
X4464930Y566898D01*
Y575856D01*
G01X4470975Y563356D02*
Y575856D01*
X4476865D01*
G01X4474695Y569814D02*
X4470975D01*
G01X4482445Y563356D02*
X4486320Y575856D01*
X4490195Y563356D01*
G01X4488800Y567731D02*
X4483840D01*
G01X4502130Y574814D02*
X4501200Y575439D01*
X4500115Y575856D01*
X4498875D01*
X4497480Y575231D01*
X4496395Y574189D01*
X4495620Y572939D01*
X4495000Y570856D01*
X4494845Y568981D01*
X4495155Y567106D01*
X4495620Y565856D01*
X4496550Y564606D01*
X4497635Y563773D01*
X4498720Y563356D01*
X4499805D01*
X4500890Y563773D01*
X4501820Y564397D01*
X4502595Y565231D01*
G01X4511120Y575856D02*
Y563356D01*
G01X4507555Y575856D02*
X4514685D01*
G01X4520110D02*
Y566898D01*
X4520730Y565022D01*
X4521970Y563773D01*
X4523520Y563356D01*
X4525070Y563773D01*
X4526310Y565022D01*
X4526930Y566898D01*
Y575856D01*
G01X4532820Y563356D02*
Y575856D01*
X4536695D01*
X4537935Y575231D01*
X4538710Y574398D01*
X4539020Y572731D01*
X4538710Y571064D01*
X4537780Y570023D01*
X4536695Y569398D01*
X4532820D01*
G01X4536695D02*
X4539020Y563356D01*
G01X4546460Y575856D02*
X4550180D01*
G01X4548320D02*
Y563356D01*
G01X4546460D02*
X4550180D01*
G01X4557155D02*
Y575856D01*
X4564285Y563356D01*
Y575856D01*
G01X4574050Y569606D02*
X4577150D01*
Y565856D01*
X4576220Y564606D01*
X4575135Y563773D01*
X4573585Y563356D01*
X4572035Y563773D01*
X4570950Y564606D01*
X4570020Y565856D01*
X4569400Y567314D01*
X4569090Y568981D01*
Y570439D01*
X4569400Y571689D01*
X4570020Y573148D01*
X4570950Y574398D01*
X4571880Y575231D01*
X4573120Y575856D01*
X4574205D01*
X4575445Y575439D01*
X4576375Y574606D01*
G01X4594665Y565022D02*
X4595905Y563981D01*
X4597300Y563356D01*
X4598540D01*
X4599780Y563981D01*
X4600710Y565022D01*
X4601175Y566481D01*
X4600865Y567939D01*
X4600090Y569189D01*
X4598695Y570023D01*
X4596835Y570439D01*
X4595750Y571273D01*
X4595285Y572731D01*
X4595595Y574189D01*
X4596370Y575231D01*
X4597455Y575856D01*
X4598540D01*
X4599625Y575439D01*
X4600555Y574398D01*
G01X4610320Y575856D02*
Y563356D01*
G01X4606755Y575856D02*
X4613885D01*
G01X4619310D02*
Y566898D01*
X4619930Y565022D01*
X4621170Y563773D01*
X4622720Y563356D01*
X4624270Y563773D01*
X4625510Y565022D01*
X4626130Y566898D01*
Y575856D01*
G01X4636360Y570023D02*
X4636980Y570648D01*
X4637445Y571689D01*
X4637755Y573148D01*
X4637445Y574398D01*
X4636825Y575231D01*
X4635740Y575856D01*
X4631555D01*
Y563356D01*
X4636670D01*
X4637755Y564189D01*
X4638375Y565439D01*
X4638685Y566898D01*
X4638375Y568356D01*
X4637445Y569606D01*
X4636360Y570023D01*
X4631555D01*
G01X4656820Y575856D02*
Y563356D01*
X4663020D01*
G01X4675420D02*
X4669220D01*
Y575856D01*
X4675420D01*
G01X4672940Y569814D02*
X4669220D01*
G01X4681155Y563356D02*
Y575856D01*
X4688285Y563356D01*
Y575856D01*
G01X4698050Y569606D02*
X4701150D01*
Y565856D01*
X4700220Y564606D01*
X4699135Y563773D01*
X4697585Y563356D01*
X4696035Y563773D01*
X4694950Y564606D01*
X4694020Y565856D01*
X4693400Y567314D01*
X4693090Y568981D01*
Y570439D01*
X4693400Y571689D01*
X4694020Y573148D01*
X4694950Y574398D01*
X4695880Y575231D01*
X4697120Y575856D01*
X4698205D01*
X4699445Y575439D01*
X4700375Y574606D01*
G01X4709520Y575856D02*
Y563356D01*
G01X4705955Y575856D02*
X4713085D01*
G01X4718665Y563356D02*
Y575856D01*
G01X4725175D02*
Y563356D01*
G01Y569606D02*
X4718665D01*
G01X4421065Y583772D02*
X4422305Y582731D01*
X4423700Y582106D01*
X4424940D01*
X4426180Y582731D01*
X4427110Y583772D01*
X4427575Y585231D01*
X4427265Y586689D01*
X4426490Y587939D01*
X4425095Y588773D01*
X4423235Y589189D01*
X4422150Y590023D01*
X4421685Y591481D01*
X4421995Y592939D01*
X4422770Y593981D01*
X4423855Y594606D01*
X4424940D01*
X4426025Y594189D01*
X4426955Y593148D01*
G01X4433310Y594606D02*
Y585648D01*
X4433930Y583772D01*
X4435170Y582523D01*
X4436720Y582106D01*
X4438270Y582523D01*
X4439510Y583772D01*
X4440130Y585648D01*
Y594606D01*
G01X4446020Y582106D02*
Y594606D01*
X4449895D01*
X4451135Y593981D01*
X4451910Y593148D01*
X4452220Y591481D01*
X4451910Y589814D01*
X4450980Y588773D01*
X4449895Y588148D01*
X4446020D01*
G01X4449895D02*
X4452220Y582106D01*
G01X4458575D02*
Y594606D01*
X4464465D01*
G01X4462295Y588564D02*
X4458575D01*
G01X4470045Y582106D02*
X4473920Y594606D01*
X4477795Y582106D01*
G01X4476400Y586481D02*
X4471440D01*
G01X4489730Y593564D02*
X4488800Y594189D01*
X4487715Y594606D01*
X4486475D01*
X4485080Y593981D01*
X4483995Y592939D01*
X4483220Y591689D01*
X4482600Y589606D01*
X4482445Y587731D01*
X4482755Y585856D01*
X4483220Y584606D01*
X4484150Y583356D01*
X4485235Y582523D01*
X4486320Y582106D01*
X4487405D01*
X4488490Y582523D01*
X4489420Y583147D01*
X4490195Y583981D01*
G01X4501820Y582106D02*
X4495620D01*
Y594606D01*
X4501820D01*
G01X4499340Y588564D02*
X4495620D01*
G01X4523520Y582106D02*
X4522280Y582314D01*
X4521195Y583147D01*
X4520265Y584398D01*
X4519645Y585856D01*
X4519335Y587523D01*
Y589189D01*
X4519645Y590856D01*
X4520265Y592314D01*
X4521195Y593564D01*
X4522280Y594398D01*
X4523520Y594606D01*
X4524760Y594398D01*
X4525845Y593564D01*
X4526775Y592314D01*
X4527395Y590856D01*
X4527705Y589189D01*
Y587523D01*
X4527395Y585856D01*
X4526775Y584398D01*
X4525845Y583147D01*
X4524760Y582314D01*
X4523520Y582106D01*
G01X4532975D02*
Y594606D01*
X4538865D01*
G01X4536695Y588564D02*
X4532975D01*
G01X4556690Y582106D02*
Y594606D01*
X4560720Y584189D01*
X4564750Y594606D01*
Y582106D01*
G01X4569710Y594606D02*
Y585648D01*
X4570330Y583772D01*
X4571570Y582523D01*
X4573120Y582106D01*
X4574670Y582523D01*
X4575910Y583772D01*
X4576530Y585648D01*
Y594606D01*
G01X4582265Y583772D02*
X4583505Y582731D01*
X4584900Y582106D01*
X4586140D01*
X4587380Y582731D01*
X4588310Y583772D01*
X4588775Y585231D01*
X4588465Y586689D01*
X4587690Y587939D01*
X4586295Y588773D01*
X4584435Y589189D01*
X4583350Y590023D01*
X4582885Y591481D01*
X4583195Y592939D01*
X4583970Y593981D01*
X4585055Y594606D01*
X4586140D01*
X4587225Y594189D01*
X4588155Y593148D01*
G01X4597920Y594606D02*
Y582106D01*
G01X4594355Y594606D02*
X4601485D01*
G01X4608305Y586273D02*
X4612335D01*
G01X4619155Y582106D02*
Y594606D01*
X4626285Y582106D01*
Y594606D01*
G01X4635120Y582106D02*
X4633880Y582314D01*
X4632795Y583147D01*
X4631865Y584398D01*
X4631245Y585856D01*
X4630935Y587523D01*
Y589189D01*
X4631245Y590856D01*
X4631865Y592314D01*
X4632795Y593564D01*
X4633880Y594398D01*
X4635120Y594606D01*
X4636360Y594398D01*
X4637445Y593564D01*
X4638375Y592314D01*
X4638995Y590856D01*
X4639305Y589189D01*
Y587523D01*
X4638995Y585856D01*
X4638375Y584398D01*
X4637445Y583147D01*
X4636360Y582314D01*
X4635120Y582106D01*
G01X4647520Y594606D02*
Y582106D01*
G01X4643955Y594606D02*
X4651085D01*
G01X4657905Y586273D02*
X4661935D01*
G01X4675730Y593564D02*
X4674800Y594189D01*
X4673715Y594606D01*
X4672475D01*
X4671080Y593981D01*
X4669995Y592939D01*
X4669220Y591689D01*
X4668600Y589606D01*
X4668445Y587731D01*
X4668755Y585856D01*
X4669220Y584606D01*
X4670150Y583356D01*
X4671235Y582523D01*
X4672320Y582106D01*
X4673405D01*
X4674490Y582523D01*
X4675420Y583147D01*
X4676195Y583981D01*
G01X4681310Y594606D02*
Y585648D01*
X4681930Y583772D01*
X4683170Y582523D01*
X4684720Y582106D01*
X4686270Y582523D01*
X4687510Y583772D01*
X4688130Y585648D01*
Y594606D01*
G01X4697120D02*
Y582106D01*
G01X4693555Y594606D02*
X4700685D01*
G01X4707505Y586273D02*
X4711535D01*
G01X4718820Y594606D02*
Y582106D01*
X4725020D01*
G01X4730445D02*
X4734320Y594606D01*
X4738195Y582106D01*
G01X4736800Y586481D02*
X4731840D01*
G01X4746720Y582106D02*
Y587731D01*
X4743620Y594606D01*
G01X4749820D02*
X4746720Y587731D01*
G01X4762220Y582106D02*
X4756020D01*
Y594606D01*
X4762220D01*
G01X4759740Y588564D02*
X4756020D01*
G01X4768420Y582106D02*
Y594606D01*
X4772295D01*
X4773535Y593981D01*
X4774310Y593148D01*
X4774620Y591481D01*
X4774310Y589814D01*
X4773380Y588773D01*
X4772295Y588148D01*
X4768420D01*
G01X4772295D02*
X4774620Y582106D01*
G01X4261105Y605023D02*
X4265135D01*
G01X4283890Y600856D02*
Y613356D01*
X4287920Y602939D01*
X4291950Y613356D01*
Y600856D01*
G01X4296445D02*
X4300320Y613356D01*
X4304195Y600856D01*
G01X4302800Y605231D02*
X4297840D01*
G01X4309465Y600856D02*
X4315975Y613356D01*
G01X4309465D02*
X4315975Y600856D01*
G01X4320470Y596689D02*
X4329770D01*
G01X4334110Y600856D02*
Y613356D01*
X4337210D01*
X4338450Y612731D01*
X4339380Y611898D01*
X4340155Y610648D01*
X4340775Y609189D01*
X4340930Y607106D01*
X4340775Y605023D01*
X4340155Y603564D01*
X4339380Y602314D01*
X4338450Y601481D01*
X4337210Y600856D01*
X4334110D01*
G01X4353020D02*
X4346820D01*
Y613356D01*
X4353020D01*
G01X4350540Y607314D02*
X4346820D01*
G01X4359220Y600856D02*
Y613356D01*
X4362940D01*
X4364180Y612731D01*
X4365110Y611273D01*
X4365420Y609606D01*
X4365110Y607939D01*
X4364335Y606689D01*
X4362940Y606064D01*
X4359220D01*
G01X4374720Y613356D02*
Y600856D01*
G01X4371155Y613356D02*
X4378285D01*
G01X4383865Y600856D02*
Y613356D01*
G01X4390375D02*
Y600856D01*
G01Y607106D02*
X4383865D01*
G01X4399520Y600439D02*
X4399210Y600648D01*
Y601064D01*
X4399520Y601273D01*
X4399830Y601064D01*
Y600648D01*
X4399520Y600439D01*
G01Y606064D02*
X4399210Y606273D01*
Y606689D01*
X4399520Y606898D01*
X4399830Y606689D01*
Y606273D01*
X4399520Y606064D01*
G01X4420910Y600856D02*
Y613356D01*
X4424010D01*
X4425250Y612731D01*
X4426180Y611898D01*
X4426955Y610648D01*
X4427575Y609189D01*
X4427730Y607106D01*
X4427575Y605023D01*
X4426955Y603564D01*
X4426180Y602314D01*
X4425250Y601481D01*
X4424010Y600856D01*
X4420910D01*
G01X4439820D02*
X4433620D01*
Y613356D01*
X4439820D01*
G01X4437340Y607314D02*
X4433620D01*
G01X4446020Y600856D02*
Y613356D01*
X4449740D01*
X4450980Y612731D01*
X4451910Y611273D01*
X4452220Y609606D01*
X4451910Y607939D01*
X4451135Y606689D01*
X4449740Y606064D01*
X4446020D01*
G01X4461520Y613356D02*
Y600856D01*
G01X4457955Y613356D02*
X4465085D01*
G01X4470665Y600856D02*
Y613356D01*
G01X4477175D02*
Y600856D01*
G01Y607106D02*
X4470665D01*
G01X4495775Y600856D02*
Y613356D01*
X4501665D01*
G01X4499495Y607314D02*
X4495775D01*
G01X4508020Y600856D02*
Y613356D01*
X4511895D01*
X4513135Y612731D01*
X4513910Y611898D01*
X4514220Y610231D01*
X4513910Y608564D01*
X4512980Y607523D01*
X4511895Y606898D01*
X4508020D01*
G01X4511895D02*
X4514220Y600856D01*
G01X4523520D02*
X4522280Y601064D01*
X4521195Y601897D01*
X4520265Y603148D01*
X4519645Y604606D01*
X4519335Y606273D01*
Y607939D01*
X4519645Y609606D01*
X4520265Y611064D01*
X4521195Y612314D01*
X4522280Y613148D01*
X4523520Y613356D01*
X4524760Y613148D01*
X4525845Y612314D01*
X4526775Y611064D01*
X4527395Y609606D01*
X4527705Y607939D01*
Y606273D01*
X4527395Y604606D01*
X4526775Y603148D01*
X4525845Y601897D01*
X4524760Y601064D01*
X4523520Y600856D01*
G01X4531890D02*
Y613356D01*
X4535920Y602939D01*
X4539950Y613356D01*
Y600856D01*
G01X4557465Y602522D02*
X4558705Y601481D01*
X4560100Y600856D01*
X4561340D01*
X4562580Y601481D01*
X4563510Y602522D01*
X4563975Y603981D01*
X4563665Y605439D01*
X4562890Y606689D01*
X4561495Y607523D01*
X4559635Y607939D01*
X4558550Y608773D01*
X4558085Y610231D01*
X4558395Y611689D01*
X4559170Y612731D01*
X4560255Y613356D01*
X4561340D01*
X4562425Y612939D01*
X4563355Y611898D01*
G01X4573120Y613356D02*
Y600856D01*
G01X4569555Y613356D02*
X4576685D01*
G01X4581645Y600856D02*
X4585520Y613356D01*
X4589395Y600856D01*
G01X4588000Y605231D02*
X4583040D01*
G01X4594820Y600856D02*
Y613356D01*
X4598695D01*
X4599935Y612731D01*
X4600710Y611898D01*
X4601020Y610231D01*
X4600710Y608564D01*
X4599780Y607523D01*
X4598695Y606898D01*
X4594820D01*
G01X4598695D02*
X4601020Y600856D01*
G01X4610320Y613356D02*
Y600856D01*
G01X4606755Y613356D02*
X4613885D01*
G01X4632020D02*
Y600856D01*
X4638220D01*
G01X4643645D02*
X4647520Y613356D01*
X4651395Y600856D01*
G01X4650000Y605231D02*
X4645040D01*
G01X4659920Y600856D02*
Y606481D01*
X4656820Y613356D01*
G01X4663020D02*
X4659920Y606481D01*
G01X4675420Y600856D02*
X4669220D01*
Y613356D01*
X4675420D01*
G01X4672940Y607314D02*
X4669220D01*
G01X4681620Y600856D02*
Y613356D01*
X4685495D01*
X4686735Y612731D01*
X4687510Y611898D01*
X4687820Y610231D01*
X4687510Y608564D01*
X4686580Y607523D01*
X4685495Y606898D01*
X4681620D01*
G01X4685495D02*
X4687820Y600856D01*
G01X4709520Y613356D02*
Y600856D01*
G01X4705955Y613356D02*
X4713085D01*
G01X4721920Y600856D02*
X4720680Y601064D01*
X4719595Y601897D01*
X4718665Y603148D01*
X4718045Y604606D01*
X4717735Y606273D01*
Y607939D01*
X4718045Y609606D01*
X4718665Y611064D01*
X4719595Y612314D01*
X4720680Y613148D01*
X4721920Y613356D01*
X4723160Y613148D01*
X4724245Y612314D01*
X4725175Y611064D01*
X4725795Y609606D01*
X4726105Y607939D01*
Y606273D01*
X4725795Y604606D01*
X4725175Y603148D01*
X4724245Y601897D01*
X4723160Y601064D01*
X4721920Y600856D01*
G01X4746720Y613356D02*
Y600856D01*
G01X4743155Y613356D02*
X4750285D01*
G01X4755865Y600856D02*
Y613356D01*
G01X4762375D02*
Y600856D01*
G01Y607106D02*
X4755865D01*
G01X4774620Y600856D02*
X4768420D01*
Y613356D01*
X4774620D01*
G01X4772140Y607314D02*
X4768420D01*
G01X4261105Y623773D02*
X4265135D01*
G01X4283890Y619606D02*
Y632106D01*
X4287920Y621689D01*
X4291950Y632106D01*
Y619606D01*
G01X4296755D02*
Y632106D01*
X4303885Y619606D01*
Y632106D01*
G01X4316130Y631064D02*
X4315200Y631689D01*
X4314115Y632106D01*
X4312875D01*
X4311480Y631481D01*
X4310395Y630439D01*
X4309620Y629189D01*
X4309000Y627106D01*
X4308845Y625231D01*
X4309155Y623356D01*
X4309620Y622106D01*
X4310550Y620856D01*
X4311635Y620023D01*
X4312720Y619606D01*
X4313805D01*
X4314890Y620023D01*
X4315820Y620647D01*
X4316595Y621481D01*
G01X4320470Y615439D02*
X4329770D01*
G01X4334420Y632106D02*
Y619606D01*
X4340620D01*
G01X4346045D02*
X4349920Y632106D01*
X4353795Y619606D01*
G01X4352400Y623981D02*
X4347440D01*
G01X4362320Y619606D02*
Y625231D01*
X4359220Y632106D01*
G01X4365420D02*
X4362320Y625231D01*
G01X4377820Y619606D02*
X4371620D01*
Y632106D01*
X4377820D01*
G01X4375340Y626064D02*
X4371620D01*
G01X4384020Y619606D02*
Y632106D01*
X4387895D01*
X4389135Y631481D01*
X4389910Y630648D01*
X4390220Y628981D01*
X4389910Y627314D01*
X4388980Y626273D01*
X4387895Y625648D01*
X4384020D01*
G01X4387895D02*
X4390220Y619606D01*
G01X4399520Y619189D02*
X4399210Y619398D01*
Y619814D01*
X4399520Y620023D01*
X4399830Y619814D01*
Y619398D01*
X4399520Y619189D01*
G01Y624814D02*
X4399210Y625023D01*
Y625439D01*
X4399520Y625648D01*
X4399830Y625439D01*
Y625023D01*
X4399520Y624814D01*
G01X4420290Y619606D02*
Y632106D01*
X4424320Y621689D01*
X4428350Y632106D01*
Y619606D01*
G01X4433310Y632106D02*
Y623148D01*
X4433930Y621272D01*
X4435170Y620023D01*
X4436720Y619606D01*
X4438270Y620023D01*
X4439510Y621272D01*
X4440130Y623148D01*
Y632106D01*
G01X4445865Y621272D02*
X4447105Y620231D01*
X4448500Y619606D01*
X4449740D01*
X4450980Y620231D01*
X4451910Y621272D01*
X4452375Y622731D01*
X4452065Y624189D01*
X4451290Y625439D01*
X4449895Y626273D01*
X4448035Y626689D01*
X4446950Y627523D01*
X4446485Y628981D01*
X4446795Y630439D01*
X4447570Y631481D01*
X4448655Y632106D01*
X4449740D01*
X4450825Y631689D01*
X4451755Y630648D01*
G01X4461520Y632106D02*
Y619606D01*
G01X4457955Y632106D02*
X4465085D01*
G01X4471905Y623773D02*
X4475935D01*
G01X4482755Y619606D02*
Y632106D01*
X4489885Y619606D01*
Y632106D01*
G01X4498720Y619606D02*
X4497480Y619814D01*
X4496395Y620647D01*
X4495465Y621898D01*
X4494845Y623356D01*
X4494535Y625023D01*
Y626689D01*
X4494845Y628356D01*
X4495465Y629814D01*
X4496395Y631064D01*
X4497480Y631898D01*
X4498720Y632106D01*
X4499960Y631898D01*
X4501045Y631064D01*
X4501975Y629814D01*
X4502595Y628356D01*
X4502905Y626689D01*
Y625023D01*
X4502595Y623356D01*
X4501975Y621898D01*
X4501045Y620647D01*
X4499960Y619814D01*
X4498720Y619606D01*
G01X4511120Y632106D02*
Y619606D01*
G01X4507555Y632106D02*
X4514685D01*
G01X4521505Y623773D02*
X4525535D01*
G01X4539330Y631064D02*
X4538400Y631689D01*
X4537315Y632106D01*
X4536075D01*
X4534680Y631481D01*
X4533595Y630439D01*
X4532820Y629189D01*
X4532200Y627106D01*
X4532045Y625231D01*
X4532355Y623356D01*
X4532820Y622106D01*
X4533750Y620856D01*
X4534835Y620023D01*
X4535920Y619606D01*
X4537005D01*
X4538090Y620023D01*
X4539020Y620647D01*
X4539795Y621481D01*
G01X4544910Y632106D02*
Y623148D01*
X4545530Y621272D01*
X4546770Y620023D01*
X4548320Y619606D01*
X4549870Y620023D01*
X4551110Y621272D01*
X4551730Y623148D01*
Y632106D01*
G01X4560720D02*
Y619606D01*
G01X4557155Y632106D02*
X4564285D01*
G01X4571105Y623773D02*
X4575135D01*
G01X4582420Y632106D02*
Y619606D01*
X4588620D01*
G01X4594045D02*
X4597920Y632106D01*
X4601795Y619606D01*
G01X4600400Y623981D02*
X4595440D01*
G01X4610320Y619606D02*
Y625231D01*
X4607220Y632106D01*
G01X4613420D02*
X4610320Y625231D01*
G01X4625820Y619606D02*
X4619620D01*
Y632106D01*
X4625820D01*
G01X4623340Y626064D02*
X4619620D01*
G01X4632020Y619606D02*
Y632106D01*
X4635895D01*
X4637135Y631481D01*
X4637910Y630648D01*
X4638220Y628981D01*
X4637910Y627314D01*
X4636980Y626273D01*
X4635895Y625648D01*
X4632020D01*
G01X4635895D02*
X4638220Y619606D01*
G01X4259555Y638356D02*
Y650856D01*
X4266685Y638356D01*
Y650856D01*
G01X4275520Y638356D02*
X4274280Y638564D01*
X4273195Y639397D01*
X4272265Y640648D01*
X4271645Y642106D01*
X4271335Y643773D01*
Y645439D01*
X4271645Y647106D01*
X4272265Y648564D01*
X4273195Y649814D01*
X4274280Y650648D01*
X4275520Y650856D01*
X4276760Y650648D01*
X4277845Y649814D01*
X4278775Y648564D01*
X4279395Y647106D01*
X4279705Y645439D01*
Y643773D01*
X4279395Y642106D01*
X4278775Y640648D01*
X4277845Y639397D01*
X4276760Y638564D01*
X4275520Y638356D01*
G01X4287920Y650856D02*
Y638356D01*
G01X4284355Y650856D02*
X4291485D01*
G01X4303420Y638356D02*
X4297220D01*
Y650856D01*
X4303420D01*
G01X4300940Y644814D02*
X4297220D01*
G01X4309465Y640022D02*
X4310705Y638981D01*
X4312100Y638356D01*
X4313340D01*
X4314580Y638981D01*
X4315510Y640022D01*
X4315975Y641481D01*
X4315665Y642939D01*
X4314890Y644189D01*
X4313495Y645023D01*
X4311635Y645439D01*
X4310550Y646273D01*
X4310085Y647731D01*
X4310395Y649189D01*
X4311170Y650231D01*
X4312255Y650856D01*
X4313340D01*
X4314425Y650439D01*
X4315355Y649398D01*
G01X4325120Y637939D02*
X4324810Y638148D01*
Y638564D01*
X4325120Y638773D01*
X4325430Y638564D01*
Y638148D01*
X4325120Y637939D01*
G01Y643564D02*
X4324810Y643773D01*
Y644189D01*
X4325120Y644398D01*
X4325430Y644189D01*
Y643773D01*
X4325120Y643564D01*
G01X4269475Y707106D02*
Y719606D01*
X4275365D01*
G01X4273195Y713564D02*
X4269475D01*
G01X4282960Y719606D02*
X4286680D01*
G01X4284820D02*
Y707106D01*
G01X4282960D02*
X4286680D01*
G01X4298150Y713356D02*
X4301250D01*
Y709606D01*
X4300320Y708356D01*
X4299235Y707523D01*
X4297685Y707106D01*
X4296135Y707523D01*
X4295050Y708356D01*
X4294120Y709606D01*
X4293500Y711064D01*
X4293190Y712731D01*
Y714189D01*
X4293500Y715439D01*
X4294120Y716898D01*
X4295050Y718148D01*
X4295980Y718981D01*
X4297220Y719606D01*
X4298305D01*
X4299545Y719189D01*
X4300475Y718356D01*
G01X4306210Y719606D02*
Y710648D01*
X4306830Y708772D01*
X4308070Y707523D01*
X4309620Y707106D01*
X4311170Y707523D01*
X4312410Y708772D01*
X4313030Y710648D01*
Y719606D01*
G01X4318920Y707106D02*
Y719606D01*
X4322795D01*
X4324035Y718981D01*
X4324810Y718148D01*
X4325120Y716481D01*
X4324810Y714814D01*
X4323880Y713773D01*
X4322795Y713148D01*
X4318920D01*
G01X4322795D02*
X4325120Y707106D01*
G01X4337520D02*
X4331320D01*
Y719606D01*
X4337520D01*
G01X4335040Y713564D02*
X4331320D01*
G01X4424060Y855273D02*
X4424680Y855898D01*
X4425145Y856939D01*
X4425455Y858398D01*
X4425145Y859648D01*
X4424525Y860481D01*
X4423440Y861106D01*
X4419255D01*
Y848606D01*
X4424370D01*
X4425455Y849439D01*
X4426075Y850689D01*
X4426385Y852148D01*
X4426075Y853606D01*
X4425145Y854856D01*
X4424060Y855273D01*
X4419255D01*
G01X4431345Y848606D02*
X4435220Y861106D01*
X4439095Y848606D01*
G01X4437700Y852981D02*
X4432740D01*
G01X4451030Y860064D02*
X4450100Y860689D01*
X4449015Y861106D01*
X4447775D01*
X4446380Y860481D01*
X4445295Y859439D01*
X4444520Y858189D01*
X4443900Y856106D01*
X4443745Y854231D01*
X4444055Y852356D01*
X4444520Y851106D01*
X4445450Y849856D01*
X4446535Y849023D01*
X4447620Y848606D01*
X4448705D01*
X4449790Y849023D01*
X4450720Y849647D01*
X4451495Y850481D01*
G01X4456610Y848606D02*
Y861106D01*
G01X4462500D02*
X4456610Y853397D01*
G01X4463430Y848606D02*
X4459245Y856939D01*
G01X4469010Y848606D02*
Y861106D01*
X4472110D01*
X4473350Y860481D01*
X4474280Y859648D01*
X4475055Y858398D01*
X4475675Y856939D01*
X4475830Y854856D01*
X4475675Y852773D01*
X4475055Y851314D01*
X4474280Y850064D01*
X4473350Y849231D01*
X4472110Y848606D01*
X4469010D01*
G01X4481720D02*
Y861106D01*
X4485595D01*
X4486835Y860481D01*
X4487610Y859648D01*
X4487920Y857981D01*
X4487610Y856314D01*
X4486680Y855273D01*
X4485595Y854648D01*
X4481720D01*
G01X4485595D02*
X4487920Y848606D01*
G01X4495360Y861106D02*
X4499080D01*
G01X4497220D02*
Y848606D01*
G01X4495360D02*
X4499080D01*
G01X4506520Y861106D02*
Y848606D01*
X4512720D01*
G01X4518920Y861106D02*
Y848606D01*
X4525120D01*
G01X4543565Y850272D02*
X4544805Y849231D01*
X4546200Y848606D01*
X4547440D01*
X4548680Y849231D01*
X4549610Y850272D01*
X4550075Y851731D01*
X4549765Y853189D01*
X4548990Y854439D01*
X4547595Y855273D01*
X4545735Y855689D01*
X4544650Y856523D01*
X4544185Y857981D01*
X4544495Y859439D01*
X4545270Y860481D01*
X4546355Y861106D01*
X4547440D01*
X4548525Y860689D01*
X4549455Y859648D01*
G01X4559220Y861106D02*
Y848606D01*
G01X4555655Y861106D02*
X4562785D01*
G01X4568210D02*
Y852148D01*
X4568830Y850272D01*
X4570070Y849023D01*
X4571620Y848606D01*
X4573170Y849023D01*
X4574410Y850272D01*
X4575030Y852148D01*
Y861106D01*
G01X4585260Y855273D02*
X4585880Y855898D01*
X4586345Y856939D01*
X4586655Y858398D01*
X4586345Y859648D01*
X4585725Y860481D01*
X4584640Y861106D01*
X4580455D01*
Y848606D01*
X4585570D01*
X4586655Y849439D01*
X4587275Y850689D01*
X4587585Y852148D01*
X4587275Y853606D01*
X4586345Y854856D01*
X4585260Y855273D01*
X4580455D01*
G01X4605720Y861106D02*
Y848606D01*
X4611920D01*
G01X4624320D02*
X4618120D01*
Y861106D01*
X4624320D01*
G01X4621840Y855064D02*
X4618120D01*
G01X4630055Y848606D02*
Y861106D01*
X4637185Y848606D01*
Y861106D01*
G01X4646950Y854856D02*
X4650050D01*
Y851106D01*
X4649120Y849856D01*
X4648035Y849023D01*
X4646485Y848606D01*
X4644935Y849023D01*
X4643850Y849856D01*
X4642920Y851106D01*
X4642300Y852564D01*
X4641990Y854231D01*
Y855689D01*
X4642300Y856939D01*
X4642920Y858398D01*
X4643850Y859648D01*
X4644780Y860481D01*
X4646020Y861106D01*
X4647105D01*
X4648345Y860689D01*
X4649275Y859856D01*
G01X4658420Y861106D02*
Y848606D01*
G01X4654855Y861106D02*
X4661985D01*
G01X4667565Y848606D02*
Y861106D01*
G01X4674075D02*
Y848606D01*
G01Y854856D02*
X4667565D01*
G01X4695620Y861106D02*
Y848606D01*
G01X4692055Y861106D02*
X4699185D01*
G01X4708020Y848606D02*
X4706780Y848814D01*
X4705695Y849647D01*
X4704765Y850898D01*
X4704145Y852356D01*
X4703835Y854023D01*
Y855689D01*
X4704145Y857356D01*
X4704765Y858814D01*
X4705695Y860064D01*
X4706780Y860898D01*
X4708020Y861106D01*
X4709260Y860898D01*
X4710345Y860064D01*
X4711275Y858814D01*
X4711895Y857356D01*
X4712205Y855689D01*
Y854023D01*
X4711895Y852356D01*
X4711275Y850898D01*
X4710345Y849647D01*
X4709260Y848814D01*
X4708020Y848606D01*
G01X4717320Y861106D02*
Y848606D01*
X4723520D01*
G01X4735920D02*
X4729720D01*
Y861106D01*
X4735920D01*
G01X4733440Y855064D02*
X4729720D01*
G01X4742120Y848606D02*
Y861106D01*
X4745995D01*
X4747235Y860481D01*
X4748010Y859648D01*
X4748320Y857981D01*
X4748010Y856314D01*
X4747080Y855273D01*
X4745995Y854648D01*
X4742120D01*
G01X4745995D02*
X4748320Y848606D01*
G01X4753745D02*
X4757620Y861106D01*
X4761495Y848606D01*
G01X4760100Y852981D02*
X4755140D01*
G01X4766455Y848606D02*
Y861106D01*
X4773585Y848606D01*
Y861106D01*
G01X4785830Y860064D02*
X4784900Y860689D01*
X4783815Y861106D01*
X4782575D01*
X4781180Y860481D01*
X4780095Y859439D01*
X4779320Y858189D01*
X4778700Y856106D01*
X4778545Y854231D01*
X4778855Y852356D01*
X4779320Y851106D01*
X4780250Y849856D01*
X4781335Y849023D01*
X4782420Y848606D01*
X4783505D01*
X4784590Y849023D01*
X4785520Y849647D01*
X4786295Y850481D01*
G01X4797920Y848606D02*
X4791720D01*
Y861106D01*
X4797920D01*
G01X4795440Y855064D02*
X4791720D01*
G01X4819620Y861106D02*
Y848606D01*
G01X4816055Y861106D02*
X4823185D01*
G01X4832020Y848606D02*
X4830780Y848814D01*
X4829695Y849647D01*
X4828765Y850898D01*
X4828145Y852356D01*
X4827835Y854023D01*
Y855689D01*
X4828145Y857356D01*
X4828765Y858814D01*
X4829695Y860064D01*
X4830780Y860898D01*
X4832020Y861106D01*
X4833260Y860898D01*
X4834345Y860064D01*
X4835275Y858814D01*
X4835895Y857356D01*
X4836205Y855689D01*
Y854023D01*
X4835895Y852356D01*
X4835275Y850898D01*
X4834345Y849647D01*
X4833260Y848814D01*
X4832020Y848606D01*
G01X4858060Y855273D02*
X4858680Y855898D01*
X4859145Y856939D01*
X4859455Y858398D01*
X4859145Y859648D01*
X4858525Y860481D01*
X4857440Y861106D01*
X4853255D01*
Y848606D01*
X4858370D01*
X4859455Y849439D01*
X4860075Y850689D01*
X4860385Y852148D01*
X4860075Y853606D01*
X4859145Y854856D01*
X4858060Y855273D01*
X4853255D01*
G01X4872320Y848606D02*
X4866120D01*
Y861106D01*
X4872320D01*
G01X4869840Y855064D02*
X4866120D01*
G01X4893710Y848606D02*
X4894020Y851314D01*
X4894485Y853606D01*
X4895105Y855689D01*
X4895880Y857981D01*
X4897120Y861106D01*
X4890920D01*
G01X4917115Y852773D02*
X4920835D01*
G01X4918820Y855481D02*
Y850064D01*
G01X4928430Y848189D02*
X4934010Y861106D01*
G01X4941605Y852773D02*
X4945635D01*
G01X4952610Y850481D02*
X4953540Y849439D01*
X4954625Y848814D01*
X4956020Y848606D01*
X4957415Y849023D01*
X4958500Y849856D01*
X4959275Y851314D01*
X4959430Y852981D01*
X4959120Y854648D01*
X4958345Y855689D01*
X4957260Y856523D01*
X4956175Y856731D01*
X4955090Y856523D01*
X4953695Y855689D01*
X4954160Y861106D01*
X4958345D01*
G01X4976790Y848606D02*
Y861106D01*
X4980820Y850689D01*
X4984850Y861106D01*
Y848606D01*
G01X4991360Y861106D02*
X4995080D01*
G01X4993220D02*
Y848606D01*
G01X4991360D02*
X4995080D01*
G01X5002520Y861106D02*
Y848606D01*
X5008720D01*
G01X5014765Y850272D02*
X5016005Y849231D01*
X5017400Y848606D01*
X5018640D01*
X5019880Y849231D01*
X5020810Y850272D01*
X5021275Y851731D01*
X5020965Y853189D01*
X5020190Y854439D01*
X5018795Y855273D01*
X5016935Y855689D01*
X5015850Y856523D01*
X5015385Y857981D01*
X5015695Y859439D01*
X5016470Y860481D01*
X5017555Y861106D01*
X5018640D01*
X5019725Y860689D01*
X5020655Y859648D01*
G01X4259605Y871523D02*
X4263635D01*
G01X4282390Y867356D02*
Y879856D01*
X4286420Y869439D01*
X4290450Y879856D01*
Y867356D01*
G01X4295875D02*
Y879856D01*
X4301765D01*
G01X4299595Y873814D02*
X4295875D01*
G01X4312150Y873606D02*
X4315250D01*
Y869856D01*
X4314320Y868606D01*
X4313235Y867773D01*
X4311685Y867356D01*
X4310135Y867773D01*
X4309050Y868606D01*
X4308120Y869856D01*
X4307500Y871314D01*
X4307190Y872981D01*
Y874439D01*
X4307500Y875689D01*
X4308120Y877148D01*
X4309050Y878398D01*
X4309980Y879231D01*
X4311220Y879856D01*
X4312305D01*
X4313545Y879439D01*
X4314475Y878606D01*
G01X4318970Y863189D02*
X4328270D01*
G01X4332765Y869022D02*
X4334005Y867981D01*
X4335400Y867356D01*
X4336640D01*
X4337880Y867981D01*
X4338810Y869022D01*
X4339275Y870481D01*
X4338965Y871939D01*
X4338190Y873189D01*
X4336795Y874023D01*
X4334935Y874439D01*
X4333850Y875273D01*
X4333385Y876731D01*
X4333695Y878189D01*
X4334470Y879231D01*
X4335555Y879856D01*
X4336640D01*
X4337725Y879439D01*
X4338655Y878398D01*
G01X4348420Y879856D02*
Y867356D01*
G01X4344855Y879856D02*
X4351985D01*
G01X4357410D02*
Y870898D01*
X4358030Y869022D01*
X4359270Y867773D01*
X4360820Y867356D01*
X4362370Y867773D01*
X4363610Y869022D01*
X4364230Y870898D01*
Y879856D01*
G01X4374460Y874023D02*
X4375080Y874648D01*
X4375545Y875689D01*
X4375855Y877148D01*
X4375545Y878398D01*
X4374925Y879231D01*
X4373840Y879856D01*
X4369655D01*
Y867356D01*
X4374770D01*
X4375855Y868189D01*
X4376475Y869439D01*
X4376785Y870898D01*
X4376475Y872356D01*
X4375545Y873606D01*
X4374460Y874023D01*
X4369655D01*
G01X4398020Y866939D02*
X4397710Y867148D01*
Y867564D01*
X4398020Y867773D01*
X4398330Y867564D01*
Y867148D01*
X4398020Y866939D01*
G01Y872564D02*
X4397710Y872773D01*
Y873189D01*
X4398020Y873398D01*
X4398330Y873189D01*
Y872773D01*
X4398020Y872564D01*
G01X4418790Y867356D02*
Y879856D01*
X4422820Y869439D01*
X4426850Y879856D01*
Y867356D01*
G01X4431345D02*
X4435220Y879856D01*
X4439095Y867356D01*
G01X4437700Y871731D02*
X4432740D01*
G01X4444055Y867356D02*
Y879856D01*
X4451185Y867356D01*
Y879856D01*
G01X4456610D02*
Y870898D01*
X4457230Y869022D01*
X4458470Y867773D01*
X4460020Y867356D01*
X4461570Y867773D01*
X4462810Y869022D01*
X4463430Y870898D01*
Y879856D01*
G01X4469475Y867356D02*
Y879856D01*
X4475365D01*
G01X4473195Y873814D02*
X4469475D01*
G01X4480945Y867356D02*
X4484820Y879856D01*
X4488695Y867356D01*
G01X4487300Y871731D02*
X4482340D01*
G01X4500630Y878814D02*
X4499700Y879439D01*
X4498615Y879856D01*
X4497375D01*
X4495980Y879231D01*
X4494895Y878189D01*
X4494120Y876939D01*
X4493500Y874856D01*
X4493345Y872981D01*
X4493655Y871106D01*
X4494120Y869856D01*
X4495050Y868606D01*
X4496135Y867773D01*
X4497220Y867356D01*
X4498305D01*
X4499390Y867773D01*
X4500320Y868397D01*
X4501095Y869231D01*
G01X4509620Y879856D02*
Y867356D01*
G01X4506055Y879856D02*
X4513185D01*
G01X4518610D02*
Y870898D01*
X4519230Y869022D01*
X4520470Y867773D01*
X4522020Y867356D01*
X4523570Y867773D01*
X4524810Y869022D01*
X4525430Y870898D01*
Y879856D01*
G01X4531320Y867356D02*
Y879856D01*
X4535195D01*
X4536435Y879231D01*
X4537210Y878398D01*
X4537520Y876731D01*
X4537210Y875064D01*
X4536280Y874023D01*
X4535195Y873398D01*
X4531320D01*
G01X4535195D02*
X4537520Y867356D01*
G01X4544960Y879856D02*
X4548680D01*
G01X4546820D02*
Y867356D01*
G01X4544960D02*
X4548680D01*
G01X4555655D02*
Y879856D01*
X4562785Y867356D01*
Y879856D01*
G01X4572550Y873606D02*
X4575650D01*
Y869856D01*
X4574720Y868606D01*
X4573635Y867773D01*
X4572085Y867356D01*
X4570535Y867773D01*
X4569450Y868606D01*
X4568520Y869856D01*
X4567900Y871314D01*
X4567590Y872981D01*
Y874439D01*
X4567900Y875689D01*
X4568520Y877148D01*
X4569450Y878398D01*
X4570380Y879231D01*
X4571620Y879856D01*
X4572705D01*
X4573945Y879439D01*
X4574875Y878606D01*
G01X4593165Y869022D02*
X4594405Y867981D01*
X4595800Y867356D01*
X4597040D01*
X4598280Y867981D01*
X4599210Y869022D01*
X4599675Y870481D01*
X4599365Y871939D01*
X4598590Y873189D01*
X4597195Y874023D01*
X4595335Y874439D01*
X4594250Y875273D01*
X4593785Y876731D01*
X4594095Y878189D01*
X4594870Y879231D01*
X4595955Y879856D01*
X4597040D01*
X4598125Y879439D01*
X4599055Y878398D01*
G01X4608820Y879856D02*
Y867356D01*
G01X4605255Y879856D02*
X4612385D01*
G01X4617810D02*
Y870898D01*
X4618430Y869022D01*
X4619670Y867773D01*
X4621220Y867356D01*
X4622770Y867773D01*
X4624010Y869022D01*
X4624630Y870898D01*
Y879856D01*
G01X4634860Y874023D02*
X4635480Y874648D01*
X4635945Y875689D01*
X4636255Y877148D01*
X4635945Y878398D01*
X4635325Y879231D01*
X4634240Y879856D01*
X4630055D01*
Y867356D01*
X4635170D01*
X4636255Y868189D01*
X4636875Y869439D01*
X4637185Y870898D01*
X4636875Y872356D01*
X4635945Y873606D01*
X4634860Y874023D01*
X4630055D01*
G01X4655320Y879856D02*
Y867356D01*
X4661520D01*
G01X4673920D02*
X4667720D01*
Y879856D01*
X4673920D01*
G01X4671440Y873814D02*
X4667720D01*
G01X4679655Y867356D02*
Y879856D01*
X4686785Y867356D01*
Y879856D01*
G01X4696550Y873606D02*
X4699650D01*
Y869856D01*
X4698720Y868606D01*
X4697635Y867773D01*
X4696085Y867356D01*
X4694535Y867773D01*
X4693450Y868606D01*
X4692520Y869856D01*
X4691900Y871314D01*
X4691590Y872981D01*
Y874439D01*
X4691900Y875689D01*
X4692520Y877148D01*
X4693450Y878398D01*
X4694380Y879231D01*
X4695620Y879856D01*
X4696705D01*
X4697945Y879439D01*
X4698875Y878606D01*
G01X4708020Y879856D02*
Y867356D01*
G01X4704455Y879856D02*
X4711585D01*
G01X4717165Y867356D02*
Y879856D01*
G01X4723675D02*
Y867356D01*
G01Y873606D02*
X4717165D01*
G01X4419565Y887772D02*
X4420805Y886731D01*
X4422200Y886106D01*
X4423440D01*
X4424680Y886731D01*
X4425610Y887772D01*
X4426075Y889231D01*
X4425765Y890689D01*
X4424990Y891939D01*
X4423595Y892773D01*
X4421735Y893189D01*
X4420650Y894023D01*
X4420185Y895481D01*
X4420495Y896939D01*
X4421270Y897981D01*
X4422355Y898606D01*
X4423440D01*
X4424525Y898189D01*
X4425455Y897148D01*
G01X4431810Y898606D02*
Y889648D01*
X4432430Y887772D01*
X4433670Y886523D01*
X4435220Y886106D01*
X4436770Y886523D01*
X4438010Y887772D01*
X4438630Y889648D01*
Y898606D01*
G01X4444520Y886106D02*
Y898606D01*
X4448395D01*
X4449635Y897981D01*
X4450410Y897148D01*
X4450720Y895481D01*
X4450410Y893814D01*
X4449480Y892773D01*
X4448395Y892148D01*
X4444520D01*
G01X4448395D02*
X4450720Y886106D01*
G01X4457075D02*
Y898606D01*
X4462965D01*
G01X4460795Y892564D02*
X4457075D01*
G01X4468545Y886106D02*
X4472420Y898606D01*
X4476295Y886106D01*
G01X4474900Y890481D02*
X4469940D01*
G01X4488230Y897564D02*
X4487300Y898189D01*
X4486215Y898606D01*
X4484975D01*
X4483580Y897981D01*
X4482495Y896939D01*
X4481720Y895689D01*
X4481100Y893606D01*
X4480945Y891731D01*
X4481255Y889856D01*
X4481720Y888606D01*
X4482650Y887356D01*
X4483735Y886523D01*
X4484820Y886106D01*
X4485905D01*
X4486990Y886523D01*
X4487920Y887147D01*
X4488695Y887981D01*
G01X4500320Y886106D02*
X4494120D01*
Y898606D01*
X4500320D01*
G01X4497840Y892564D02*
X4494120D01*
G01X4522020Y886106D02*
X4520780Y886314D01*
X4519695Y887147D01*
X4518765Y888398D01*
X4518145Y889856D01*
X4517835Y891523D01*
Y893189D01*
X4518145Y894856D01*
X4518765Y896314D01*
X4519695Y897564D01*
X4520780Y898398D01*
X4522020Y898606D01*
X4523260Y898398D01*
X4524345Y897564D01*
X4525275Y896314D01*
X4525895Y894856D01*
X4526205Y893189D01*
Y891523D01*
X4525895Y889856D01*
X4525275Y888398D01*
X4524345Y887147D01*
X4523260Y886314D01*
X4522020Y886106D01*
G01X4531475D02*
Y898606D01*
X4537365D01*
G01X4535195Y892564D02*
X4531475D01*
G01X4555190Y886106D02*
Y898606D01*
X4559220Y888189D01*
X4563250Y898606D01*
Y886106D01*
G01X4568210Y898606D02*
Y889648D01*
X4568830Y887772D01*
X4570070Y886523D01*
X4571620Y886106D01*
X4573170Y886523D01*
X4574410Y887772D01*
X4575030Y889648D01*
Y898606D01*
G01X4580765Y887772D02*
X4582005Y886731D01*
X4583400Y886106D01*
X4584640D01*
X4585880Y886731D01*
X4586810Y887772D01*
X4587275Y889231D01*
X4586965Y890689D01*
X4586190Y891939D01*
X4584795Y892773D01*
X4582935Y893189D01*
X4581850Y894023D01*
X4581385Y895481D01*
X4581695Y896939D01*
X4582470Y897981D01*
X4583555Y898606D01*
X4584640D01*
X4585725Y898189D01*
X4586655Y897148D01*
G01X4596420Y898606D02*
Y886106D01*
G01X4592855Y898606D02*
X4599985D01*
G01X4606805Y890273D02*
X4610835D01*
G01X4617655Y886106D02*
Y898606D01*
X4624785Y886106D01*
Y898606D01*
G01X4633620Y886106D02*
X4632380Y886314D01*
X4631295Y887147D01*
X4630365Y888398D01*
X4629745Y889856D01*
X4629435Y891523D01*
Y893189D01*
X4629745Y894856D01*
X4630365Y896314D01*
X4631295Y897564D01*
X4632380Y898398D01*
X4633620Y898606D01*
X4634860Y898398D01*
X4635945Y897564D01*
X4636875Y896314D01*
X4637495Y894856D01*
X4637805Y893189D01*
Y891523D01*
X4637495Y889856D01*
X4636875Y888398D01*
X4635945Y887147D01*
X4634860Y886314D01*
X4633620Y886106D01*
G01X4646020Y898606D02*
Y886106D01*
G01X4642455Y898606D02*
X4649585D01*
G01X4656405Y890273D02*
X4660435D01*
G01X4674230Y897564D02*
X4673300Y898189D01*
X4672215Y898606D01*
X4670975D01*
X4669580Y897981D01*
X4668495Y896939D01*
X4667720Y895689D01*
X4667100Y893606D01*
X4666945Y891731D01*
X4667255Y889856D01*
X4667720Y888606D01*
X4668650Y887356D01*
X4669735Y886523D01*
X4670820Y886106D01*
X4671905D01*
X4672990Y886523D01*
X4673920Y887147D01*
X4674695Y887981D01*
G01X4679810Y898606D02*
Y889648D01*
X4680430Y887772D01*
X4681670Y886523D01*
X4683220Y886106D01*
X4684770Y886523D01*
X4686010Y887772D01*
X4686630Y889648D01*
Y898606D01*
G01X4695620D02*
Y886106D01*
G01X4692055Y898606D02*
X4699185D01*
G01X4706005Y890273D02*
X4710035D01*
G01X4717320Y898606D02*
Y886106D01*
X4723520D01*
G01X4728945D02*
X4732820Y898606D01*
X4736695Y886106D01*
G01X4735300Y890481D02*
X4730340D01*
G01X4745220Y886106D02*
Y891731D01*
X4742120Y898606D01*
G01X4748320D02*
X4745220Y891731D01*
G01X4760720Y886106D02*
X4754520D01*
Y898606D01*
X4760720D01*
G01X4758240Y892564D02*
X4754520D01*
G01X4766920Y886106D02*
Y898606D01*
X4770795D01*
X4772035Y897981D01*
X4772810Y897148D01*
X4773120Y895481D01*
X4772810Y893814D01*
X4771880Y892773D01*
X4770795Y892148D01*
X4766920D01*
G01X4770795D02*
X4773120Y886106D01*
G01X4259605Y909023D02*
X4263635D01*
G01X4282390Y904856D02*
Y917356D01*
X4286420Y906939D01*
X4290450Y917356D01*
Y904856D01*
G01X4294945D02*
X4298820Y917356D01*
X4302695Y904856D01*
G01X4301300Y909231D02*
X4296340D01*
G01X4307965Y904856D02*
X4314475Y917356D01*
G01X4307965D02*
X4314475Y904856D01*
G01X4318970Y900689D02*
X4328270D01*
G01X4332610Y904856D02*
Y917356D01*
X4335710D01*
X4336950Y916731D01*
X4337880Y915898D01*
X4338655Y914648D01*
X4339275Y913189D01*
X4339430Y911106D01*
X4339275Y909023D01*
X4338655Y907564D01*
X4337880Y906314D01*
X4336950Y905481D01*
X4335710Y904856D01*
X4332610D01*
G01X4351520D02*
X4345320D01*
Y917356D01*
X4351520D01*
G01X4349040Y911314D02*
X4345320D01*
G01X4357720Y904856D02*
Y917356D01*
X4361440D01*
X4362680Y916731D01*
X4363610Y915273D01*
X4363920Y913606D01*
X4363610Y911939D01*
X4362835Y910689D01*
X4361440Y910064D01*
X4357720D01*
G01X4373220Y917356D02*
Y904856D01*
G01X4369655Y917356D02*
X4376785D01*
G01X4382365Y904856D02*
Y917356D01*
G01X4388875D02*
Y904856D01*
G01Y911106D02*
X4382365D01*
G01X4398020Y904439D02*
X4397710Y904648D01*
Y905064D01*
X4398020Y905273D01*
X4398330Y905064D01*
Y904648D01*
X4398020Y904439D01*
G01Y910064D02*
X4397710Y910273D01*
Y910689D01*
X4398020Y910898D01*
X4398330Y910689D01*
Y910273D01*
X4398020Y910064D01*
G01X4419410Y904856D02*
Y917356D01*
X4422510D01*
X4423750Y916731D01*
X4424680Y915898D01*
X4425455Y914648D01*
X4426075Y913189D01*
X4426230Y911106D01*
X4426075Y909023D01*
X4425455Y907564D01*
X4424680Y906314D01*
X4423750Y905481D01*
X4422510Y904856D01*
X4419410D01*
G01X4438320D02*
X4432120D01*
Y917356D01*
X4438320D01*
G01X4435840Y911314D02*
X4432120D01*
G01X4444520Y904856D02*
Y917356D01*
X4448240D01*
X4449480Y916731D01*
X4450410Y915273D01*
X4450720Y913606D01*
X4450410Y911939D01*
X4449635Y910689D01*
X4448240Y910064D01*
X4444520D01*
G01X4460020Y917356D02*
Y904856D01*
G01X4456455Y917356D02*
X4463585D01*
G01X4469165Y904856D02*
Y917356D01*
G01X4475675D02*
Y904856D01*
G01Y911106D02*
X4469165D01*
G01X4494275Y904856D02*
Y917356D01*
X4500165D01*
G01X4497995Y911314D02*
X4494275D01*
G01X4506520Y904856D02*
Y917356D01*
X4510395D01*
X4511635Y916731D01*
X4512410Y915898D01*
X4512720Y914231D01*
X4512410Y912564D01*
X4511480Y911523D01*
X4510395Y910898D01*
X4506520D01*
G01X4510395D02*
X4512720Y904856D01*
G01X4522020D02*
X4520780Y905064D01*
X4519695Y905897D01*
X4518765Y907148D01*
X4518145Y908606D01*
X4517835Y910273D01*
Y911939D01*
X4518145Y913606D01*
X4518765Y915064D01*
X4519695Y916314D01*
X4520780Y917148D01*
X4522020Y917356D01*
X4523260Y917148D01*
X4524345Y916314D01*
X4525275Y915064D01*
X4525895Y913606D01*
X4526205Y911939D01*
Y910273D01*
X4525895Y908606D01*
X4525275Y907148D01*
X4524345Y905897D01*
X4523260Y905064D01*
X4522020Y904856D01*
G01X4530390D02*
Y917356D01*
X4534420Y906939D01*
X4538450Y917356D01*
Y904856D01*
G01X4555965Y906522D02*
X4557205Y905481D01*
X4558600Y904856D01*
X4559840D01*
X4561080Y905481D01*
X4562010Y906522D01*
X4562475Y907981D01*
X4562165Y909439D01*
X4561390Y910689D01*
X4559995Y911523D01*
X4558135Y911939D01*
X4557050Y912773D01*
X4556585Y914231D01*
X4556895Y915689D01*
X4557670Y916731D01*
X4558755Y917356D01*
X4559840D01*
X4560925Y916939D01*
X4561855Y915898D01*
G01X4571620Y917356D02*
Y904856D01*
G01X4568055Y917356D02*
X4575185D01*
G01X4580145Y904856D02*
X4584020Y917356D01*
X4587895Y904856D01*
G01X4586500Y909231D02*
X4581540D01*
G01X4593320Y904856D02*
Y917356D01*
X4597195D01*
X4598435Y916731D01*
X4599210Y915898D01*
X4599520Y914231D01*
X4599210Y912564D01*
X4598280Y911523D01*
X4597195Y910898D01*
X4593320D01*
G01X4597195D02*
X4599520Y904856D01*
G01X4608820Y917356D02*
Y904856D01*
G01X4605255Y917356D02*
X4612385D01*
G01X4630520D02*
Y904856D01*
X4636720D01*
G01X4642145D02*
X4646020Y917356D01*
X4649895Y904856D01*
G01X4648500Y909231D02*
X4643540D01*
G01X4658420Y904856D02*
Y910481D01*
X4655320Y917356D01*
G01X4661520D02*
X4658420Y910481D01*
G01X4673920Y904856D02*
X4667720D01*
Y917356D01*
X4673920D01*
G01X4671440Y911314D02*
X4667720D01*
G01X4680120Y904856D02*
Y917356D01*
X4683995D01*
X4685235Y916731D01*
X4686010Y915898D01*
X4686320Y914231D01*
X4686010Y912564D01*
X4685080Y911523D01*
X4683995Y910898D01*
X4680120D01*
G01X4683995D02*
X4686320Y904856D01*
G01X4708020Y917356D02*
Y904856D01*
G01X4704455Y917356D02*
X4711585D01*
G01X4720420Y904856D02*
X4719180Y905064D01*
X4718095Y905897D01*
X4717165Y907148D01*
X4716545Y908606D01*
X4716235Y910273D01*
Y911939D01*
X4716545Y913606D01*
X4717165Y915064D01*
X4718095Y916314D01*
X4719180Y917148D01*
X4720420Y917356D01*
X4721660Y917148D01*
X4722745Y916314D01*
X4723675Y915064D01*
X4724295Y913606D01*
X4724605Y911939D01*
Y910273D01*
X4724295Y908606D01*
X4723675Y907148D01*
X4722745Y905897D01*
X4721660Y905064D01*
X4720420Y904856D01*
G01X4745220Y917356D02*
Y904856D01*
G01X4741655Y917356D02*
X4748785D01*
G01X4754365Y904856D02*
Y917356D01*
G01X4760875D02*
Y904856D01*
G01Y911106D02*
X4754365D01*
G01X4773120Y904856D02*
X4766920D01*
Y917356D01*
X4773120D01*
G01X4770640Y911314D02*
X4766920D01*
G01X4259605Y927773D02*
X4263635D01*
G01X4282390Y923606D02*
Y936106D01*
X4286420Y925689D01*
X4290450Y936106D01*
Y923606D01*
G01X4295255D02*
Y936106D01*
X4302385Y923606D01*
Y936106D01*
G01X4314630Y935064D02*
X4313700Y935689D01*
X4312615Y936106D01*
X4311375D01*
X4309980Y935481D01*
X4308895Y934439D01*
X4308120Y933189D01*
X4307500Y931106D01*
X4307345Y929231D01*
X4307655Y927356D01*
X4308120Y926106D01*
X4309050Y924856D01*
X4310135Y924023D01*
X4311220Y923606D01*
X4312305D01*
X4313390Y924023D01*
X4314320Y924647D01*
X4315095Y925481D01*
G01X4318970Y919439D02*
X4328270D01*
G01X4332920Y936106D02*
Y923606D01*
X4339120D01*
G01X4344545D02*
X4348420Y936106D01*
X4352295Y923606D01*
G01X4350900Y927981D02*
X4345940D01*
G01X4360820Y923606D02*
Y929231D01*
X4357720Y936106D01*
G01X4363920D02*
X4360820Y929231D01*
G01X4376320Y923606D02*
X4370120D01*
Y936106D01*
X4376320D01*
G01X4373840Y930064D02*
X4370120D01*
G01X4382520Y923606D02*
Y936106D01*
X4386395D01*
X4387635Y935481D01*
X4388410Y934648D01*
X4388720Y932981D01*
X4388410Y931314D01*
X4387480Y930273D01*
X4386395Y929648D01*
X4382520D01*
G01X4386395D02*
X4388720Y923606D01*
G01X4398020Y923189D02*
X4397710Y923398D01*
Y923814D01*
X4398020Y924023D01*
X4398330Y923814D01*
Y923398D01*
X4398020Y923189D01*
G01Y928814D02*
X4397710Y929023D01*
Y929439D01*
X4398020Y929648D01*
X4398330Y929439D01*
Y929023D01*
X4398020Y928814D01*
G01X4418790Y923606D02*
Y936106D01*
X4422820Y925689D01*
X4426850Y936106D01*
Y923606D01*
G01X4431810Y936106D02*
Y927148D01*
X4432430Y925272D01*
X4433670Y924023D01*
X4435220Y923606D01*
X4436770Y924023D01*
X4438010Y925272D01*
X4438630Y927148D01*
Y936106D01*
G01X4444365Y925272D02*
X4445605Y924231D01*
X4447000Y923606D01*
X4448240D01*
X4449480Y924231D01*
X4450410Y925272D01*
X4450875Y926731D01*
X4450565Y928189D01*
X4449790Y929439D01*
X4448395Y930273D01*
X4446535Y930689D01*
X4445450Y931523D01*
X4444985Y932981D01*
X4445295Y934439D01*
X4446070Y935481D01*
X4447155Y936106D01*
X4448240D01*
X4449325Y935689D01*
X4450255Y934648D01*
G01X4460020Y936106D02*
Y923606D01*
G01X4456455Y936106D02*
X4463585D01*
G01X4470405Y927773D02*
X4474435D01*
G01X4481255Y923606D02*
Y936106D01*
X4488385Y923606D01*
Y936106D01*
G01X4497220Y923606D02*
X4495980Y923814D01*
X4494895Y924647D01*
X4493965Y925898D01*
X4493345Y927356D01*
X4493035Y929023D01*
Y930689D01*
X4493345Y932356D01*
X4493965Y933814D01*
X4494895Y935064D01*
X4495980Y935898D01*
X4497220Y936106D01*
X4498460Y935898D01*
X4499545Y935064D01*
X4500475Y933814D01*
X4501095Y932356D01*
X4501405Y930689D01*
Y929023D01*
X4501095Y927356D01*
X4500475Y925898D01*
X4499545Y924647D01*
X4498460Y923814D01*
X4497220Y923606D01*
G01X4509620Y936106D02*
Y923606D01*
G01X4506055Y936106D02*
X4513185D01*
G01X4520005Y927773D02*
X4524035D01*
G01X4537830Y935064D02*
X4536900Y935689D01*
X4535815Y936106D01*
X4534575D01*
X4533180Y935481D01*
X4532095Y934439D01*
X4531320Y933189D01*
X4530700Y931106D01*
X4530545Y929231D01*
X4530855Y927356D01*
X4531320Y926106D01*
X4532250Y924856D01*
X4533335Y924023D01*
X4534420Y923606D01*
X4535505D01*
X4536590Y924023D01*
X4537520Y924647D01*
X4538295Y925481D01*
G01X4543410Y936106D02*
Y927148D01*
X4544030Y925272D01*
X4545270Y924023D01*
X4546820Y923606D01*
X4548370Y924023D01*
X4549610Y925272D01*
X4550230Y927148D01*
Y936106D01*
G01X4559220D02*
Y923606D01*
G01X4555655Y936106D02*
X4562785D01*
G01X4569605Y927773D02*
X4573635D01*
G01X4580920Y936106D02*
Y923606D01*
X4587120D01*
G01X4592545D02*
X4596420Y936106D01*
X4600295Y923606D01*
G01X4598900Y927981D02*
X4593940D01*
G01X4608820Y923606D02*
Y929231D01*
X4605720Y936106D01*
G01X4611920D02*
X4608820Y929231D01*
G01X4624320Y923606D02*
X4618120D01*
Y936106D01*
X4624320D01*
G01X4621840Y930064D02*
X4618120D01*
G01X4630520Y923606D02*
Y936106D01*
X4634395D01*
X4635635Y935481D01*
X4636410Y934648D01*
X4636720Y932981D01*
X4636410Y931314D01*
X4635480Y930273D01*
X4634395Y929648D01*
X4630520D01*
G01X4634395D02*
X4636720Y923606D01*
G01X4258055Y942356D02*
Y954856D01*
X4265185Y942356D01*
Y954856D01*
G01X4274020Y942356D02*
X4272780Y942564D01*
X4271695Y943397D01*
X4270765Y944648D01*
X4270145Y946106D01*
X4269835Y947773D01*
Y949439D01*
X4270145Y951106D01*
X4270765Y952564D01*
X4271695Y953814D01*
X4272780Y954648D01*
X4274020Y954856D01*
X4275260Y954648D01*
X4276345Y953814D01*
X4277275Y952564D01*
X4277895Y951106D01*
X4278205Y949439D01*
Y947773D01*
X4277895Y946106D01*
X4277275Y944648D01*
X4276345Y943397D01*
X4275260Y942564D01*
X4274020Y942356D01*
G01X4286420Y954856D02*
Y942356D01*
G01X4282855Y954856D02*
X4289985D01*
G01X4301920Y942356D02*
X4295720D01*
Y954856D01*
X4301920D01*
G01X4299440Y948814D02*
X4295720D01*
G01X4307965Y944022D02*
X4309205Y942981D01*
X4310600Y942356D01*
X4311840D01*
X4313080Y942981D01*
X4314010Y944022D01*
X4314475Y945481D01*
X4314165Y946939D01*
X4313390Y948189D01*
X4311995Y949023D01*
X4310135Y949439D01*
X4309050Y950273D01*
X4308585Y951731D01*
X4308895Y953189D01*
X4309670Y954231D01*
X4310755Y954856D01*
X4311840D01*
X4312925Y954439D01*
X4313855Y953398D01*
G01X4323620Y941939D02*
X4323310Y942148D01*
Y942564D01*
X4323620Y942773D01*
X4323930Y942564D01*
Y942148D01*
X4323620Y941939D01*
G01Y947564D02*
X4323310Y947773D01*
Y948189D01*
X4323620Y948398D01*
X4323930Y948189D01*
Y947773D01*
X4323620Y947564D01*
G01X4267975Y1011106D02*
Y1023606D01*
X4273865D01*
G01X4271695Y1017564D02*
X4267975D01*
G01X4281460Y1023606D02*
X4285180D01*
G01X4283320D02*
Y1011106D01*
G01X4281460D02*
X4285180D01*
G01X4296650Y1017356D02*
X4299750D01*
Y1013606D01*
X4298820Y1012356D01*
X4297735Y1011523D01*
X4296185Y1011106D01*
X4294635Y1011523D01*
X4293550Y1012356D01*
X4292620Y1013606D01*
X4292000Y1015064D01*
X4291690Y1016731D01*
Y1018189D01*
X4292000Y1019439D01*
X4292620Y1020898D01*
X4293550Y1022148D01*
X4294480Y1022981D01*
X4295720Y1023606D01*
X4296805D01*
X4298045Y1023189D01*
X4298975Y1022356D01*
G01X4304710Y1023606D02*
Y1014648D01*
X4305330Y1012772D01*
X4306570Y1011523D01*
X4308120Y1011106D01*
X4309670Y1011523D01*
X4310910Y1012772D01*
X4311530Y1014648D01*
Y1023606D01*
G01X4317420Y1011106D02*
Y1023606D01*
X4321295D01*
X4322535Y1022981D01*
X4323310Y1022148D01*
X4323620Y1020481D01*
X4323310Y1018814D01*
X4322380Y1017773D01*
X4321295Y1017148D01*
X4317420D01*
G01X4321295D02*
X4323620Y1011106D01*
G01X4336020D02*
X4329820D01*
Y1023606D01*
X4336020D01*
G01X4333540Y1017564D02*
X4329820D01*
G01X4429060Y1171773D02*
X4429680Y1172398D01*
X4430145Y1173439D01*
X4430455Y1174898D01*
X4430145Y1176148D01*
X4429525Y1176981D01*
X4428440Y1177606D01*
X4424255D01*
Y1165106D01*
X4429370D01*
X4430455Y1165939D01*
X4431075Y1167189D01*
X4431385Y1168648D01*
X4431075Y1170106D01*
X4430145Y1171356D01*
X4429060Y1171773D01*
X4424255D01*
G01X4436345Y1165106D02*
X4440220Y1177606D01*
X4444095Y1165106D01*
G01X4442700Y1169481D02*
X4437740D01*
G01X4456030Y1176564D02*
X4455100Y1177189D01*
X4454015Y1177606D01*
X4452775D01*
X4451380Y1176981D01*
X4450295Y1175939D01*
X4449520Y1174689D01*
X4448900Y1172606D01*
X4448745Y1170731D01*
X4449055Y1168856D01*
X4449520Y1167606D01*
X4450450Y1166356D01*
X4451535Y1165523D01*
X4452620Y1165106D01*
X4453705D01*
X4454790Y1165523D01*
X4455720Y1166147D01*
X4456495Y1166981D01*
G01X4461610Y1165106D02*
Y1177606D01*
G01X4467500D02*
X4461610Y1169897D01*
G01X4468430Y1165106D02*
X4464245Y1173439D01*
G01X4474010Y1165106D02*
Y1177606D01*
X4477110D01*
X4478350Y1176981D01*
X4479280Y1176148D01*
X4480055Y1174898D01*
X4480675Y1173439D01*
X4480830Y1171356D01*
X4480675Y1169273D01*
X4480055Y1167814D01*
X4479280Y1166564D01*
X4478350Y1165731D01*
X4477110Y1165106D01*
X4474010D01*
G01X4486720D02*
Y1177606D01*
X4490595D01*
X4491835Y1176981D01*
X4492610Y1176148D01*
X4492920Y1174481D01*
X4492610Y1172814D01*
X4491680Y1171773D01*
X4490595Y1171148D01*
X4486720D01*
G01X4490595D02*
X4492920Y1165106D01*
G01X4500360Y1177606D02*
X4504080D01*
G01X4502220D02*
Y1165106D01*
G01X4500360D02*
X4504080D01*
G01X4511520Y1177606D02*
Y1165106D01*
X4517720D01*
G01X4523920Y1177606D02*
Y1165106D01*
X4530120D01*
G01X4548565Y1166772D02*
X4549805Y1165731D01*
X4551200Y1165106D01*
X4552440D01*
X4553680Y1165731D01*
X4554610Y1166772D01*
X4555075Y1168231D01*
X4554765Y1169689D01*
X4553990Y1170939D01*
X4552595Y1171773D01*
X4550735Y1172189D01*
X4549650Y1173023D01*
X4549185Y1174481D01*
X4549495Y1175939D01*
X4550270Y1176981D01*
X4551355Y1177606D01*
X4552440D01*
X4553525Y1177189D01*
X4554455Y1176148D01*
G01X4564220Y1177606D02*
Y1165106D01*
G01X4560655Y1177606D02*
X4567785D01*
G01X4573210D02*
Y1168648D01*
X4573830Y1166772D01*
X4575070Y1165523D01*
X4576620Y1165106D01*
X4578170Y1165523D01*
X4579410Y1166772D01*
X4580030Y1168648D01*
Y1177606D01*
G01X4590260Y1171773D02*
X4590880Y1172398D01*
X4591345Y1173439D01*
X4591655Y1174898D01*
X4591345Y1176148D01*
X4590725Y1176981D01*
X4589640Y1177606D01*
X4585455D01*
Y1165106D01*
X4590570D01*
X4591655Y1165939D01*
X4592275Y1167189D01*
X4592585Y1168648D01*
X4592275Y1170106D01*
X4591345Y1171356D01*
X4590260Y1171773D01*
X4585455D01*
G01X4610720Y1177606D02*
Y1165106D01*
X4616920D01*
G01X4629320D02*
X4623120D01*
Y1177606D01*
X4629320D01*
G01X4626840Y1171564D02*
X4623120D01*
G01X4635055Y1165106D02*
Y1177606D01*
X4642185Y1165106D01*
Y1177606D01*
G01X4651950Y1171356D02*
X4655050D01*
Y1167606D01*
X4654120Y1166356D01*
X4653035Y1165523D01*
X4651485Y1165106D01*
X4649935Y1165523D01*
X4648850Y1166356D01*
X4647920Y1167606D01*
X4647300Y1169064D01*
X4646990Y1170731D01*
Y1172189D01*
X4647300Y1173439D01*
X4647920Y1174898D01*
X4648850Y1176148D01*
X4649780Y1176981D01*
X4651020Y1177606D01*
X4652105D01*
X4653345Y1177189D01*
X4654275Y1176356D01*
G01X4663420Y1177606D02*
Y1165106D01*
G01X4659855Y1177606D02*
X4666985D01*
G01X4672565Y1165106D02*
Y1177606D01*
G01X4679075D02*
Y1165106D01*
G01Y1171356D02*
X4672565D01*
G01X4700620Y1177606D02*
Y1165106D01*
G01X4697055Y1177606D02*
X4704185D01*
G01X4713020Y1165106D02*
X4711780Y1165314D01*
X4710695Y1166147D01*
X4709765Y1167398D01*
X4709145Y1168856D01*
X4708835Y1170523D01*
Y1172189D01*
X4709145Y1173856D01*
X4709765Y1175314D01*
X4710695Y1176564D01*
X4711780Y1177398D01*
X4713020Y1177606D01*
X4714260Y1177398D01*
X4715345Y1176564D01*
X4716275Y1175314D01*
X4716895Y1173856D01*
X4717205Y1172189D01*
Y1170523D01*
X4716895Y1168856D01*
X4716275Y1167398D01*
X4715345Y1166147D01*
X4714260Y1165314D01*
X4713020Y1165106D01*
G01X4722320Y1177606D02*
Y1165106D01*
X4728520D01*
G01X4740920D02*
X4734720D01*
Y1177606D01*
X4740920D01*
G01X4738440Y1171564D02*
X4734720D01*
G01X4747120Y1165106D02*
Y1177606D01*
X4750995D01*
X4752235Y1176981D01*
X4753010Y1176148D01*
X4753320Y1174481D01*
X4753010Y1172814D01*
X4752080Y1171773D01*
X4750995Y1171148D01*
X4747120D01*
G01X4750995D02*
X4753320Y1165106D01*
G01X4758745D02*
X4762620Y1177606D01*
X4766495Y1165106D01*
G01X4765100Y1169481D02*
X4760140D01*
G01X4771455Y1165106D02*
Y1177606D01*
X4778585Y1165106D01*
Y1177606D01*
G01X4790830Y1176564D02*
X4789900Y1177189D01*
X4788815Y1177606D01*
X4787575D01*
X4786180Y1176981D01*
X4785095Y1175939D01*
X4784320Y1174689D01*
X4783700Y1172606D01*
X4783545Y1170731D01*
X4783855Y1168856D01*
X4784320Y1167606D01*
X4785250Y1166356D01*
X4786335Y1165523D01*
X4787420Y1165106D01*
X4788505D01*
X4789590Y1165523D01*
X4790520Y1166147D01*
X4791295Y1166981D01*
G01X4802920Y1165106D02*
X4796720D01*
Y1177606D01*
X4802920D01*
G01X4800440Y1171564D02*
X4796720D01*
G01X4824620Y1177606D02*
Y1165106D01*
G01X4821055Y1177606D02*
X4828185D01*
G01X4837020Y1165106D02*
X4835780Y1165314D01*
X4834695Y1166147D01*
X4833765Y1167398D01*
X4833145Y1168856D01*
X4832835Y1170523D01*
Y1172189D01*
X4833145Y1173856D01*
X4833765Y1175314D01*
X4834695Y1176564D01*
X4835780Y1177398D01*
X4837020Y1177606D01*
X4838260Y1177398D01*
X4839345Y1176564D01*
X4840275Y1175314D01*
X4840895Y1173856D01*
X4841205Y1172189D01*
Y1170523D01*
X4840895Y1168856D01*
X4840275Y1167398D01*
X4839345Y1166147D01*
X4838260Y1165314D01*
X4837020Y1165106D01*
G01X4863060Y1171773D02*
X4863680Y1172398D01*
X4864145Y1173439D01*
X4864455Y1174898D01*
X4864145Y1176148D01*
X4863525Y1176981D01*
X4862440Y1177606D01*
X4858255D01*
Y1165106D01*
X4863370D01*
X4864455Y1165939D01*
X4865075Y1167189D01*
X4865385Y1168648D01*
X4865075Y1170106D01*
X4864145Y1171356D01*
X4863060Y1171773D01*
X4858255D01*
G01X4877320Y1165106D02*
X4871120D01*
Y1177606D01*
X4877320D01*
G01X4874840Y1171564D02*
X4871120D01*
G01X4898710Y1165106D02*
X4899020Y1167814D01*
X4899485Y1170106D01*
X4900105Y1172189D01*
X4900880Y1174481D01*
X4902120Y1177606D01*
X4895920D01*
G01X4922115Y1169273D02*
X4925835D01*
G01X4923820Y1171981D02*
Y1166564D01*
G01X4933430Y1164689D02*
X4939010Y1177606D01*
G01X4946605Y1169273D02*
X4950635D01*
G01X4957610Y1166981D02*
X4958540Y1165939D01*
X4959625Y1165314D01*
X4961020Y1165106D01*
X4962415Y1165523D01*
X4963500Y1166356D01*
X4964275Y1167814D01*
X4964430Y1169481D01*
X4964120Y1171148D01*
X4963345Y1172189D01*
X4962260Y1173023D01*
X4961175Y1173231D01*
X4960090Y1173023D01*
X4958695Y1172189D01*
X4959160Y1177606D01*
X4963345D01*
G01X4981790Y1165106D02*
Y1177606D01*
X4985820Y1167189D01*
X4989850Y1177606D01*
Y1165106D01*
G01X4996360Y1177606D02*
X5000080D01*
G01X4998220D02*
Y1165106D01*
G01X4996360D02*
X5000080D01*
G01X5007520Y1177606D02*
Y1165106D01*
X5013720D01*
G01X5019765Y1166772D02*
X5021005Y1165731D01*
X5022400Y1165106D01*
X5023640D01*
X5024880Y1165731D01*
X5025810Y1166772D01*
X5026275Y1168231D01*
X5025965Y1169689D01*
X5025190Y1170939D01*
X5023795Y1171773D01*
X5021935Y1172189D01*
X5020850Y1173023D01*
X5020385Y1174481D01*
X5020695Y1175939D01*
X5021470Y1176981D01*
X5022555Y1177606D01*
X5023640D01*
X5024725Y1177189D01*
X5025655Y1176148D01*
G01X4264605Y1188023D02*
X4268635D01*
G01X4287390Y1183856D02*
Y1196356D01*
X4291420Y1185939D01*
X4295450Y1196356D01*
Y1183856D01*
G01X4300875D02*
Y1196356D01*
X4306765D01*
G01X4304595Y1190314D02*
X4300875D01*
G01X4317150Y1190106D02*
X4320250D01*
Y1186356D01*
X4319320Y1185106D01*
X4318235Y1184273D01*
X4316685Y1183856D01*
X4315135Y1184273D01*
X4314050Y1185106D01*
X4313120Y1186356D01*
X4312500Y1187814D01*
X4312190Y1189481D01*
Y1190939D01*
X4312500Y1192189D01*
X4313120Y1193648D01*
X4314050Y1194898D01*
X4314980Y1195731D01*
X4316220Y1196356D01*
X4317305D01*
X4318545Y1195939D01*
X4319475Y1195106D01*
G01X4323970Y1179689D02*
X4333270D01*
G01X4337765Y1185522D02*
X4339005Y1184481D01*
X4340400Y1183856D01*
X4341640D01*
X4342880Y1184481D01*
X4343810Y1185522D01*
X4344275Y1186981D01*
X4343965Y1188439D01*
X4343190Y1189689D01*
X4341795Y1190523D01*
X4339935Y1190939D01*
X4338850Y1191773D01*
X4338385Y1193231D01*
X4338695Y1194689D01*
X4339470Y1195731D01*
X4340555Y1196356D01*
X4341640D01*
X4342725Y1195939D01*
X4343655Y1194898D01*
G01X4353420Y1196356D02*
Y1183856D01*
G01X4349855Y1196356D02*
X4356985D01*
G01X4362410D02*
Y1187398D01*
X4363030Y1185522D01*
X4364270Y1184273D01*
X4365820Y1183856D01*
X4367370Y1184273D01*
X4368610Y1185522D01*
X4369230Y1187398D01*
Y1196356D01*
G01X4379460Y1190523D02*
X4380080Y1191148D01*
X4380545Y1192189D01*
X4380855Y1193648D01*
X4380545Y1194898D01*
X4379925Y1195731D01*
X4378840Y1196356D01*
X4374655D01*
Y1183856D01*
X4379770D01*
X4380855Y1184689D01*
X4381475Y1185939D01*
X4381785Y1187398D01*
X4381475Y1188856D01*
X4380545Y1190106D01*
X4379460Y1190523D01*
X4374655D01*
G01X4403020Y1183439D02*
X4402710Y1183648D01*
Y1184064D01*
X4403020Y1184273D01*
X4403330Y1184064D01*
Y1183648D01*
X4403020Y1183439D01*
G01Y1189064D02*
X4402710Y1189273D01*
Y1189689D01*
X4403020Y1189898D01*
X4403330Y1189689D01*
Y1189273D01*
X4403020Y1189064D01*
G01X4423790Y1183856D02*
Y1196356D01*
X4427820Y1185939D01*
X4431850Y1196356D01*
Y1183856D01*
G01X4436345D02*
X4440220Y1196356D01*
X4444095Y1183856D01*
G01X4442700Y1188231D02*
X4437740D01*
G01X4449055Y1183856D02*
Y1196356D01*
X4456185Y1183856D01*
Y1196356D01*
G01X4461610D02*
Y1187398D01*
X4462230Y1185522D01*
X4463470Y1184273D01*
X4465020Y1183856D01*
X4466570Y1184273D01*
X4467810Y1185522D01*
X4468430Y1187398D01*
Y1196356D01*
G01X4474475Y1183856D02*
Y1196356D01*
X4480365D01*
G01X4478195Y1190314D02*
X4474475D01*
G01X4485945Y1183856D02*
X4489820Y1196356D01*
X4493695Y1183856D01*
G01X4492300Y1188231D02*
X4487340D01*
G01X4505630Y1195314D02*
X4504700Y1195939D01*
X4503615Y1196356D01*
X4502375D01*
X4500980Y1195731D01*
X4499895Y1194689D01*
X4499120Y1193439D01*
X4498500Y1191356D01*
X4498345Y1189481D01*
X4498655Y1187606D01*
X4499120Y1186356D01*
X4500050Y1185106D01*
X4501135Y1184273D01*
X4502220Y1183856D01*
X4503305D01*
X4504390Y1184273D01*
X4505320Y1184897D01*
X4506095Y1185731D01*
G01X4514620Y1196356D02*
Y1183856D01*
G01X4511055Y1196356D02*
X4518185D01*
G01X4523610D02*
Y1187398D01*
X4524230Y1185522D01*
X4525470Y1184273D01*
X4527020Y1183856D01*
X4528570Y1184273D01*
X4529810Y1185522D01*
X4530430Y1187398D01*
Y1196356D01*
G01X4536320Y1183856D02*
Y1196356D01*
X4540195D01*
X4541435Y1195731D01*
X4542210Y1194898D01*
X4542520Y1193231D01*
X4542210Y1191564D01*
X4541280Y1190523D01*
X4540195Y1189898D01*
X4536320D01*
G01X4540195D02*
X4542520Y1183856D01*
G01X4549960Y1196356D02*
X4553680D01*
G01X4551820D02*
Y1183856D01*
G01X4549960D02*
X4553680D01*
G01X4560655D02*
Y1196356D01*
X4567785Y1183856D01*
Y1196356D01*
G01X4577550Y1190106D02*
X4580650D01*
Y1186356D01*
X4579720Y1185106D01*
X4578635Y1184273D01*
X4577085Y1183856D01*
X4575535Y1184273D01*
X4574450Y1185106D01*
X4573520Y1186356D01*
X4572900Y1187814D01*
X4572590Y1189481D01*
Y1190939D01*
X4572900Y1192189D01*
X4573520Y1193648D01*
X4574450Y1194898D01*
X4575380Y1195731D01*
X4576620Y1196356D01*
X4577705D01*
X4578945Y1195939D01*
X4579875Y1195106D01*
G01X4598165Y1185522D02*
X4599405Y1184481D01*
X4600800Y1183856D01*
X4602040D01*
X4603280Y1184481D01*
X4604210Y1185522D01*
X4604675Y1186981D01*
X4604365Y1188439D01*
X4603590Y1189689D01*
X4602195Y1190523D01*
X4600335Y1190939D01*
X4599250Y1191773D01*
X4598785Y1193231D01*
X4599095Y1194689D01*
X4599870Y1195731D01*
X4600955Y1196356D01*
X4602040D01*
X4603125Y1195939D01*
X4604055Y1194898D01*
G01X4613820Y1196356D02*
Y1183856D01*
G01X4610255Y1196356D02*
X4617385D01*
G01X4622810D02*
Y1187398D01*
X4623430Y1185522D01*
X4624670Y1184273D01*
X4626220Y1183856D01*
X4627770Y1184273D01*
X4629010Y1185522D01*
X4629630Y1187398D01*
Y1196356D01*
G01X4639860Y1190523D02*
X4640480Y1191148D01*
X4640945Y1192189D01*
X4641255Y1193648D01*
X4640945Y1194898D01*
X4640325Y1195731D01*
X4639240Y1196356D01*
X4635055D01*
Y1183856D01*
X4640170D01*
X4641255Y1184689D01*
X4641875Y1185939D01*
X4642185Y1187398D01*
X4641875Y1188856D01*
X4640945Y1190106D01*
X4639860Y1190523D01*
X4635055D01*
G01X4660320Y1196356D02*
Y1183856D01*
X4666520D01*
G01X4678920D02*
X4672720D01*
Y1196356D01*
X4678920D01*
G01X4676440Y1190314D02*
X4672720D01*
G01X4684655Y1183856D02*
Y1196356D01*
X4691785Y1183856D01*
Y1196356D01*
G01X4701550Y1190106D02*
X4704650D01*
Y1186356D01*
X4703720Y1185106D01*
X4702635Y1184273D01*
X4701085Y1183856D01*
X4699535Y1184273D01*
X4698450Y1185106D01*
X4697520Y1186356D01*
X4696900Y1187814D01*
X4696590Y1189481D01*
Y1190939D01*
X4696900Y1192189D01*
X4697520Y1193648D01*
X4698450Y1194898D01*
X4699380Y1195731D01*
X4700620Y1196356D01*
X4701705D01*
X4702945Y1195939D01*
X4703875Y1195106D01*
G01X4713020Y1196356D02*
Y1183856D01*
G01X4709455Y1196356D02*
X4716585D01*
G01X4722165Y1183856D02*
Y1196356D01*
G01X4728675D02*
Y1183856D01*
G01Y1190106D02*
X4722165D01*
G01X4424565Y1204272D02*
X4425805Y1203231D01*
X4427200Y1202606D01*
X4428440D01*
X4429680Y1203231D01*
X4430610Y1204272D01*
X4431075Y1205731D01*
X4430765Y1207189D01*
X4429990Y1208439D01*
X4428595Y1209273D01*
X4426735Y1209689D01*
X4425650Y1210523D01*
X4425185Y1211981D01*
X4425495Y1213439D01*
X4426270Y1214481D01*
X4427355Y1215106D01*
X4428440D01*
X4429525Y1214689D01*
X4430455Y1213648D01*
G01X4436810Y1215106D02*
Y1206148D01*
X4437430Y1204272D01*
X4438670Y1203023D01*
X4440220Y1202606D01*
X4441770Y1203023D01*
X4443010Y1204272D01*
X4443630Y1206148D01*
Y1215106D01*
G01X4449520Y1202606D02*
Y1215106D01*
X4453395D01*
X4454635Y1214481D01*
X4455410Y1213648D01*
X4455720Y1211981D01*
X4455410Y1210314D01*
X4454480Y1209273D01*
X4453395Y1208648D01*
X4449520D01*
G01X4453395D02*
X4455720Y1202606D01*
G01X4462075D02*
Y1215106D01*
X4467965D01*
G01X4465795Y1209064D02*
X4462075D01*
G01X4473545Y1202606D02*
X4477420Y1215106D01*
X4481295Y1202606D01*
G01X4479900Y1206981D02*
X4474940D01*
G01X4493230Y1214064D02*
X4492300Y1214689D01*
X4491215Y1215106D01*
X4489975D01*
X4488580Y1214481D01*
X4487495Y1213439D01*
X4486720Y1212189D01*
X4486100Y1210106D01*
X4485945Y1208231D01*
X4486255Y1206356D01*
X4486720Y1205106D01*
X4487650Y1203856D01*
X4488735Y1203023D01*
X4489820Y1202606D01*
X4490905D01*
X4491990Y1203023D01*
X4492920Y1203647D01*
X4493695Y1204481D01*
G01X4505320Y1202606D02*
X4499120D01*
Y1215106D01*
X4505320D01*
G01X4502840Y1209064D02*
X4499120D01*
G01X4527020Y1202606D02*
X4525780Y1202814D01*
X4524695Y1203647D01*
X4523765Y1204898D01*
X4523145Y1206356D01*
X4522835Y1208023D01*
Y1209689D01*
X4523145Y1211356D01*
X4523765Y1212814D01*
X4524695Y1214064D01*
X4525780Y1214898D01*
X4527020Y1215106D01*
X4528260Y1214898D01*
X4529345Y1214064D01*
X4530275Y1212814D01*
X4530895Y1211356D01*
X4531205Y1209689D01*
Y1208023D01*
X4530895Y1206356D01*
X4530275Y1204898D01*
X4529345Y1203647D01*
X4528260Y1202814D01*
X4527020Y1202606D01*
G01X4536475D02*
Y1215106D01*
X4542365D01*
G01X4540195Y1209064D02*
X4536475D01*
G01X4560190Y1202606D02*
Y1215106D01*
X4564220Y1204689D01*
X4568250Y1215106D01*
Y1202606D01*
G01X4573210Y1215106D02*
Y1206148D01*
X4573830Y1204272D01*
X4575070Y1203023D01*
X4576620Y1202606D01*
X4578170Y1203023D01*
X4579410Y1204272D01*
X4580030Y1206148D01*
Y1215106D01*
G01X4585765Y1204272D02*
X4587005Y1203231D01*
X4588400Y1202606D01*
X4589640D01*
X4590880Y1203231D01*
X4591810Y1204272D01*
X4592275Y1205731D01*
X4591965Y1207189D01*
X4591190Y1208439D01*
X4589795Y1209273D01*
X4587935Y1209689D01*
X4586850Y1210523D01*
X4586385Y1211981D01*
X4586695Y1213439D01*
X4587470Y1214481D01*
X4588555Y1215106D01*
X4589640D01*
X4590725Y1214689D01*
X4591655Y1213648D01*
G01X4601420Y1215106D02*
Y1202606D01*
G01X4597855Y1215106D02*
X4604985D01*
G01X4611805Y1206773D02*
X4615835D01*
G01X4622655Y1202606D02*
Y1215106D01*
X4629785Y1202606D01*
Y1215106D01*
G01X4638620Y1202606D02*
X4637380Y1202814D01*
X4636295Y1203647D01*
X4635365Y1204898D01*
X4634745Y1206356D01*
X4634435Y1208023D01*
Y1209689D01*
X4634745Y1211356D01*
X4635365Y1212814D01*
X4636295Y1214064D01*
X4637380Y1214898D01*
X4638620Y1215106D01*
X4639860Y1214898D01*
X4640945Y1214064D01*
X4641875Y1212814D01*
X4642495Y1211356D01*
X4642805Y1209689D01*
Y1208023D01*
X4642495Y1206356D01*
X4641875Y1204898D01*
X4640945Y1203647D01*
X4639860Y1202814D01*
X4638620Y1202606D01*
G01X4651020Y1215106D02*
Y1202606D01*
G01X4647455Y1215106D02*
X4654585D01*
G01X4661405Y1206773D02*
X4665435D01*
G01X4679230Y1214064D02*
X4678300Y1214689D01*
X4677215Y1215106D01*
X4675975D01*
X4674580Y1214481D01*
X4673495Y1213439D01*
X4672720Y1212189D01*
X4672100Y1210106D01*
X4671945Y1208231D01*
X4672255Y1206356D01*
X4672720Y1205106D01*
X4673650Y1203856D01*
X4674735Y1203023D01*
X4675820Y1202606D01*
X4676905D01*
X4677990Y1203023D01*
X4678920Y1203647D01*
X4679695Y1204481D01*
G01X4684810Y1215106D02*
Y1206148D01*
X4685430Y1204272D01*
X4686670Y1203023D01*
X4688220Y1202606D01*
X4689770Y1203023D01*
X4691010Y1204272D01*
X4691630Y1206148D01*
Y1215106D01*
G01X4700620D02*
Y1202606D01*
G01X4697055Y1215106D02*
X4704185D01*
G01X4711005Y1206773D02*
X4715035D01*
G01X4722320Y1215106D02*
Y1202606D01*
X4728520D01*
G01X4733945D02*
X4737820Y1215106D01*
X4741695Y1202606D01*
G01X4740300Y1206981D02*
X4735340D01*
G01X4750220Y1202606D02*
Y1208231D01*
X4747120Y1215106D01*
G01X4753320D02*
X4750220Y1208231D01*
G01X4765720Y1202606D02*
X4759520D01*
Y1215106D01*
X4765720D01*
G01X4763240Y1209064D02*
X4759520D01*
G01X4771920Y1202606D02*
Y1215106D01*
X4775795D01*
X4777035Y1214481D01*
X4777810Y1213648D01*
X4778120Y1211981D01*
X4777810Y1210314D01*
X4776880Y1209273D01*
X4775795Y1208648D01*
X4771920D01*
G01X4775795D02*
X4778120Y1202606D01*
G01X4264605Y1225523D02*
X4268635D01*
G01X4287390Y1221356D02*
Y1233856D01*
X4291420Y1223439D01*
X4295450Y1233856D01*
Y1221356D01*
G01X4299945D02*
X4303820Y1233856D01*
X4307695Y1221356D01*
G01X4306300Y1225731D02*
X4301340D01*
G01X4312965Y1221356D02*
X4319475Y1233856D01*
G01X4312965D02*
X4319475Y1221356D01*
G01X4323970Y1217189D02*
X4333270D01*
G01X4337610Y1221356D02*
Y1233856D01*
X4340710D01*
X4341950Y1233231D01*
X4342880Y1232398D01*
X4343655Y1231148D01*
X4344275Y1229689D01*
X4344430Y1227606D01*
X4344275Y1225523D01*
X4343655Y1224064D01*
X4342880Y1222814D01*
X4341950Y1221981D01*
X4340710Y1221356D01*
X4337610D01*
G01X4356520D02*
X4350320D01*
Y1233856D01*
X4356520D01*
G01X4354040Y1227814D02*
X4350320D01*
G01X4362720Y1221356D02*
Y1233856D01*
X4366440D01*
X4367680Y1233231D01*
X4368610Y1231773D01*
X4368920Y1230106D01*
X4368610Y1228439D01*
X4367835Y1227189D01*
X4366440Y1226564D01*
X4362720D01*
G01X4378220Y1233856D02*
Y1221356D01*
G01X4374655Y1233856D02*
X4381785D01*
G01X4387365Y1221356D02*
Y1233856D01*
G01X4393875D02*
Y1221356D01*
G01Y1227606D02*
X4387365D01*
G01X4403020Y1220939D02*
X4402710Y1221148D01*
Y1221564D01*
X4403020Y1221773D01*
X4403330Y1221564D01*
Y1221148D01*
X4403020Y1220939D01*
G01Y1226564D02*
X4402710Y1226773D01*
Y1227189D01*
X4403020Y1227398D01*
X4403330Y1227189D01*
Y1226773D01*
X4403020Y1226564D01*
G01X4424410Y1221356D02*
Y1233856D01*
X4427510D01*
X4428750Y1233231D01*
X4429680Y1232398D01*
X4430455Y1231148D01*
X4431075Y1229689D01*
X4431230Y1227606D01*
X4431075Y1225523D01*
X4430455Y1224064D01*
X4429680Y1222814D01*
X4428750Y1221981D01*
X4427510Y1221356D01*
X4424410D01*
G01X4443320D02*
X4437120D01*
Y1233856D01*
X4443320D01*
G01X4440840Y1227814D02*
X4437120D01*
G01X4449520Y1221356D02*
Y1233856D01*
X4453240D01*
X4454480Y1233231D01*
X4455410Y1231773D01*
X4455720Y1230106D01*
X4455410Y1228439D01*
X4454635Y1227189D01*
X4453240Y1226564D01*
X4449520D01*
G01X4465020Y1233856D02*
Y1221356D01*
G01X4461455Y1233856D02*
X4468585D01*
G01X4474165Y1221356D02*
Y1233856D01*
G01X4480675D02*
Y1221356D01*
G01Y1227606D02*
X4474165D01*
G01X4499275Y1221356D02*
Y1233856D01*
X4505165D01*
G01X4502995Y1227814D02*
X4499275D01*
G01X4511520Y1221356D02*
Y1233856D01*
X4515395D01*
X4516635Y1233231D01*
X4517410Y1232398D01*
X4517720Y1230731D01*
X4517410Y1229064D01*
X4516480Y1228023D01*
X4515395Y1227398D01*
X4511520D01*
G01X4515395D02*
X4517720Y1221356D01*
G01X4527020D02*
X4525780Y1221564D01*
X4524695Y1222397D01*
X4523765Y1223648D01*
X4523145Y1225106D01*
X4522835Y1226773D01*
Y1228439D01*
X4523145Y1230106D01*
X4523765Y1231564D01*
X4524695Y1232814D01*
X4525780Y1233648D01*
X4527020Y1233856D01*
X4528260Y1233648D01*
X4529345Y1232814D01*
X4530275Y1231564D01*
X4530895Y1230106D01*
X4531205Y1228439D01*
Y1226773D01*
X4530895Y1225106D01*
X4530275Y1223648D01*
X4529345Y1222397D01*
X4528260Y1221564D01*
X4527020Y1221356D01*
G01X4535390D02*
Y1233856D01*
X4539420Y1223439D01*
X4543450Y1233856D01*
Y1221356D01*
G01X4560965Y1223022D02*
X4562205Y1221981D01*
X4563600Y1221356D01*
X4564840D01*
X4566080Y1221981D01*
X4567010Y1223022D01*
X4567475Y1224481D01*
X4567165Y1225939D01*
X4566390Y1227189D01*
X4564995Y1228023D01*
X4563135Y1228439D01*
X4562050Y1229273D01*
X4561585Y1230731D01*
X4561895Y1232189D01*
X4562670Y1233231D01*
X4563755Y1233856D01*
X4564840D01*
X4565925Y1233439D01*
X4566855Y1232398D01*
G01X4576620Y1233856D02*
Y1221356D01*
G01X4573055Y1233856D02*
X4580185D01*
G01X4585145Y1221356D02*
X4589020Y1233856D01*
X4592895Y1221356D01*
G01X4591500Y1225731D02*
X4586540D01*
G01X4598320Y1221356D02*
Y1233856D01*
X4602195D01*
X4603435Y1233231D01*
X4604210Y1232398D01*
X4604520Y1230731D01*
X4604210Y1229064D01*
X4603280Y1228023D01*
X4602195Y1227398D01*
X4598320D01*
G01X4602195D02*
X4604520Y1221356D01*
G01X4613820Y1233856D02*
Y1221356D01*
G01X4610255Y1233856D02*
X4617385D01*
G01X4635520D02*
Y1221356D01*
X4641720D01*
G01X4647145D02*
X4651020Y1233856D01*
X4654895Y1221356D01*
G01X4653500Y1225731D02*
X4648540D01*
G01X4663420Y1221356D02*
Y1226981D01*
X4660320Y1233856D01*
G01X4666520D02*
X4663420Y1226981D01*
G01X4678920Y1221356D02*
X4672720D01*
Y1233856D01*
X4678920D01*
G01X4676440Y1227814D02*
X4672720D01*
G01X4685120Y1221356D02*
Y1233856D01*
X4688995D01*
X4690235Y1233231D01*
X4691010Y1232398D01*
X4691320Y1230731D01*
X4691010Y1229064D01*
X4690080Y1228023D01*
X4688995Y1227398D01*
X4685120D01*
G01X4688995D02*
X4691320Y1221356D01*
G01X4713020Y1233856D02*
Y1221356D01*
G01X4709455Y1233856D02*
X4716585D01*
G01X4725420Y1221356D02*
X4724180Y1221564D01*
X4723095Y1222397D01*
X4722165Y1223648D01*
X4721545Y1225106D01*
X4721235Y1226773D01*
Y1228439D01*
X4721545Y1230106D01*
X4722165Y1231564D01*
X4723095Y1232814D01*
X4724180Y1233648D01*
X4725420Y1233856D01*
X4726660Y1233648D01*
X4727745Y1232814D01*
X4728675Y1231564D01*
X4729295Y1230106D01*
X4729605Y1228439D01*
Y1226773D01*
X4729295Y1225106D01*
X4728675Y1223648D01*
X4727745Y1222397D01*
X4726660Y1221564D01*
X4725420Y1221356D01*
G01X4750220Y1233856D02*
Y1221356D01*
G01X4746655Y1233856D02*
X4753785D01*
G01X4759365Y1221356D02*
Y1233856D01*
G01X4765875D02*
Y1221356D01*
G01Y1227606D02*
X4759365D01*
G01X4778120Y1221356D02*
X4771920D01*
Y1233856D01*
X4778120D01*
G01X4775640Y1227814D02*
X4771920D01*
G01X4264605Y1244273D02*
X4268635D01*
G01X4287390Y1240106D02*
Y1252606D01*
X4291420Y1242189D01*
X4295450Y1252606D01*
Y1240106D01*
G01X4300255D02*
Y1252606D01*
X4307385Y1240106D01*
Y1252606D01*
G01X4319630Y1251564D02*
X4318700Y1252189D01*
X4317615Y1252606D01*
X4316375D01*
X4314980Y1251981D01*
X4313895Y1250939D01*
X4313120Y1249689D01*
X4312500Y1247606D01*
X4312345Y1245731D01*
X4312655Y1243856D01*
X4313120Y1242606D01*
X4314050Y1241356D01*
X4315135Y1240523D01*
X4316220Y1240106D01*
X4317305D01*
X4318390Y1240523D01*
X4319320Y1241147D01*
X4320095Y1241981D01*
G01X4323970Y1235939D02*
X4333270D01*
G01X4337920Y1252606D02*
Y1240106D01*
X4344120D01*
G01X4349545D02*
X4353420Y1252606D01*
X4357295Y1240106D01*
G01X4355900Y1244481D02*
X4350940D01*
G01X4365820Y1240106D02*
Y1245731D01*
X4362720Y1252606D01*
G01X4368920D02*
X4365820Y1245731D01*
G01X4381320Y1240106D02*
X4375120D01*
Y1252606D01*
X4381320D01*
G01X4378840Y1246564D02*
X4375120D01*
G01X4387520Y1240106D02*
Y1252606D01*
X4391395D01*
X4392635Y1251981D01*
X4393410Y1251148D01*
X4393720Y1249481D01*
X4393410Y1247814D01*
X4392480Y1246773D01*
X4391395Y1246148D01*
X4387520D01*
G01X4391395D02*
X4393720Y1240106D01*
G01X4403020Y1239689D02*
X4402710Y1239898D01*
Y1240314D01*
X4403020Y1240523D01*
X4403330Y1240314D01*
Y1239898D01*
X4403020Y1239689D01*
G01Y1245314D02*
X4402710Y1245523D01*
Y1245939D01*
X4403020Y1246148D01*
X4403330Y1245939D01*
Y1245523D01*
X4403020Y1245314D01*
G01X4423790Y1240106D02*
Y1252606D01*
X4427820Y1242189D01*
X4431850Y1252606D01*
Y1240106D01*
G01X4436810Y1252606D02*
Y1243648D01*
X4437430Y1241772D01*
X4438670Y1240523D01*
X4440220Y1240106D01*
X4441770Y1240523D01*
X4443010Y1241772D01*
X4443630Y1243648D01*
Y1252606D01*
G01X4449365Y1241772D02*
X4450605Y1240731D01*
X4452000Y1240106D01*
X4453240D01*
X4454480Y1240731D01*
X4455410Y1241772D01*
X4455875Y1243231D01*
X4455565Y1244689D01*
X4454790Y1245939D01*
X4453395Y1246773D01*
X4451535Y1247189D01*
X4450450Y1248023D01*
X4449985Y1249481D01*
X4450295Y1250939D01*
X4451070Y1251981D01*
X4452155Y1252606D01*
X4453240D01*
X4454325Y1252189D01*
X4455255Y1251148D01*
G01X4465020Y1252606D02*
Y1240106D01*
G01X4461455Y1252606D02*
X4468585D01*
G01X4475405Y1244273D02*
X4479435D01*
G01X4486255Y1240106D02*
Y1252606D01*
X4493385Y1240106D01*
Y1252606D01*
G01X4502220Y1240106D02*
X4500980Y1240314D01*
X4499895Y1241147D01*
X4498965Y1242398D01*
X4498345Y1243856D01*
X4498035Y1245523D01*
Y1247189D01*
X4498345Y1248856D01*
X4498965Y1250314D01*
X4499895Y1251564D01*
X4500980Y1252398D01*
X4502220Y1252606D01*
X4503460Y1252398D01*
X4504545Y1251564D01*
X4505475Y1250314D01*
X4506095Y1248856D01*
X4506405Y1247189D01*
Y1245523D01*
X4506095Y1243856D01*
X4505475Y1242398D01*
X4504545Y1241147D01*
X4503460Y1240314D01*
X4502220Y1240106D01*
G01X4514620Y1252606D02*
Y1240106D01*
G01X4511055Y1252606D02*
X4518185D01*
G01X4525005Y1244273D02*
X4529035D01*
G01X4542830Y1251564D02*
X4541900Y1252189D01*
X4540815Y1252606D01*
X4539575D01*
X4538180Y1251981D01*
X4537095Y1250939D01*
X4536320Y1249689D01*
X4535700Y1247606D01*
X4535545Y1245731D01*
X4535855Y1243856D01*
X4536320Y1242606D01*
X4537250Y1241356D01*
X4538335Y1240523D01*
X4539420Y1240106D01*
X4540505D01*
X4541590Y1240523D01*
X4542520Y1241147D01*
X4543295Y1241981D01*
G01X4548410Y1252606D02*
Y1243648D01*
X4549030Y1241772D01*
X4550270Y1240523D01*
X4551820Y1240106D01*
X4553370Y1240523D01*
X4554610Y1241772D01*
X4555230Y1243648D01*
Y1252606D01*
G01X4564220D02*
Y1240106D01*
G01X4560655Y1252606D02*
X4567785D01*
G01X4574605Y1244273D02*
X4578635D01*
G01X4585920Y1252606D02*
Y1240106D01*
X4592120D01*
G01X4597545D02*
X4601420Y1252606D01*
X4605295Y1240106D01*
G01X4603900Y1244481D02*
X4598940D01*
G01X4613820Y1240106D02*
Y1245731D01*
X4610720Y1252606D01*
G01X4616920D02*
X4613820Y1245731D01*
G01X4629320Y1240106D02*
X4623120D01*
Y1252606D01*
X4629320D01*
G01X4626840Y1246564D02*
X4623120D01*
G01X4635520Y1240106D02*
Y1252606D01*
X4639395D01*
X4640635Y1251981D01*
X4641410Y1251148D01*
X4641720Y1249481D01*
X4641410Y1247814D01*
X4640480Y1246773D01*
X4639395Y1246148D01*
X4635520D01*
G01X4639395D02*
X4641720Y1240106D01*
G01X4263055Y1258856D02*
Y1271356D01*
X4270185Y1258856D01*
Y1271356D01*
G01X4279020Y1258856D02*
X4277780Y1259064D01*
X4276695Y1259897D01*
X4275765Y1261148D01*
X4275145Y1262606D01*
X4274835Y1264273D01*
Y1265939D01*
X4275145Y1267606D01*
X4275765Y1269064D01*
X4276695Y1270314D01*
X4277780Y1271148D01*
X4279020Y1271356D01*
X4280260Y1271148D01*
X4281345Y1270314D01*
X4282275Y1269064D01*
X4282895Y1267606D01*
X4283205Y1265939D01*
Y1264273D01*
X4282895Y1262606D01*
X4282275Y1261148D01*
X4281345Y1259897D01*
X4280260Y1259064D01*
X4279020Y1258856D01*
G01X4291420Y1271356D02*
Y1258856D01*
G01X4287855Y1271356D02*
X4294985D01*
G01X4306920Y1258856D02*
X4300720D01*
Y1271356D01*
X4306920D01*
G01X4304440Y1265314D02*
X4300720D01*
G01X4312965Y1260522D02*
X4314205Y1259481D01*
X4315600Y1258856D01*
X4316840D01*
X4318080Y1259481D01*
X4319010Y1260522D01*
X4319475Y1261981D01*
X4319165Y1263439D01*
X4318390Y1264689D01*
X4316995Y1265523D01*
X4315135Y1265939D01*
X4314050Y1266773D01*
X4313585Y1268231D01*
X4313895Y1269689D01*
X4314670Y1270731D01*
X4315755Y1271356D01*
X4316840D01*
X4317925Y1270939D01*
X4318855Y1269898D01*
G01X4328620Y1258439D02*
X4328310Y1258648D01*
Y1259064D01*
X4328620Y1259273D01*
X4328930Y1259064D01*
Y1258648D01*
X4328620Y1258439D01*
G01Y1264064D02*
X4328310Y1264273D01*
Y1264689D01*
X4328620Y1264898D01*
X4328930Y1264689D01*
Y1264273D01*
X4328620Y1264064D01*
G01X4431738Y1487212D02*
X4432358Y1487837D01*
X4432823Y1488878D01*
X4433133Y1490337D01*
X4432823Y1491587D01*
X4432203Y1492420D01*
X4431118Y1493045D01*
X4426933D01*
Y1480545D01*
X4432048D01*
X4433133Y1481378D01*
X4433753Y1482628D01*
X4434063Y1484087D01*
X4433753Y1485545D01*
X4432823Y1486795D01*
X4431738Y1487212D01*
X4426933D01*
G01X4439023Y1480545D02*
X4442898Y1493045D01*
X4446773Y1480545D01*
G01X4445378Y1484920D02*
X4440418D01*
G01X4458708Y1492003D02*
X4457778Y1492628D01*
X4456693Y1493045D01*
X4455453D01*
X4454058Y1492420D01*
X4452973Y1491378D01*
X4452198Y1490128D01*
X4451578Y1488045D01*
X4451423Y1486170D01*
X4451733Y1484295D01*
X4452198Y1483045D01*
X4453128Y1481795D01*
X4454213Y1480962D01*
X4455298Y1480545D01*
X4456383D01*
X4457468Y1480962D01*
X4458398Y1481586D01*
X4459173Y1482420D01*
G01X4464288Y1480545D02*
Y1493045D01*
G01X4470178D02*
X4464288Y1485336D01*
G01X4471108Y1480545D02*
X4466923Y1488878D01*
G01X4476688Y1480545D02*
Y1493045D01*
X4479788D01*
X4481028Y1492420D01*
X4481958Y1491587D01*
X4482733Y1490337D01*
X4483353Y1488878D01*
X4483508Y1486795D01*
X4483353Y1484712D01*
X4482733Y1483253D01*
X4481958Y1482003D01*
X4481028Y1481170D01*
X4479788Y1480545D01*
X4476688D01*
G01X4489398D02*
Y1493045D01*
X4493273D01*
X4494513Y1492420D01*
X4495288Y1491587D01*
X4495598Y1489920D01*
X4495288Y1488253D01*
X4494358Y1487212D01*
X4493273Y1486587D01*
X4489398D01*
G01X4493273D02*
X4495598Y1480545D01*
G01X4503038Y1493045D02*
X4506758D01*
G01X4504898D02*
Y1480545D01*
G01X4503038D02*
X4506758D01*
G01X4514198Y1493045D02*
Y1480545D01*
X4520398D01*
G01X4526598Y1493045D02*
Y1480545D01*
X4532798D01*
G01X4551243Y1482211D02*
X4552483Y1481170D01*
X4553878Y1480545D01*
X4555118D01*
X4556358Y1481170D01*
X4557288Y1482211D01*
X4557753Y1483670D01*
X4557443Y1485128D01*
X4556668Y1486378D01*
X4555273Y1487212D01*
X4553413Y1487628D01*
X4552328Y1488462D01*
X4551863Y1489920D01*
X4552173Y1491378D01*
X4552948Y1492420D01*
X4554033Y1493045D01*
X4555118D01*
X4556203Y1492628D01*
X4557133Y1491587D01*
G01X4566898Y1493045D02*
Y1480545D01*
G01X4563333Y1493045D02*
X4570463D01*
G01X4575888D02*
Y1484087D01*
X4576508Y1482211D01*
X4577748Y1480962D01*
X4579298Y1480545D01*
X4580848Y1480962D01*
X4582088Y1482211D01*
X4582708Y1484087D01*
Y1493045D01*
G01X4592938Y1487212D02*
X4593558Y1487837D01*
X4594023Y1488878D01*
X4594333Y1490337D01*
X4594023Y1491587D01*
X4593403Y1492420D01*
X4592318Y1493045D01*
X4588133D01*
Y1480545D01*
X4593248D01*
X4594333Y1481378D01*
X4594953Y1482628D01*
X4595263Y1484087D01*
X4594953Y1485545D01*
X4594023Y1486795D01*
X4592938Y1487212D01*
X4588133D01*
G01X4613398Y1493045D02*
Y1480545D01*
X4619598D01*
G01X4631998D02*
X4625798D01*
Y1493045D01*
X4631998D01*
G01X4629518Y1487003D02*
X4625798D01*
G01X4637733Y1480545D02*
Y1493045D01*
X4644863Y1480545D01*
Y1493045D01*
G01X4654628Y1486795D02*
X4657728D01*
Y1483045D01*
X4656798Y1481795D01*
X4655713Y1480962D01*
X4654163Y1480545D01*
X4652613Y1480962D01*
X4651528Y1481795D01*
X4650598Y1483045D01*
X4649978Y1484503D01*
X4649668Y1486170D01*
Y1487628D01*
X4649978Y1488878D01*
X4650598Y1490337D01*
X4651528Y1491587D01*
X4652458Y1492420D01*
X4653698Y1493045D01*
X4654783D01*
X4656023Y1492628D01*
X4656953Y1491795D01*
G01X4666098Y1493045D02*
Y1480545D01*
G01X4662533Y1493045D02*
X4669663D01*
G01X4675243Y1480545D02*
Y1493045D01*
G01X4681753D02*
Y1480545D01*
G01Y1486795D02*
X4675243D01*
G01X4703298Y1493045D02*
Y1480545D01*
G01X4699733Y1493045D02*
X4706863D01*
G01X4715698Y1480545D02*
X4714458Y1480753D01*
X4713373Y1481586D01*
X4712443Y1482837D01*
X4711823Y1484295D01*
X4711513Y1485962D01*
Y1487628D01*
X4711823Y1489295D01*
X4712443Y1490753D01*
X4713373Y1492003D01*
X4714458Y1492837D01*
X4715698Y1493045D01*
X4716938Y1492837D01*
X4718023Y1492003D01*
X4718953Y1490753D01*
X4719573Y1489295D01*
X4719883Y1487628D01*
Y1485962D01*
X4719573Y1484295D01*
X4718953Y1482837D01*
X4718023Y1481586D01*
X4716938Y1480753D01*
X4715698Y1480545D01*
G01X4724998Y1493045D02*
Y1480545D01*
X4731198D01*
G01X4743598D02*
X4737398D01*
Y1493045D01*
X4743598D01*
G01X4741118Y1487003D02*
X4737398D01*
G01X4749798Y1480545D02*
Y1493045D01*
X4753673D01*
X4754913Y1492420D01*
X4755688Y1491587D01*
X4755998Y1489920D01*
X4755688Y1488253D01*
X4754758Y1487212D01*
X4753673Y1486587D01*
X4749798D01*
G01X4753673D02*
X4755998Y1480545D01*
G01X4761423D02*
X4765298Y1493045D01*
X4769173Y1480545D01*
G01X4767778Y1484920D02*
X4762818D01*
G01X4774133Y1480545D02*
Y1493045D01*
X4781263Y1480545D01*
Y1493045D01*
G01X4793508Y1492003D02*
X4792578Y1492628D01*
X4791493Y1493045D01*
X4790253D01*
X4788858Y1492420D01*
X4787773Y1491378D01*
X4786998Y1490128D01*
X4786378Y1488045D01*
X4786223Y1486170D01*
X4786533Y1484295D01*
X4786998Y1483045D01*
X4787928Y1481795D01*
X4789013Y1480962D01*
X4790098Y1480545D01*
X4791183D01*
X4792268Y1480962D01*
X4793198Y1481586D01*
X4793973Y1482420D01*
G01X4805598Y1480545D02*
X4799398D01*
Y1493045D01*
X4805598D01*
G01X4803118Y1487003D02*
X4799398D01*
G01X4827298Y1493045D02*
Y1480545D01*
G01X4823733Y1493045D02*
X4830863D01*
G01X4839698Y1480545D02*
X4838458Y1480753D01*
X4837373Y1481586D01*
X4836443Y1482837D01*
X4835823Y1484295D01*
X4835513Y1485962D01*
Y1487628D01*
X4835823Y1489295D01*
X4836443Y1490753D01*
X4837373Y1492003D01*
X4838458Y1492837D01*
X4839698Y1493045D01*
X4840938Y1492837D01*
X4842023Y1492003D01*
X4842953Y1490753D01*
X4843573Y1489295D01*
X4843883Y1487628D01*
Y1485962D01*
X4843573Y1484295D01*
X4842953Y1482837D01*
X4842023Y1481586D01*
X4840938Y1480753D01*
X4839698Y1480545D01*
G01X4865738Y1487212D02*
X4866358Y1487837D01*
X4866823Y1488878D01*
X4867133Y1490337D01*
X4866823Y1491587D01*
X4866203Y1492420D01*
X4865118Y1493045D01*
X4860933D01*
Y1480545D01*
X4866048D01*
X4867133Y1481378D01*
X4867753Y1482628D01*
X4868063Y1484087D01*
X4867753Y1485545D01*
X4866823Y1486795D01*
X4865738Y1487212D01*
X4860933D01*
G01X4879998Y1480545D02*
X4873798D01*
Y1493045D01*
X4879998D01*
G01X4877518Y1487003D02*
X4873798D01*
G01X4901388Y1480545D02*
X4901698Y1483253D01*
X4902163Y1485545D01*
X4902783Y1487628D01*
X4903558Y1489920D01*
X4904798Y1493045D01*
X4898598D01*
G01X4924793Y1484712D02*
X4928513D01*
G01X4926498Y1487420D02*
Y1482003D01*
G01X4936108Y1480128D02*
X4941688Y1493045D01*
G01X4949283Y1484712D02*
X4953313D01*
G01X4960288Y1482420D02*
X4961218Y1481378D01*
X4962303Y1480753D01*
X4963698Y1480545D01*
X4965093Y1480962D01*
X4966178Y1481795D01*
X4966953Y1483253D01*
X4967108Y1484920D01*
X4966798Y1486587D01*
X4966023Y1487628D01*
X4964938Y1488462D01*
X4963853Y1488670D01*
X4962768Y1488462D01*
X4961373Y1487628D01*
X4961838Y1493045D01*
X4966023D01*
G01X4984468Y1480545D02*
Y1493045D01*
X4988498Y1482628D01*
X4992528Y1493045D01*
Y1480545D01*
G01X4999038Y1493045D02*
X5002758D01*
G01X5000898D02*
Y1480545D01*
G01X4999038D02*
X5002758D01*
G01X5010198Y1493045D02*
Y1480545D01*
X5016398D01*
G01X5022443Y1482211D02*
X5023683Y1481170D01*
X5025078Y1480545D01*
X5026318D01*
X5027558Y1481170D01*
X5028488Y1482211D01*
X5028953Y1483670D01*
X5028643Y1485128D01*
X5027868Y1486378D01*
X5026473Y1487212D01*
X5024613Y1487628D01*
X5023528Y1488462D01*
X5023063Y1489920D01*
X5023373Y1491378D01*
X5024148Y1492420D01*
X5025233Y1493045D01*
X5026318D01*
X5027403Y1492628D01*
X5028333Y1491587D01*
G01X4267283Y1503462D02*
X4271313D01*
G01X4290068Y1499295D02*
Y1511795D01*
X4294098Y1501378D01*
X4298128Y1511795D01*
Y1499295D01*
G01X4303553D02*
Y1511795D01*
X4309443D01*
G01X4307273Y1505753D02*
X4303553D01*
G01X4319828Y1505545D02*
X4322928D01*
Y1501795D01*
X4321998Y1500545D01*
X4320913Y1499712D01*
X4319363Y1499295D01*
X4317813Y1499712D01*
X4316728Y1500545D01*
X4315798Y1501795D01*
X4315178Y1503253D01*
X4314868Y1504920D01*
Y1506378D01*
X4315178Y1507628D01*
X4315798Y1509087D01*
X4316728Y1510337D01*
X4317658Y1511170D01*
X4318898Y1511795D01*
X4319983D01*
X4321223Y1511378D01*
X4322153Y1510545D01*
G01X4326648Y1495128D02*
X4335948D01*
G01X4340443Y1500961D02*
X4341683Y1499920D01*
X4343078Y1499295D01*
X4344318D01*
X4345558Y1499920D01*
X4346488Y1500961D01*
X4346953Y1502420D01*
X4346643Y1503878D01*
X4345868Y1505128D01*
X4344473Y1505962D01*
X4342613Y1506378D01*
X4341528Y1507212D01*
X4341063Y1508670D01*
X4341373Y1510128D01*
X4342148Y1511170D01*
X4343233Y1511795D01*
X4344318D01*
X4345403Y1511378D01*
X4346333Y1510337D01*
G01X4356098Y1511795D02*
Y1499295D01*
G01X4352533Y1511795D02*
X4359663D01*
G01X4365088D02*
Y1502837D01*
X4365708Y1500961D01*
X4366948Y1499712D01*
X4368498Y1499295D01*
X4370048Y1499712D01*
X4371288Y1500961D01*
X4371908Y1502837D01*
Y1511795D01*
G01X4382138Y1505962D02*
X4382758Y1506587D01*
X4383223Y1507628D01*
X4383533Y1509087D01*
X4383223Y1510337D01*
X4382603Y1511170D01*
X4381518Y1511795D01*
X4377333D01*
Y1499295D01*
X4382448D01*
X4383533Y1500128D01*
X4384153Y1501378D01*
X4384463Y1502837D01*
X4384153Y1504295D01*
X4383223Y1505545D01*
X4382138Y1505962D01*
X4377333D01*
G01X4405698Y1498878D02*
X4405388Y1499087D01*
Y1499503D01*
X4405698Y1499712D01*
X4406008Y1499503D01*
Y1499087D01*
X4405698Y1498878D01*
G01Y1504503D02*
X4405388Y1504712D01*
Y1505128D01*
X4405698Y1505337D01*
X4406008Y1505128D01*
Y1504712D01*
X4405698Y1504503D01*
G01X4426468Y1499295D02*
Y1511795D01*
X4430498Y1501378D01*
X4434528Y1511795D01*
Y1499295D01*
G01X4439023D02*
X4442898Y1511795D01*
X4446773Y1499295D01*
G01X4445378Y1503670D02*
X4440418D01*
G01X4451733Y1499295D02*
Y1511795D01*
X4458863Y1499295D01*
Y1511795D01*
G01X4464288D02*
Y1502837D01*
X4464908Y1500961D01*
X4466148Y1499712D01*
X4467698Y1499295D01*
X4469248Y1499712D01*
X4470488Y1500961D01*
X4471108Y1502837D01*
Y1511795D01*
G01X4477153Y1499295D02*
Y1511795D01*
X4483043D01*
G01X4480873Y1505753D02*
X4477153D01*
G01X4488623Y1499295D02*
X4492498Y1511795D01*
X4496373Y1499295D01*
G01X4494978Y1503670D02*
X4490018D01*
G01X4508308Y1510753D02*
X4507378Y1511378D01*
X4506293Y1511795D01*
X4505053D01*
X4503658Y1511170D01*
X4502573Y1510128D01*
X4501798Y1508878D01*
X4501178Y1506795D01*
X4501023Y1504920D01*
X4501333Y1503045D01*
X4501798Y1501795D01*
X4502728Y1500545D01*
X4503813Y1499712D01*
X4504898Y1499295D01*
X4505983D01*
X4507068Y1499712D01*
X4507998Y1500336D01*
X4508773Y1501170D01*
G01X4517298Y1511795D02*
Y1499295D01*
G01X4513733Y1511795D02*
X4520863D01*
G01X4526288D02*
Y1502837D01*
X4526908Y1500961D01*
X4528148Y1499712D01*
X4529698Y1499295D01*
X4531248Y1499712D01*
X4532488Y1500961D01*
X4533108Y1502837D01*
Y1511795D01*
G01X4538998Y1499295D02*
Y1511795D01*
X4542873D01*
X4544113Y1511170D01*
X4544888Y1510337D01*
X4545198Y1508670D01*
X4544888Y1507003D01*
X4543958Y1505962D01*
X4542873Y1505337D01*
X4538998D01*
G01X4542873D02*
X4545198Y1499295D01*
G01X4552638Y1511795D02*
X4556358D01*
G01X4554498D02*
Y1499295D01*
G01X4552638D02*
X4556358D01*
G01X4563333D02*
Y1511795D01*
X4570463Y1499295D01*
Y1511795D01*
G01X4580228Y1505545D02*
X4583328D01*
Y1501795D01*
X4582398Y1500545D01*
X4581313Y1499712D01*
X4579763Y1499295D01*
X4578213Y1499712D01*
X4577128Y1500545D01*
X4576198Y1501795D01*
X4575578Y1503253D01*
X4575268Y1504920D01*
Y1506378D01*
X4575578Y1507628D01*
X4576198Y1509087D01*
X4577128Y1510337D01*
X4578058Y1511170D01*
X4579298Y1511795D01*
X4580383D01*
X4581623Y1511378D01*
X4582553Y1510545D01*
G01X4600843Y1500961D02*
X4602083Y1499920D01*
X4603478Y1499295D01*
X4604718D01*
X4605958Y1499920D01*
X4606888Y1500961D01*
X4607353Y1502420D01*
X4607043Y1503878D01*
X4606268Y1505128D01*
X4604873Y1505962D01*
X4603013Y1506378D01*
X4601928Y1507212D01*
X4601463Y1508670D01*
X4601773Y1510128D01*
X4602548Y1511170D01*
X4603633Y1511795D01*
X4604718D01*
X4605803Y1511378D01*
X4606733Y1510337D01*
G01X4616498Y1511795D02*
Y1499295D01*
G01X4612933Y1511795D02*
X4620063D01*
G01X4625488D02*
Y1502837D01*
X4626108Y1500961D01*
X4627348Y1499712D01*
X4628898Y1499295D01*
X4630448Y1499712D01*
X4631688Y1500961D01*
X4632308Y1502837D01*
Y1511795D01*
G01X4642538Y1505962D02*
X4643158Y1506587D01*
X4643623Y1507628D01*
X4643933Y1509087D01*
X4643623Y1510337D01*
X4643003Y1511170D01*
X4641918Y1511795D01*
X4637733D01*
Y1499295D01*
X4642848D01*
X4643933Y1500128D01*
X4644553Y1501378D01*
X4644863Y1502837D01*
X4644553Y1504295D01*
X4643623Y1505545D01*
X4642538Y1505962D01*
X4637733D01*
G01X4662998Y1511795D02*
Y1499295D01*
X4669198D01*
G01X4681598D02*
X4675398D01*
Y1511795D01*
X4681598D01*
G01X4679118Y1505753D02*
X4675398D01*
G01X4687333Y1499295D02*
Y1511795D01*
X4694463Y1499295D01*
Y1511795D01*
G01X4704228Y1505545D02*
X4707328D01*
Y1501795D01*
X4706398Y1500545D01*
X4705313Y1499712D01*
X4703763Y1499295D01*
X4702213Y1499712D01*
X4701128Y1500545D01*
X4700198Y1501795D01*
X4699578Y1503253D01*
X4699268Y1504920D01*
Y1506378D01*
X4699578Y1507628D01*
X4700198Y1509087D01*
X4701128Y1510337D01*
X4702058Y1511170D01*
X4703298Y1511795D01*
X4704383D01*
X4705623Y1511378D01*
X4706553Y1510545D01*
G01X4715698Y1511795D02*
Y1499295D01*
G01X4712133Y1511795D02*
X4719263D01*
G01X4724843Y1499295D02*
Y1511795D01*
G01X4731353D02*
Y1499295D01*
G01Y1505545D02*
X4724843D01*
G01X4427243Y1519711D02*
X4428483Y1518670D01*
X4429878Y1518045D01*
X4431118D01*
X4432358Y1518670D01*
X4433288Y1519711D01*
X4433753Y1521170D01*
X4433443Y1522628D01*
X4432668Y1523878D01*
X4431273Y1524712D01*
X4429413Y1525128D01*
X4428328Y1525962D01*
X4427863Y1527420D01*
X4428173Y1528878D01*
X4428948Y1529920D01*
X4430033Y1530545D01*
X4431118D01*
X4432203Y1530128D01*
X4433133Y1529087D01*
G01X4439488Y1530545D02*
Y1521587D01*
X4440108Y1519711D01*
X4441348Y1518462D01*
X4442898Y1518045D01*
X4444448Y1518462D01*
X4445688Y1519711D01*
X4446308Y1521587D01*
Y1530545D01*
G01X4452198Y1518045D02*
Y1530545D01*
X4456073D01*
X4457313Y1529920D01*
X4458088Y1529087D01*
X4458398Y1527420D01*
X4458088Y1525753D01*
X4457158Y1524712D01*
X4456073Y1524087D01*
X4452198D01*
G01X4456073D02*
X4458398Y1518045D01*
G01X4464753D02*
Y1530545D01*
X4470643D01*
G01X4468473Y1524503D02*
X4464753D01*
G01X4476223Y1518045D02*
X4480098Y1530545D01*
X4483973Y1518045D01*
G01X4482578Y1522420D02*
X4477618D01*
G01X4495908Y1529503D02*
X4494978Y1530128D01*
X4493893Y1530545D01*
X4492653D01*
X4491258Y1529920D01*
X4490173Y1528878D01*
X4489398Y1527628D01*
X4488778Y1525545D01*
X4488623Y1523670D01*
X4488933Y1521795D01*
X4489398Y1520545D01*
X4490328Y1519295D01*
X4491413Y1518462D01*
X4492498Y1518045D01*
X4493583D01*
X4494668Y1518462D01*
X4495598Y1519086D01*
X4496373Y1519920D01*
G01X4507998Y1518045D02*
X4501798D01*
Y1530545D01*
X4507998D01*
G01X4505518Y1524503D02*
X4501798D01*
G01X4529698Y1518045D02*
X4528458Y1518253D01*
X4527373Y1519086D01*
X4526443Y1520337D01*
X4525823Y1521795D01*
X4525513Y1523462D01*
Y1525128D01*
X4525823Y1526795D01*
X4526443Y1528253D01*
X4527373Y1529503D01*
X4528458Y1530337D01*
X4529698Y1530545D01*
X4530938Y1530337D01*
X4532023Y1529503D01*
X4532953Y1528253D01*
X4533573Y1526795D01*
X4533883Y1525128D01*
Y1523462D01*
X4533573Y1521795D01*
X4532953Y1520337D01*
X4532023Y1519086D01*
X4530938Y1518253D01*
X4529698Y1518045D01*
G01X4539153D02*
Y1530545D01*
X4545043D01*
G01X4542873Y1524503D02*
X4539153D01*
G01X4562868Y1518045D02*
Y1530545D01*
X4566898Y1520128D01*
X4570928Y1530545D01*
Y1518045D01*
G01X4575888Y1530545D02*
Y1521587D01*
X4576508Y1519711D01*
X4577748Y1518462D01*
X4579298Y1518045D01*
X4580848Y1518462D01*
X4582088Y1519711D01*
X4582708Y1521587D01*
Y1530545D01*
G01X4588443Y1519711D02*
X4589683Y1518670D01*
X4591078Y1518045D01*
X4592318D01*
X4593558Y1518670D01*
X4594488Y1519711D01*
X4594953Y1521170D01*
X4594643Y1522628D01*
X4593868Y1523878D01*
X4592473Y1524712D01*
X4590613Y1525128D01*
X4589528Y1525962D01*
X4589063Y1527420D01*
X4589373Y1528878D01*
X4590148Y1529920D01*
X4591233Y1530545D01*
X4592318D01*
X4593403Y1530128D01*
X4594333Y1529087D01*
G01X4604098Y1530545D02*
Y1518045D01*
G01X4600533Y1530545D02*
X4607663D01*
G01X4614483Y1522212D02*
X4618513D01*
G01X4625333Y1518045D02*
Y1530545D01*
X4632463Y1518045D01*
Y1530545D01*
G01X4641298Y1518045D02*
X4640058Y1518253D01*
X4638973Y1519086D01*
X4638043Y1520337D01*
X4637423Y1521795D01*
X4637113Y1523462D01*
Y1525128D01*
X4637423Y1526795D01*
X4638043Y1528253D01*
X4638973Y1529503D01*
X4640058Y1530337D01*
X4641298Y1530545D01*
X4642538Y1530337D01*
X4643623Y1529503D01*
X4644553Y1528253D01*
X4645173Y1526795D01*
X4645483Y1525128D01*
Y1523462D01*
X4645173Y1521795D01*
X4644553Y1520337D01*
X4643623Y1519086D01*
X4642538Y1518253D01*
X4641298Y1518045D01*
G01X4653698Y1530545D02*
Y1518045D01*
G01X4650133Y1530545D02*
X4657263D01*
G01X4664083Y1522212D02*
X4668113D01*
G01X4681908Y1529503D02*
X4680978Y1530128D01*
X4679893Y1530545D01*
X4678653D01*
X4677258Y1529920D01*
X4676173Y1528878D01*
X4675398Y1527628D01*
X4674778Y1525545D01*
X4674623Y1523670D01*
X4674933Y1521795D01*
X4675398Y1520545D01*
X4676328Y1519295D01*
X4677413Y1518462D01*
X4678498Y1518045D01*
X4679583D01*
X4680668Y1518462D01*
X4681598Y1519086D01*
X4682373Y1519920D01*
G01X4687488Y1530545D02*
Y1521587D01*
X4688108Y1519711D01*
X4689348Y1518462D01*
X4690898Y1518045D01*
X4692448Y1518462D01*
X4693688Y1519711D01*
X4694308Y1521587D01*
Y1530545D01*
G01X4703298D02*
Y1518045D01*
G01X4699733Y1530545D02*
X4706863D01*
G01X4713683Y1522212D02*
X4717713D01*
G01X4724998Y1530545D02*
Y1518045D01*
X4731198D01*
G01X4736623D02*
X4740498Y1530545D01*
X4744373Y1518045D01*
G01X4742978Y1522420D02*
X4738018D01*
G01X4752898Y1518045D02*
Y1523670D01*
X4749798Y1530545D01*
G01X4755998D02*
X4752898Y1523670D01*
G01X4768398Y1518045D02*
X4762198D01*
Y1530545D01*
X4768398D01*
G01X4765918Y1524503D02*
X4762198D01*
G01X4774598Y1518045D02*
Y1530545D01*
X4778473D01*
X4779713Y1529920D01*
X4780488Y1529087D01*
X4780798Y1527420D01*
X4780488Y1525753D01*
X4779558Y1524712D01*
X4778473Y1524087D01*
X4774598D01*
G01X4778473D02*
X4780798Y1518045D01*
G01X4267283Y1540962D02*
X4271313D01*
G01X4290068Y1536795D02*
Y1549295D01*
X4294098Y1538878D01*
X4298128Y1549295D01*
Y1536795D01*
G01X4302623D02*
X4306498Y1549295D01*
X4310373Y1536795D01*
G01X4308978Y1541170D02*
X4304018D01*
G01X4315643Y1536795D02*
X4322153Y1549295D01*
G01X4315643D02*
X4322153Y1536795D01*
G01X4326648Y1532628D02*
X4335948D01*
G01X4340288Y1536795D02*
Y1549295D01*
X4343388D01*
X4344628Y1548670D01*
X4345558Y1547837D01*
X4346333Y1546587D01*
X4346953Y1545128D01*
X4347108Y1543045D01*
X4346953Y1540962D01*
X4346333Y1539503D01*
X4345558Y1538253D01*
X4344628Y1537420D01*
X4343388Y1536795D01*
X4340288D01*
G01X4359198D02*
X4352998D01*
Y1549295D01*
X4359198D01*
G01X4356718Y1543253D02*
X4352998D01*
G01X4365398Y1536795D02*
Y1549295D01*
X4369118D01*
X4370358Y1548670D01*
X4371288Y1547212D01*
X4371598Y1545545D01*
X4371288Y1543878D01*
X4370513Y1542628D01*
X4369118Y1542003D01*
X4365398D01*
G01X4380898Y1549295D02*
Y1536795D01*
G01X4377333Y1549295D02*
X4384463D01*
G01X4390043Y1536795D02*
Y1549295D01*
G01X4396553D02*
Y1536795D01*
G01Y1543045D02*
X4390043D01*
G01X4405698Y1536378D02*
X4405388Y1536587D01*
Y1537003D01*
X4405698Y1537212D01*
X4406008Y1537003D01*
Y1536587D01*
X4405698Y1536378D01*
G01Y1542003D02*
X4405388Y1542212D01*
Y1542628D01*
X4405698Y1542837D01*
X4406008Y1542628D01*
Y1542212D01*
X4405698Y1542003D01*
G01X4427088Y1536795D02*
Y1549295D01*
X4430188D01*
X4431428Y1548670D01*
X4432358Y1547837D01*
X4433133Y1546587D01*
X4433753Y1545128D01*
X4433908Y1543045D01*
X4433753Y1540962D01*
X4433133Y1539503D01*
X4432358Y1538253D01*
X4431428Y1537420D01*
X4430188Y1536795D01*
X4427088D01*
G01X4445998D02*
X4439798D01*
Y1549295D01*
X4445998D01*
G01X4443518Y1543253D02*
X4439798D01*
G01X4452198Y1536795D02*
Y1549295D01*
X4455918D01*
X4457158Y1548670D01*
X4458088Y1547212D01*
X4458398Y1545545D01*
X4458088Y1543878D01*
X4457313Y1542628D01*
X4455918Y1542003D01*
X4452198D01*
G01X4467698Y1549295D02*
Y1536795D01*
G01X4464133Y1549295D02*
X4471263D01*
G01X4476843Y1536795D02*
Y1549295D01*
G01X4483353D02*
Y1536795D01*
G01Y1543045D02*
X4476843D01*
G01X4501953Y1536795D02*
Y1549295D01*
X4507843D01*
G01X4505673Y1543253D02*
X4501953D01*
G01X4514198Y1536795D02*
Y1549295D01*
X4518073D01*
X4519313Y1548670D01*
X4520088Y1547837D01*
X4520398Y1546170D01*
X4520088Y1544503D01*
X4519158Y1543462D01*
X4518073Y1542837D01*
X4514198D01*
G01X4518073D02*
X4520398Y1536795D01*
G01X4529698D02*
X4528458Y1537003D01*
X4527373Y1537836D01*
X4526443Y1539087D01*
X4525823Y1540545D01*
X4525513Y1542212D01*
Y1543878D01*
X4525823Y1545545D01*
X4526443Y1547003D01*
X4527373Y1548253D01*
X4528458Y1549087D01*
X4529698Y1549295D01*
X4530938Y1549087D01*
X4532023Y1548253D01*
X4532953Y1547003D01*
X4533573Y1545545D01*
X4533883Y1543878D01*
Y1542212D01*
X4533573Y1540545D01*
X4532953Y1539087D01*
X4532023Y1537836D01*
X4530938Y1537003D01*
X4529698Y1536795D01*
G01X4538068D02*
Y1549295D01*
X4542098Y1538878D01*
X4546128Y1549295D01*
Y1536795D01*
G01X4563643Y1538461D02*
X4564883Y1537420D01*
X4566278Y1536795D01*
X4567518D01*
X4568758Y1537420D01*
X4569688Y1538461D01*
X4570153Y1539920D01*
X4569843Y1541378D01*
X4569068Y1542628D01*
X4567673Y1543462D01*
X4565813Y1543878D01*
X4564728Y1544712D01*
X4564263Y1546170D01*
X4564573Y1547628D01*
X4565348Y1548670D01*
X4566433Y1549295D01*
X4567518D01*
X4568603Y1548878D01*
X4569533Y1547837D01*
G01X4579298Y1549295D02*
Y1536795D01*
G01X4575733Y1549295D02*
X4582863D01*
G01X4587823Y1536795D02*
X4591698Y1549295D01*
X4595573Y1536795D01*
G01X4594178Y1541170D02*
X4589218D01*
G01X4600998Y1536795D02*
Y1549295D01*
X4604873D01*
X4606113Y1548670D01*
X4606888Y1547837D01*
X4607198Y1546170D01*
X4606888Y1544503D01*
X4605958Y1543462D01*
X4604873Y1542837D01*
X4600998D01*
G01X4604873D02*
X4607198Y1536795D01*
G01X4616498Y1549295D02*
Y1536795D01*
G01X4612933Y1549295D02*
X4620063D01*
G01X4638198D02*
Y1536795D01*
X4644398D01*
G01X4649823D02*
X4653698Y1549295D01*
X4657573Y1536795D01*
G01X4656178Y1541170D02*
X4651218D01*
G01X4666098Y1536795D02*
Y1542420D01*
X4662998Y1549295D01*
G01X4669198D02*
X4666098Y1542420D01*
G01X4681598Y1536795D02*
X4675398D01*
Y1549295D01*
X4681598D01*
G01X4679118Y1543253D02*
X4675398D01*
G01X4687798Y1536795D02*
Y1549295D01*
X4691673D01*
X4692913Y1548670D01*
X4693688Y1547837D01*
X4693998Y1546170D01*
X4693688Y1544503D01*
X4692758Y1543462D01*
X4691673Y1542837D01*
X4687798D01*
G01X4691673D02*
X4693998Y1536795D01*
G01X4715698Y1549295D02*
Y1536795D01*
G01X4712133Y1549295D02*
X4719263D01*
G01X4728098Y1536795D02*
X4726858Y1537003D01*
X4725773Y1537836D01*
X4724843Y1539087D01*
X4724223Y1540545D01*
X4723913Y1542212D01*
Y1543878D01*
X4724223Y1545545D01*
X4724843Y1547003D01*
X4725773Y1548253D01*
X4726858Y1549087D01*
X4728098Y1549295D01*
X4729338Y1549087D01*
X4730423Y1548253D01*
X4731353Y1547003D01*
X4731973Y1545545D01*
X4732283Y1543878D01*
Y1542212D01*
X4731973Y1540545D01*
X4731353Y1539087D01*
X4730423Y1537836D01*
X4729338Y1537003D01*
X4728098Y1536795D01*
G01X4752898Y1549295D02*
Y1536795D01*
G01X4749333Y1549295D02*
X4756463D01*
G01X4762043Y1536795D02*
Y1549295D01*
G01X4768553D02*
Y1536795D01*
G01Y1543045D02*
X4762043D01*
G01X4780798Y1536795D02*
X4774598D01*
Y1549295D01*
X4780798D01*
G01X4778318Y1543253D02*
X4774598D01*
G01X4267283Y1559712D02*
X4271313D01*
G01X4290068Y1555545D02*
Y1568045D01*
X4294098Y1557628D01*
X4298128Y1568045D01*
Y1555545D01*
G01X4302933D02*
Y1568045D01*
X4310063Y1555545D01*
Y1568045D01*
G01X4322308Y1567003D02*
X4321378Y1567628D01*
X4320293Y1568045D01*
X4319053D01*
X4317658Y1567420D01*
X4316573Y1566378D01*
X4315798Y1565128D01*
X4315178Y1563045D01*
X4315023Y1561170D01*
X4315333Y1559295D01*
X4315798Y1558045D01*
X4316728Y1556795D01*
X4317813Y1555962D01*
X4318898Y1555545D01*
X4319983D01*
X4321068Y1555962D01*
X4321998Y1556586D01*
X4322773Y1557420D01*
G01X4326648Y1551378D02*
X4335948D01*
G01X4340598Y1568045D02*
Y1555545D01*
X4346798D01*
G01X4352223D02*
X4356098Y1568045D01*
X4359973Y1555545D01*
G01X4358578Y1559920D02*
X4353618D01*
G01X4368498Y1555545D02*
Y1561170D01*
X4365398Y1568045D01*
G01X4371598D02*
X4368498Y1561170D01*
G01X4383998Y1555545D02*
X4377798D01*
Y1568045D01*
X4383998D01*
G01X4381518Y1562003D02*
X4377798D01*
G01X4390198Y1555545D02*
Y1568045D01*
X4394073D01*
X4395313Y1567420D01*
X4396088Y1566587D01*
X4396398Y1564920D01*
X4396088Y1563253D01*
X4395158Y1562212D01*
X4394073Y1561587D01*
X4390198D01*
G01X4394073D02*
X4396398Y1555545D01*
G01X4405698Y1555128D02*
X4405388Y1555337D01*
Y1555753D01*
X4405698Y1555962D01*
X4406008Y1555753D01*
Y1555337D01*
X4405698Y1555128D01*
G01Y1560753D02*
X4405388Y1560962D01*
Y1561378D01*
X4405698Y1561587D01*
X4406008Y1561378D01*
Y1560962D01*
X4405698Y1560753D01*
G01X4426468Y1555545D02*
Y1568045D01*
X4430498Y1557628D01*
X4434528Y1568045D01*
Y1555545D01*
G01X4439488Y1568045D02*
Y1559087D01*
X4440108Y1557211D01*
X4441348Y1555962D01*
X4442898Y1555545D01*
X4444448Y1555962D01*
X4445688Y1557211D01*
X4446308Y1559087D01*
Y1568045D01*
G01X4452043Y1557211D02*
X4453283Y1556170D01*
X4454678Y1555545D01*
X4455918D01*
X4457158Y1556170D01*
X4458088Y1557211D01*
X4458553Y1558670D01*
X4458243Y1560128D01*
X4457468Y1561378D01*
X4456073Y1562212D01*
X4454213Y1562628D01*
X4453128Y1563462D01*
X4452663Y1564920D01*
X4452973Y1566378D01*
X4453748Y1567420D01*
X4454833Y1568045D01*
X4455918D01*
X4457003Y1567628D01*
X4457933Y1566587D01*
G01X4467698Y1568045D02*
Y1555545D01*
G01X4464133Y1568045D02*
X4471263D01*
G01X4478083Y1559712D02*
X4482113D01*
G01X4488933Y1555545D02*
Y1568045D01*
X4496063Y1555545D01*
Y1568045D01*
G01X4504898Y1555545D02*
X4503658Y1555753D01*
X4502573Y1556586D01*
X4501643Y1557837D01*
X4501023Y1559295D01*
X4500713Y1560962D01*
Y1562628D01*
X4501023Y1564295D01*
X4501643Y1565753D01*
X4502573Y1567003D01*
X4503658Y1567837D01*
X4504898Y1568045D01*
X4506138Y1567837D01*
X4507223Y1567003D01*
X4508153Y1565753D01*
X4508773Y1564295D01*
X4509083Y1562628D01*
Y1560962D01*
X4508773Y1559295D01*
X4508153Y1557837D01*
X4507223Y1556586D01*
X4506138Y1555753D01*
X4504898Y1555545D01*
G01X4517298Y1568045D02*
Y1555545D01*
G01X4513733Y1568045D02*
X4520863D01*
G01X4527683Y1559712D02*
X4531713D01*
G01X4545508Y1567003D02*
X4544578Y1567628D01*
X4543493Y1568045D01*
X4542253D01*
X4540858Y1567420D01*
X4539773Y1566378D01*
X4538998Y1565128D01*
X4538378Y1563045D01*
X4538223Y1561170D01*
X4538533Y1559295D01*
X4538998Y1558045D01*
X4539928Y1556795D01*
X4541013Y1555962D01*
X4542098Y1555545D01*
X4543183D01*
X4544268Y1555962D01*
X4545198Y1556586D01*
X4545973Y1557420D01*
G01X4551088Y1568045D02*
Y1559087D01*
X4551708Y1557211D01*
X4552948Y1555962D01*
X4554498Y1555545D01*
X4556048Y1555962D01*
X4557288Y1557211D01*
X4557908Y1559087D01*
Y1568045D01*
G01X4566898D02*
Y1555545D01*
G01X4563333Y1568045D02*
X4570463D01*
G01X4577283Y1559712D02*
X4581313D01*
G01X4588598Y1568045D02*
Y1555545D01*
X4594798D01*
G01X4600223D02*
X4604098Y1568045D01*
X4607973Y1555545D01*
G01X4606578Y1559920D02*
X4601618D01*
G01X4616498Y1555545D02*
Y1561170D01*
X4613398Y1568045D01*
G01X4619598D02*
X4616498Y1561170D01*
G01X4631998Y1555545D02*
X4625798D01*
Y1568045D01*
X4631998D01*
G01X4629518Y1562003D02*
X4625798D01*
G01X4638198Y1555545D02*
Y1568045D01*
X4642073D01*
X4643313Y1567420D01*
X4644088Y1566587D01*
X4644398Y1564920D01*
X4644088Y1563253D01*
X4643158Y1562212D01*
X4642073Y1561587D01*
X4638198D01*
G01X4642073D02*
X4644398Y1555545D01*
G01X4265733Y1574295D02*
Y1586795D01*
X4272863Y1574295D01*
Y1586795D01*
G01X4281698Y1574295D02*
X4280458Y1574503D01*
X4279373Y1575336D01*
X4278443Y1576587D01*
X4277823Y1578045D01*
X4277513Y1579712D01*
Y1581378D01*
X4277823Y1583045D01*
X4278443Y1584503D01*
X4279373Y1585753D01*
X4280458Y1586587D01*
X4281698Y1586795D01*
X4282938Y1586587D01*
X4284023Y1585753D01*
X4284953Y1584503D01*
X4285573Y1583045D01*
X4285883Y1581378D01*
Y1579712D01*
X4285573Y1578045D01*
X4284953Y1576587D01*
X4284023Y1575336D01*
X4282938Y1574503D01*
X4281698Y1574295D01*
G01X4294098Y1586795D02*
Y1574295D01*
G01X4290533Y1586795D02*
X4297663D01*
G01X4309598Y1574295D02*
X4303398D01*
Y1586795D01*
X4309598D01*
G01X4307118Y1580753D02*
X4303398D01*
G01X4315643Y1575961D02*
X4316883Y1574920D01*
X4318278Y1574295D01*
X4319518D01*
X4320758Y1574920D01*
X4321688Y1575961D01*
X4322153Y1577420D01*
X4321843Y1578878D01*
X4321068Y1580128D01*
X4319673Y1580962D01*
X4317813Y1581378D01*
X4316728Y1582212D01*
X4316263Y1583670D01*
X4316573Y1585128D01*
X4317348Y1586170D01*
X4318433Y1586795D01*
X4319518D01*
X4320603Y1586378D01*
X4321533Y1585337D01*
G01X4331298Y1573878D02*
X4330988Y1574087D01*
Y1574503D01*
X4331298Y1574712D01*
X4331608Y1574503D01*
Y1574087D01*
X4331298Y1573878D01*
G01Y1579503D02*
X4330988Y1579712D01*
Y1580128D01*
X4331298Y1580337D01*
X4331608Y1580128D01*
Y1579712D01*
X4331298Y1579503D01*
G01X4272975Y1327606D02*
Y1340106D01*
X4278865D01*
G01X4276695Y1334064D02*
X4272975D01*
G01X4286460Y1340106D02*
X4290180D01*
G01X4288320D02*
Y1327606D01*
G01X4286460D02*
X4290180D01*
G01X4301650Y1333856D02*
X4304750D01*
Y1330106D01*
X4303820Y1328856D01*
X4302735Y1328023D01*
X4301185Y1327606D01*
X4299635Y1328023D01*
X4298550Y1328856D01*
X4297620Y1330106D01*
X4297000Y1331564D01*
X4296690Y1333231D01*
Y1334689D01*
X4297000Y1335939D01*
X4297620Y1337398D01*
X4298550Y1338648D01*
X4299480Y1339481D01*
X4300720Y1340106D01*
X4301805D01*
X4303045Y1339689D01*
X4303975Y1338856D01*
G01X4309710Y1340106D02*
Y1331148D01*
X4310330Y1329272D01*
X4311570Y1328023D01*
X4313120Y1327606D01*
X4314670Y1328023D01*
X4315910Y1329272D01*
X4316530Y1331148D01*
Y1340106D01*
G01X4322420Y1327606D02*
Y1340106D01*
X4326295D01*
X4327535Y1339481D01*
X4328310Y1338648D01*
X4328620Y1336981D01*
X4328310Y1335314D01*
X4327380Y1334273D01*
X4326295Y1333648D01*
X4322420D01*
G01X4326295D02*
X4328620Y1327606D01*
G01X4341020D02*
X4334820D01*
Y1340106D01*
X4341020D01*
G01X4338540Y1334064D02*
X4334820D01*
G01X4275653Y1643045D02*
Y1655545D01*
X4281543D01*
G01X4279373Y1649503D02*
X4275653D01*
G01X4289138Y1655545D02*
X4292858D01*
G01X4290998D02*
Y1643045D01*
G01X4289138D02*
X4292858D01*
G01X4304328Y1649295D02*
X4307428D01*
Y1645545D01*
X4306498Y1644295D01*
X4305413Y1643462D01*
X4303863Y1643045D01*
X4302313Y1643462D01*
X4301228Y1644295D01*
X4300298Y1645545D01*
X4299678Y1647003D01*
X4299368Y1648670D01*
Y1650128D01*
X4299678Y1651378D01*
X4300298Y1652837D01*
X4301228Y1654087D01*
X4302158Y1654920D01*
X4303398Y1655545D01*
X4304483D01*
X4305723Y1655128D01*
X4306653Y1654295D01*
G01X4312388Y1655545D02*
Y1646587D01*
X4313008Y1644711D01*
X4314248Y1643462D01*
X4315798Y1643045D01*
X4317348Y1643462D01*
X4318588Y1644711D01*
X4319208Y1646587D01*
Y1655545D01*
G01X4325098Y1643045D02*
Y1655545D01*
X4328973D01*
X4330213Y1654920D01*
X4330988Y1654087D01*
X4331298Y1652420D01*
X4330988Y1650753D01*
X4330058Y1649712D01*
X4328973Y1649087D01*
X4325098D01*
G01X4328973D02*
X4331298Y1643045D01*
G01X4343698D02*
X4337498D01*
Y1655545D01*
X4343698D01*
G01X4341218Y1649503D02*
X4337498D01*
G01X4377247Y-86668D02*
X4377867Y-86043D01*
X4378332Y-85002D01*
X4378642Y-83543D01*
X4378332Y-82293D01*
X4377712Y-81460D01*
X4376627Y-80835D01*
X4372442D01*
Y-93335D01*
X4377557D01*
X4378642Y-92502D01*
X4379262Y-91252D01*
X4379572Y-89793D01*
X4379262Y-88335D01*
X4378332Y-87085D01*
X4377247Y-86668D01*
X4372442D01*
G01X4384997Y-93335D02*
Y-80835D01*
X4388097D01*
X4389337Y-81460D01*
X4390267Y-82293D01*
X4391042Y-83543D01*
X4391662Y-85002D01*
X4391817Y-87085D01*
X4391662Y-89168D01*
X4391042Y-90627D01*
X4390267Y-91877D01*
X4389337Y-92710D01*
X4388097Y-93335D01*
X4384997D01*
G01X4396157Y-97502D02*
X4405457D01*
G01X4409952Y-91669D02*
X4411192Y-92710D01*
X4412587Y-93335D01*
X4413827D01*
X4415067Y-92710D01*
X4415997Y-91669D01*
X4416462Y-90210D01*
X4416152Y-88752D01*
X4415377Y-87502D01*
X4413982Y-86668D01*
X4412122Y-86252D01*
X4411037Y-85418D01*
X4410572Y-83960D01*
X4410882Y-82502D01*
X4411657Y-81460D01*
X4412742Y-80835D01*
X4413827D01*
X4414912Y-81252D01*
X4415842Y-82293D01*
G01X4423747Y-80835D02*
X4427467D01*
G01X4425607D02*
Y-93335D01*
G01X4423747D02*
X4427467D01*
G01X4435062Y-80835D02*
X4440952D01*
X4435062Y-93335D01*
X4440952D01*
G01X4453507D02*
X4447307D01*
Y-80835D01*
X4453507D01*
G01X4451027Y-86877D02*
X4447307D01*
G01X4371460Y170273D02*
X4372080Y170898D01*
X4372545Y171939D01*
X4372855Y173398D01*
X4372545Y174648D01*
X4371925Y175481D01*
X4370840Y176106D01*
X4366655D01*
Y163606D01*
X4371770D01*
X4372855Y164439D01*
X4373475Y165689D01*
X4373785Y167148D01*
X4373475Y168606D01*
X4372545Y169856D01*
X4371460Y170273D01*
X4366655D01*
G01X4379210Y163606D02*
Y176106D01*
X4382310D01*
X4383550Y175481D01*
X4384480Y174648D01*
X4385255Y173398D01*
X4385875Y171939D01*
X4386030Y169856D01*
X4385875Y167773D01*
X4385255Y166314D01*
X4384480Y165064D01*
X4383550Y164231D01*
X4382310Y163606D01*
X4379210D01*
G01X4390370Y159439D02*
X4399670D01*
G01X4404165Y165272D02*
X4405405Y164231D01*
X4406800Y163606D01*
X4408040D01*
X4409280Y164231D01*
X4410210Y165272D01*
X4410675Y166731D01*
X4410365Y168189D01*
X4409590Y169439D01*
X4408195Y170273D01*
X4406335Y170689D01*
X4405250Y171523D01*
X4404785Y172981D01*
X4405095Y174439D01*
X4405870Y175481D01*
X4406955Y176106D01*
X4408040D01*
X4409125Y175689D01*
X4410055Y174648D01*
G01X4417960Y176106D02*
X4421680D01*
G01X4419820D02*
Y163606D01*
G01X4417960D02*
X4421680D01*
G01X4429275Y176106D02*
X4435165D01*
X4429275Y163606D01*
X4435165D01*
G01X4447720D02*
X4441520D01*
Y176106D01*
X4447720D01*
G01X4445240Y170064D02*
X4441520D01*
G01X4374960Y441273D02*
X4375580Y441898D01*
X4376045Y442939D01*
X4376355Y444398D01*
X4376045Y445648D01*
X4375425Y446481D01*
X4374340Y447106D01*
X4370155D01*
Y434606D01*
X4375270D01*
X4376355Y435439D01*
X4376975Y436689D01*
X4377285Y438148D01*
X4376975Y439606D01*
X4376045Y440856D01*
X4374960Y441273D01*
X4370155D01*
G01X4382710Y434606D02*
Y447106D01*
X4385810D01*
X4387050Y446481D01*
X4387980Y445648D01*
X4388755Y444398D01*
X4389375Y442939D01*
X4389530Y440856D01*
X4389375Y438773D01*
X4388755Y437314D01*
X4387980Y436064D01*
X4387050Y435231D01*
X4385810Y434606D01*
X4382710D01*
G01X4393870Y430439D02*
X4403170D01*
G01X4407665Y436272D02*
X4408905Y435231D01*
X4410300Y434606D01*
X4411540D01*
X4412780Y435231D01*
X4413710Y436272D01*
X4414175Y437731D01*
X4413865Y439189D01*
X4413090Y440439D01*
X4411695Y441273D01*
X4409835Y441689D01*
X4408750Y442523D01*
X4408285Y443981D01*
X4408595Y445439D01*
X4409370Y446481D01*
X4410455Y447106D01*
X4411540D01*
X4412625Y446689D01*
X4413555Y445648D01*
G01X4421460Y447106D02*
X4425180D01*
G01X4423320D02*
Y434606D01*
G01X4421460D02*
X4425180D01*
G01X4432775Y447106D02*
X4438665D01*
X4432775Y434606D01*
X4438665D01*
G01X4451220D02*
X4445020D01*
Y447106D01*
X4451220D01*
G01X4448740Y441064D02*
X4445020D01*
G01X4375960Y713773D02*
X4376580Y714398D01*
X4377045Y715439D01*
X4377355Y716898D01*
X4377045Y718148D01*
X4376425Y718981D01*
X4375340Y719606D01*
X4371155D01*
Y707106D01*
X4376270D01*
X4377355Y707939D01*
X4377975Y709189D01*
X4378285Y710648D01*
X4377975Y712106D01*
X4377045Y713356D01*
X4375960Y713773D01*
X4371155D01*
G01X4383710Y707106D02*
Y719606D01*
X4386810D01*
X4388050Y718981D01*
X4388980Y718148D01*
X4389755Y716898D01*
X4390375Y715439D01*
X4390530Y713356D01*
X4390375Y711273D01*
X4389755Y709814D01*
X4388980Y708564D01*
X4388050Y707731D01*
X4386810Y707106D01*
X4383710D01*
G01X4394870Y702939D02*
X4404170D01*
G01X4408665Y708772D02*
X4409905Y707731D01*
X4411300Y707106D01*
X4412540D01*
X4413780Y707731D01*
X4414710Y708772D01*
X4415175Y710231D01*
X4414865Y711689D01*
X4414090Y712939D01*
X4412695Y713773D01*
X4410835Y714189D01*
X4409750Y715023D01*
X4409285Y716481D01*
X4409595Y717939D01*
X4410370Y718981D01*
X4411455Y719606D01*
X4412540D01*
X4413625Y719189D01*
X4414555Y718148D01*
G01X4422460Y719606D02*
X4426180D01*
G01X4424320D02*
Y707106D01*
G01X4422460D02*
X4426180D01*
G01X4433775Y719606D02*
X4439665D01*
X4433775Y707106D01*
X4439665D01*
G01X4452220D02*
X4446020D01*
Y719606D01*
X4452220D01*
G01X4449740Y713564D02*
X4446020D01*
G01X4374460Y1017773D02*
X4375080Y1018398D01*
X4375545Y1019439D01*
X4375855Y1020898D01*
X4375545Y1022148D01*
X4374925Y1022981D01*
X4373840Y1023606D01*
X4369655D01*
Y1011106D01*
X4374770D01*
X4375855Y1011939D01*
X4376475Y1013189D01*
X4376785Y1014648D01*
X4376475Y1016106D01*
X4375545Y1017356D01*
X4374460Y1017773D01*
X4369655D01*
G01X4382210Y1011106D02*
Y1023606D01*
X4385310D01*
X4386550Y1022981D01*
X4387480Y1022148D01*
X4388255Y1020898D01*
X4388875Y1019439D01*
X4389030Y1017356D01*
X4388875Y1015273D01*
X4388255Y1013814D01*
X4387480Y1012564D01*
X4386550Y1011731D01*
X4385310Y1011106D01*
X4382210D01*
G01X4393370Y1006939D02*
X4402670D01*
G01X4407165Y1012772D02*
X4408405Y1011731D01*
X4409800Y1011106D01*
X4411040D01*
X4412280Y1011731D01*
X4413210Y1012772D01*
X4413675Y1014231D01*
X4413365Y1015689D01*
X4412590Y1016939D01*
X4411195Y1017773D01*
X4409335Y1018189D01*
X4408250Y1019023D01*
X4407785Y1020481D01*
X4408095Y1021939D01*
X4408870Y1022981D01*
X4409955Y1023606D01*
X4411040D01*
X4412125Y1023189D01*
X4413055Y1022148D01*
G01X4420960Y1023606D02*
X4424680D01*
G01X4422820D02*
Y1011106D01*
G01X4420960D02*
X4424680D01*
G01X4432275Y1023606D02*
X4438165D01*
X4432275Y1011106D01*
X4438165D01*
G01X4450720D02*
X4444520D01*
Y1023606D01*
X4450720D01*
G01X4448240Y1017564D02*
X4444520D01*
G01X4379460Y1334273D02*
X4380080Y1334898D01*
X4380545Y1335939D01*
X4380855Y1337398D01*
X4380545Y1338648D01*
X4379925Y1339481D01*
X4378840Y1340106D01*
X4374655D01*
Y1327606D01*
X4379770D01*
X4380855Y1328439D01*
X4381475Y1329689D01*
X4381785Y1331148D01*
X4381475Y1332606D01*
X4380545Y1333856D01*
X4379460Y1334273D01*
X4374655D01*
G01X4387210Y1327606D02*
Y1340106D01*
X4390310D01*
X4391550Y1339481D01*
X4392480Y1338648D01*
X4393255Y1337398D01*
X4393875Y1335939D01*
X4394030Y1333856D01*
X4393875Y1331773D01*
X4393255Y1330314D01*
X4392480Y1329064D01*
X4391550Y1328231D01*
X4390310Y1327606D01*
X4387210D01*
G01X4398370Y1323439D02*
X4407670D01*
G01X4412165Y1329272D02*
X4413405Y1328231D01*
X4414800Y1327606D01*
X4416040D01*
X4417280Y1328231D01*
X4418210Y1329272D01*
X4418675Y1330731D01*
X4418365Y1332189D01*
X4417590Y1333439D01*
X4416195Y1334273D01*
X4414335Y1334689D01*
X4413250Y1335523D01*
X4412785Y1336981D01*
X4413095Y1338439D01*
X4413870Y1339481D01*
X4414955Y1340106D01*
X4416040D01*
X4417125Y1339689D01*
X4418055Y1338648D01*
G01X4425960Y1340106D02*
X4429680D01*
G01X4427820D02*
Y1327606D01*
G01X4425960D02*
X4429680D01*
G01X4437275Y1340106D02*
X4443165D01*
X4437275Y1327606D01*
X4443165D01*
G01X4455720D02*
X4449520D01*
Y1340106D01*
X4455720D01*
G01X4453240Y1334064D02*
X4449520D01*
G01X4385462Y-107918D02*
X4386392Y-106669D01*
X4387477Y-106043D01*
X4388717Y-105835D01*
X4390267Y-106252D01*
X4391352Y-107293D01*
X4391662Y-108543D01*
X4391507Y-109794D01*
X4390887Y-110835D01*
X4387787Y-112918D01*
X4386392Y-114377D01*
X4385462Y-116460D01*
X4385152Y-118335D01*
X4391662D01*
G01X4400807D02*
Y-105835D01*
X4398947Y-108335D01*
G01Y-118335D02*
X4402667D01*
G01X4413207Y-118752D02*
X4412897Y-118543D01*
Y-118127D01*
X4413207Y-117918D01*
X4413517Y-118127D01*
Y-118543D01*
X4413207Y-118752D01*
G01X4425607Y-118335D02*
Y-105835D01*
X4423747Y-108335D01*
G01Y-118335D02*
X4427467D01*
G01X4437697D02*
X4438007Y-115627D01*
X4438472Y-113335D01*
X4439092Y-111252D01*
X4439867Y-108960D01*
X4441107Y-105835D01*
X4434907D01*
G01X4388820Y138606D02*
Y151106D01*
X4386960Y148606D01*
G01Y138606D02*
X4390680D01*
G01X4400910D02*
X4401220Y141314D01*
X4401685Y143606D01*
X4402305Y145689D01*
X4403080Y147981D01*
X4404320Y151106D01*
X4398120D01*
G01X4413620Y138189D02*
X4413310Y138398D01*
Y138814D01*
X4413620Y139023D01*
X4413930Y138814D01*
Y138398D01*
X4413620Y138189D01*
G01X4426020Y151106D02*
X4424780Y150689D01*
X4423850Y149648D01*
X4423230Y148398D01*
X4422765Y146731D01*
X4422610Y144856D01*
X4422765Y142981D01*
X4423230Y141314D01*
X4423850Y140064D01*
X4424780Y139023D01*
X4426020Y138606D01*
X4427260Y139023D01*
X4428190Y140064D01*
X4428810Y141314D01*
X4429275Y142981D01*
X4429430Y144856D01*
X4429275Y146731D01*
X4428810Y148398D01*
X4428190Y149648D01*
X4427260Y150689D01*
X4426020Y151106D01*
G01X4392320Y409606D02*
Y422106D01*
X4390460Y419606D01*
G01Y409606D02*
X4394180D01*
G01X4404410D02*
X4404720Y412314D01*
X4405185Y414606D01*
X4405805Y416689D01*
X4406580Y418981D01*
X4407820Y422106D01*
X4401620D01*
G01X4417120Y409189D02*
X4416810Y409398D01*
Y409814D01*
X4417120Y410023D01*
X4417430Y409814D01*
Y409398D01*
X4417120Y409189D01*
G01X4429520Y422106D02*
X4428280Y421689D01*
X4427350Y420648D01*
X4426730Y419398D01*
X4426265Y417731D01*
X4426110Y415856D01*
X4426265Y413981D01*
X4426730Y412314D01*
X4427350Y411064D01*
X4428280Y410023D01*
X4429520Y409606D01*
X4430760Y410023D01*
X4431690Y411064D01*
X4432310Y412314D01*
X4432775Y413981D01*
X4432930Y415856D01*
X4432775Y417731D01*
X4432310Y419398D01*
X4431690Y420648D01*
X4430760Y421689D01*
X4429520Y422106D01*
G01X4393320Y682106D02*
Y694606D01*
X4391460Y692106D01*
G01Y682106D02*
X4395180D01*
G01X4405410D02*
X4405720Y684814D01*
X4406185Y687106D01*
X4406805Y689189D01*
X4407580Y691481D01*
X4408820Y694606D01*
X4402620D01*
G01X4418120Y681689D02*
X4417810Y681898D01*
Y682314D01*
X4418120Y682523D01*
X4418430Y682314D01*
Y681898D01*
X4418120Y681689D01*
G01X4430520Y694606D02*
X4429280Y694189D01*
X4428350Y693148D01*
X4427730Y691898D01*
X4427265Y690231D01*
X4427110Y688356D01*
X4427265Y686481D01*
X4427730Y684814D01*
X4428350Y683564D01*
X4429280Y682523D01*
X4430520Y682106D01*
X4431760Y682523D01*
X4432690Y683564D01*
X4433310Y684814D01*
X4433775Y686481D01*
X4433930Y688356D01*
X4433775Y690231D01*
X4433310Y691898D01*
X4432690Y693148D01*
X4431760Y694189D01*
X4430520Y694606D01*
G01X4391820Y986106D02*
Y998606D01*
X4389960Y996106D01*
G01Y986106D02*
X4393680D01*
G01X4403910D02*
X4404220Y988814D01*
X4404685Y991106D01*
X4405305Y993189D01*
X4406080Y995481D01*
X4407320Y998606D01*
X4401120D01*
G01X4416620Y985689D02*
X4416310Y985898D01*
Y986314D01*
X4416620Y986523D01*
X4416930Y986314D01*
Y985898D01*
X4416620Y985689D01*
G01X4429020Y998606D02*
X4427780Y998189D01*
X4426850Y997148D01*
X4426230Y995898D01*
X4425765Y994231D01*
X4425610Y992356D01*
X4425765Y990481D01*
X4426230Y988814D01*
X4426850Y987564D01*
X4427780Y986523D01*
X4429020Y986106D01*
X4430260Y986523D01*
X4431190Y987564D01*
X4431810Y988814D01*
X4432275Y990481D01*
X4432430Y992356D01*
X4432275Y994231D01*
X4431810Y995898D01*
X4431190Y997148D01*
X4430260Y998189D01*
X4429020Y998606D01*
G01X4382138Y1649712D02*
X4382758Y1650337D01*
X4383223Y1651378D01*
X4383533Y1652837D01*
X4383223Y1654087D01*
X4382603Y1654920D01*
X4381518Y1655545D01*
X4377333D01*
Y1643045D01*
X4382448D01*
X4383533Y1643878D01*
X4384153Y1645128D01*
X4384463Y1646587D01*
X4384153Y1648045D01*
X4383223Y1649295D01*
X4382138Y1649712D01*
X4377333D01*
G01X4389888Y1643045D02*
Y1655545D01*
X4392988D01*
X4394228Y1654920D01*
X4395158Y1654087D01*
X4395933Y1652837D01*
X4396553Y1651378D01*
X4396708Y1649295D01*
X4396553Y1647212D01*
X4395933Y1645753D01*
X4395158Y1644503D01*
X4394228Y1643670D01*
X4392988Y1643045D01*
X4389888D01*
G01X4401048Y1638878D02*
X4410348D01*
G01X4414843Y1644711D02*
X4416083Y1643670D01*
X4417478Y1643045D01*
X4418718D01*
X4419958Y1643670D01*
X4420888Y1644711D01*
X4421353Y1646170D01*
X4421043Y1647628D01*
X4420268Y1648878D01*
X4418873Y1649712D01*
X4417013Y1650128D01*
X4415928Y1650962D01*
X4415463Y1652420D01*
X4415773Y1653878D01*
X4416548Y1654920D01*
X4417633Y1655545D01*
X4418718D01*
X4419803Y1655128D01*
X4420733Y1654087D01*
G01X4428638Y1655545D02*
X4432358D01*
G01X4430498D02*
Y1643045D01*
G01X4428638D02*
X4432358D01*
G01X4439953Y1655545D02*
X4445843D01*
X4439953Y1643045D01*
X4445843D01*
G01X4458398D02*
X4452198D01*
Y1655545D01*
X4458398D01*
G01X4455918Y1649503D02*
X4452198D01*
G01X4396820Y1302606D02*
Y1315106D01*
X4394960Y1312606D01*
G01Y1302606D02*
X4398680D01*
G01X4408910D02*
X4409220Y1305314D01*
X4409685Y1307606D01*
X4410305Y1309689D01*
X4411080Y1311981D01*
X4412320Y1315106D01*
X4406120D01*
G01X4421620Y1302189D02*
X4421310Y1302398D01*
Y1302814D01*
X4421620Y1303023D01*
X4421930Y1302814D01*
Y1302398D01*
X4421620Y1302189D01*
G01X4434020Y1315106D02*
X4432780Y1314689D01*
X4431850Y1313648D01*
X4431230Y1312398D01*
X4430765Y1310731D01*
X4430610Y1308856D01*
X4430765Y1306981D01*
X4431230Y1305314D01*
X4431850Y1304064D01*
X4432780Y1303023D01*
X4434020Y1302606D01*
X4435260Y1303023D01*
X4436190Y1304064D01*
X4436810Y1305314D01*
X4437275Y1306981D01*
X4437430Y1308856D01*
X4437275Y1310731D01*
X4436810Y1312398D01*
X4436190Y1313648D01*
X4435260Y1314689D01*
X4434020Y1315106D01*
G01X4399498Y1618045D02*
Y1630545D01*
X4397638Y1628045D01*
G01Y1618045D02*
X4401358D01*
G01X4411588D02*
X4411898Y1620753D01*
X4412363Y1623045D01*
X4412983Y1625128D01*
X4413758Y1627420D01*
X4414998Y1630545D01*
X4408798D01*
G01X4424298Y1617628D02*
X4423988Y1617837D01*
Y1618253D01*
X4424298Y1618462D01*
X4424608Y1618253D01*
Y1617837D01*
X4424298Y1617628D01*
G01X4436698Y1630545D02*
X4435458Y1630128D01*
X4434528Y1629087D01*
X4433908Y1627837D01*
X4433443Y1626170D01*
X4433288Y1624295D01*
X4433443Y1622420D01*
X4433908Y1620753D01*
X4434528Y1619503D01*
X4435458Y1618462D01*
X4436698Y1618045D01*
X4437938Y1618462D01*
X4438868Y1619503D01*
X4439488Y1620753D01*
X4439953Y1622420D01*
X4440108Y1624295D01*
X4439953Y1626170D01*
X4439488Y1627837D01*
X4438868Y1629087D01*
X4437938Y1630128D01*
X4436698Y1630545D01*
G01X4493497Y-36668D02*
X4494117Y-36043D01*
X4494582Y-35002D01*
X4494892Y-33543D01*
X4494582Y-32293D01*
X4493962Y-31460D01*
X4492877Y-30835D01*
X4488692D01*
Y-43335D01*
X4493807D01*
X4494892Y-42502D01*
X4495512Y-41252D01*
X4495822Y-39793D01*
X4495512Y-38335D01*
X4494582Y-37085D01*
X4493497Y-36668D01*
X4488692D01*
G01X4500782Y-43335D02*
X4504657Y-30835D01*
X4508532Y-43335D01*
G01X4507137Y-38960D02*
X4502177D01*
G01X4520467Y-31877D02*
X4519537Y-31252D01*
X4518452Y-30835D01*
X4517212D01*
X4515817Y-31460D01*
X4514732Y-32502D01*
X4513957Y-33752D01*
X4513337Y-35835D01*
X4513182Y-37710D01*
X4513492Y-39585D01*
X4513957Y-40835D01*
X4514887Y-42085D01*
X4515972Y-42918D01*
X4517057Y-43335D01*
X4518142D01*
X4519227Y-42918D01*
X4520157Y-42294D01*
X4520932Y-41460D01*
G01X4526047Y-43335D02*
Y-30835D01*
G01X4531937D02*
X4526047Y-38544D01*
G01X4532867Y-43335D02*
X4528682Y-35002D01*
G01X4538447Y-43335D02*
Y-30835D01*
X4541547D01*
X4542787Y-31460D01*
X4543717Y-32293D01*
X4544492Y-33543D01*
X4545112Y-35002D01*
X4545267Y-37085D01*
X4545112Y-39168D01*
X4544492Y-40627D01*
X4543717Y-41877D01*
X4542787Y-42710D01*
X4541547Y-43335D01*
X4538447D01*
G01X4551157D02*
Y-30835D01*
X4555032D01*
X4556272Y-31460D01*
X4557047Y-32293D01*
X4557357Y-33960D01*
X4557047Y-35627D01*
X4556117Y-36668D01*
X4555032Y-37293D01*
X4551157D01*
G01X4555032D02*
X4557357Y-43335D01*
G01X4564797Y-30835D02*
X4568517D01*
G01X4566657D02*
Y-43335D01*
G01X4564797D02*
X4568517D01*
G01X4575957Y-30835D02*
Y-43335D01*
X4582157D01*
G01X4588357Y-30835D02*
Y-43335D01*
X4594557D01*
G01X4603857Y-43752D02*
X4603547Y-43543D01*
Y-43127D01*
X4603857Y-42918D01*
X4604167Y-43127D01*
Y-43543D01*
X4603857Y-43752D01*
G01Y-38127D02*
X4603547Y-37918D01*
Y-37502D01*
X4603857Y-37293D01*
X4604167Y-37502D01*
Y-37918D01*
X4603857Y-38127D01*
G01X4629897Y-36668D02*
X4630517Y-36043D01*
X4630982Y-35002D01*
X4631292Y-33543D01*
X4630982Y-32293D01*
X4630362Y-31460D01*
X4629277Y-30835D01*
X4625092D01*
Y-43335D01*
X4630207D01*
X4631292Y-42502D01*
X4631912Y-41252D01*
X4632222Y-39793D01*
X4631912Y-38335D01*
X4630982Y-37085D01*
X4629897Y-36668D01*
X4625092D01*
G01X4641057Y-43335D02*
X4639817Y-43127D01*
X4638732Y-42294D01*
X4637802Y-41043D01*
X4637182Y-39585D01*
X4636872Y-37918D01*
Y-36252D01*
X4637182Y-34585D01*
X4637802Y-33127D01*
X4638732Y-31877D01*
X4639817Y-31043D01*
X4641057Y-30835D01*
X4642297Y-31043D01*
X4643382Y-31877D01*
X4644312Y-33127D01*
X4644932Y-34585D01*
X4645242Y-36252D01*
Y-37918D01*
X4644932Y-39585D01*
X4644312Y-41043D01*
X4643382Y-42294D01*
X4642297Y-43127D01*
X4641057Y-43335D01*
G01X4653457Y-30835D02*
Y-43335D01*
G01X4649892Y-30835D02*
X4657022D01*
G01X4665857D02*
Y-43335D01*
G01X4662292Y-30835D02*
X4669422D01*
G01X4678257Y-43335D02*
X4677017Y-43127D01*
X4675932Y-42294D01*
X4675002Y-41043D01*
X4674382Y-39585D01*
X4674072Y-37918D01*
Y-36252D01*
X4674382Y-34585D01*
X4675002Y-33127D01*
X4675932Y-31877D01*
X4677017Y-31043D01*
X4678257Y-30835D01*
X4679497Y-31043D01*
X4680582Y-31877D01*
X4681512Y-33127D01*
X4682132Y-34585D01*
X4682442Y-36252D01*
Y-37918D01*
X4682132Y-39585D01*
X4681512Y-41043D01*
X4680582Y-42294D01*
X4679497Y-43127D01*
X4678257Y-43335D01*
G01X4686627D02*
Y-30835D01*
X4690657Y-41252D01*
X4694687Y-30835D01*
Y-43335D01*
G01X4715457Y-30835D02*
Y-43335D01*
G01X4713287Y-35002D02*
X4717627D01*
G01X4727857Y-43335D02*
X4726927Y-43127D01*
X4725997Y-42294D01*
X4725377Y-40835D01*
X4725067Y-39168D01*
X4725377Y-37502D01*
X4725997Y-36043D01*
X4726927Y-35210D01*
X4727857Y-35002D01*
X4728787Y-35210D01*
X4729717Y-36043D01*
X4730337Y-37502D01*
X4730492Y-39168D01*
X4730337Y-40835D01*
X4729717Y-42294D01*
X4728787Y-43127D01*
X4727857Y-43335D01*
G01X4748782Y-30835D02*
X4752657Y-43335D01*
X4756532Y-30835D01*
G01X4768467Y-31877D02*
X4767537Y-31252D01*
X4766452Y-30835D01*
X4765212D01*
X4763817Y-31460D01*
X4762732Y-32502D01*
X4761957Y-33752D01*
X4761337Y-35835D01*
X4761182Y-37710D01*
X4761492Y-39585D01*
X4761957Y-40835D01*
X4762887Y-42085D01*
X4763972Y-42918D01*
X4765057Y-43335D01*
X4766142D01*
X4767227Y-42918D01*
X4768157Y-42294D01*
X4768932Y-41460D01*
G01X4780867Y-31877D02*
X4779937Y-31252D01*
X4778852Y-30835D01*
X4777612D01*
X4776217Y-31460D01*
X4775132Y-32502D01*
X4774357Y-33752D01*
X4773737Y-35835D01*
X4773582Y-37710D01*
X4773892Y-39585D01*
X4774357Y-40835D01*
X4775287Y-42085D01*
X4776372Y-42918D01*
X4777457Y-43335D01*
X4778542D01*
X4779627Y-42918D01*
X4780557Y-42294D01*
X4781332Y-41460D01*
G01X4500110Y220273D02*
X4500730Y220898D01*
X4501195Y221939D01*
X4501505Y223398D01*
X4501195Y224648D01*
X4500575Y225481D01*
X4499490Y226106D01*
X4495305D01*
Y213606D01*
X4500420D01*
X4501505Y214439D01*
X4502125Y215689D01*
X4502435Y217148D01*
X4502125Y218606D01*
X4501195Y219856D01*
X4500110Y220273D01*
X4495305D01*
G01X4507395Y213606D02*
X4511270Y226106D01*
X4515145Y213606D01*
G01X4513750Y217981D02*
X4508790D01*
G01X4527080Y225064D02*
X4526150Y225689D01*
X4525065Y226106D01*
X4523825D01*
X4522430Y225481D01*
X4521345Y224439D01*
X4520570Y223189D01*
X4519950Y221106D01*
X4519795Y219231D01*
X4520105Y217356D01*
X4520570Y216106D01*
X4521500Y214856D01*
X4522585Y214023D01*
X4523670Y213606D01*
X4524755D01*
X4525840Y214023D01*
X4526770Y214647D01*
X4527545Y215481D01*
G01X4532660Y213606D02*
Y226106D01*
G01X4538550D02*
X4532660Y218397D01*
G01X4539480Y213606D02*
X4535295Y221939D01*
G01X4545060Y213606D02*
Y226106D01*
X4548160D01*
X4549400Y225481D01*
X4550330Y224648D01*
X4551105Y223398D01*
X4551725Y221939D01*
X4551880Y219856D01*
X4551725Y217773D01*
X4551105Y216314D01*
X4550330Y215064D01*
X4549400Y214231D01*
X4548160Y213606D01*
X4545060D01*
G01X4557770D02*
Y226106D01*
X4561645D01*
X4562885Y225481D01*
X4563660Y224648D01*
X4563970Y222981D01*
X4563660Y221314D01*
X4562730Y220273D01*
X4561645Y219648D01*
X4557770D01*
G01X4561645D02*
X4563970Y213606D01*
G01X4571410Y226106D02*
X4575130D01*
G01X4573270D02*
Y213606D01*
G01X4571410D02*
X4575130D01*
G01X4582570Y226106D02*
Y213606D01*
X4588770D01*
G01X4594970Y226106D02*
Y213606D01*
X4601170D01*
G01X4610470Y213189D02*
X4610160Y213398D01*
Y213814D01*
X4610470Y214023D01*
X4610780Y213814D01*
Y213398D01*
X4610470Y213189D01*
G01Y218814D02*
X4610160Y219023D01*
Y219439D01*
X4610470Y219648D01*
X4610780Y219439D01*
Y219023D01*
X4610470Y218814D01*
G01X4635270Y226106D02*
Y213606D01*
G01X4631705Y226106D02*
X4638835D01*
G01X4647670Y213606D02*
X4646430Y213814D01*
X4645345Y214647D01*
X4644415Y215898D01*
X4643795Y217356D01*
X4643485Y219023D01*
Y220689D01*
X4643795Y222356D01*
X4644415Y223814D01*
X4645345Y225064D01*
X4646430Y225898D01*
X4647670Y226106D01*
X4648910Y225898D01*
X4649995Y225064D01*
X4650925Y223814D01*
X4651545Y222356D01*
X4651855Y220689D01*
Y219023D01*
X4651545Y217356D01*
X4650925Y215898D01*
X4649995Y214647D01*
X4648910Y213814D01*
X4647670Y213606D01*
G01X4656970D02*
Y226106D01*
X4660690D01*
X4661930Y225481D01*
X4662860Y224023D01*
X4663170Y222356D01*
X4662860Y220689D01*
X4662085Y219439D01*
X4660690Y218814D01*
X4656970D01*
G01X4684870Y226106D02*
Y213606D01*
G01X4682700Y221939D02*
X4687040D01*
G01X4697270Y213606D02*
X4696340Y213814D01*
X4695410Y214647D01*
X4694790Y216106D01*
X4694480Y217773D01*
X4694790Y219439D01*
X4695410Y220898D01*
X4696340Y221731D01*
X4697270Y221939D01*
X4698200Y221731D01*
X4699130Y220898D01*
X4699750Y219439D01*
X4699905Y217773D01*
X4699750Y216106D01*
X4699130Y214647D01*
X4698200Y213814D01*
X4697270Y213606D01*
G01X4723000Y219856D02*
X4726100D01*
Y216106D01*
X4725170Y214856D01*
X4724085Y214023D01*
X4722535Y213606D01*
X4720985Y214023D01*
X4719900Y214856D01*
X4718970Y216106D01*
X4718350Y217564D01*
X4718040Y219231D01*
Y220689D01*
X4718350Y221939D01*
X4718970Y223398D01*
X4719900Y224648D01*
X4720830Y225481D01*
X4722070Y226106D01*
X4723155D01*
X4724395Y225689D01*
X4725325Y224856D01*
G01X4730905Y213606D02*
Y226106D01*
X4738035Y213606D01*
Y226106D01*
G01X4743460Y213606D02*
Y226106D01*
X4746560D01*
X4747800Y225481D01*
X4748730Y224648D01*
X4749505Y223398D01*
X4750125Y221939D01*
X4750280Y219856D01*
X4750125Y217773D01*
X4749505Y216314D01*
X4748730Y215064D01*
X4747800Y214231D01*
X4746560Y213606D01*
X4743460D01*
G01X4756325Y218814D02*
X4757410Y220273D01*
X4758340Y221106D01*
X4759580Y221523D01*
X4760665Y221106D01*
X4761440Y220273D01*
X4762060Y219023D01*
X4762215Y217564D01*
X4762060Y216314D01*
X4761440Y215064D01*
X4760510Y214023D01*
X4759425Y213606D01*
X4758185Y214023D01*
X4757100Y215272D01*
X4756480Y217148D01*
X4756325Y219231D01*
X4756635Y221939D01*
X4757100Y223398D01*
X4757875Y224856D01*
X4758960Y225898D01*
X4760045Y226106D01*
X4761130Y225689D01*
X4761905Y224648D01*
G01X4506982Y-68335D02*
X4510857Y-55835D01*
X4514732Y-68335D01*
G01X4513337Y-63960D02*
X4508377D01*
G01X4520157Y-55835D02*
Y-68335D01*
X4526357D01*
G01X4532557Y-55835D02*
Y-68335D01*
X4538757D01*
G01X4557047Y-55835D02*
Y-64793D01*
X4557667Y-66669D01*
X4558907Y-67918D01*
X4560457Y-68335D01*
X4562007Y-67918D01*
X4563247Y-66669D01*
X4563867Y-64793D01*
Y-55835D01*
G01X4569292Y-68335D02*
Y-55835D01*
X4576422Y-68335D01*
Y-55835D01*
G01X4583397D02*
X4587117D01*
G01X4585257D02*
Y-68335D01*
G01X4583397D02*
X4587117D01*
G01X4597657Y-55835D02*
Y-68335D01*
G01X4594092Y-55835D02*
X4601222D01*
G01X4606802Y-66669D02*
X4608042Y-67710D01*
X4609437Y-68335D01*
X4610677D01*
X4611917Y-67710D01*
X4612847Y-66669D01*
X4613312Y-65210D01*
X4613002Y-63752D01*
X4612227Y-62502D01*
X4610832Y-61668D01*
X4608972Y-61252D01*
X4607887Y-60418D01*
X4607422Y-58960D01*
X4607732Y-57502D01*
X4608507Y-56460D01*
X4609592Y-55835D01*
X4610677D01*
X4611762Y-56252D01*
X4612692Y-57293D01*
G01X4630982Y-68335D02*
X4634857Y-55835D01*
X4638732Y-68335D01*
G01X4637337Y-63960D02*
X4632377D01*
G01X4644157Y-68335D02*
Y-55835D01*
X4648032D01*
X4649272Y-56460D01*
X4650047Y-57293D01*
X4650357Y-58960D01*
X4650047Y-60627D01*
X4649117Y-61668D01*
X4648032Y-62293D01*
X4644157D01*
G01X4648032D02*
X4650357Y-68335D01*
G01X4662757D02*
X4656557D01*
Y-55835D01*
X4662757D01*
G01X4660277Y-61877D02*
X4656557D01*
G01X4682597Y-55835D02*
X4686317D01*
G01X4684457D02*
Y-68335D01*
G01X4682597D02*
X4686317D01*
G01X4693292D02*
Y-55835D01*
X4700422Y-68335D01*
Y-55835D01*
G01X4717627Y-68335D02*
Y-55835D01*
X4721657Y-66252D01*
X4725687Y-55835D01*
Y-68335D01*
G01X4732197Y-55835D02*
X4735917D01*
G01X4734057D02*
Y-68335D01*
G01X4732197D02*
X4735917D01*
G01X4743357Y-55835D02*
Y-68335D01*
X4749557D01*
G01X4755602Y-66669D02*
X4756842Y-67710D01*
X4758237Y-68335D01*
X4759477D01*
X4760717Y-67710D01*
X4761647Y-66669D01*
X4762112Y-65210D01*
X4761802Y-63752D01*
X4761027Y-62502D01*
X4759632Y-61668D01*
X4757772Y-61252D01*
X4756687Y-60418D01*
X4756222Y-58960D01*
X4756532Y-57502D01*
X4757307Y-56460D01*
X4758392Y-55835D01*
X4759477D01*
X4760562Y-56252D01*
X4761492Y-57293D01*
G01X4501195Y188606D02*
X4505070Y201106D01*
X4508945Y188606D01*
G01X4507550Y192981D02*
X4502590D01*
G01X4514370Y201106D02*
Y188606D01*
X4520570D01*
G01X4526770Y201106D02*
Y188606D01*
X4532970D01*
G01X4551260Y201106D02*
Y192148D01*
X4551880Y190272D01*
X4553120Y189023D01*
X4554670Y188606D01*
X4556220Y189023D01*
X4557460Y190272D01*
X4558080Y192148D01*
Y201106D01*
G01X4563505Y188606D02*
Y201106D01*
X4570635Y188606D01*
Y201106D01*
G01X4577610D02*
X4581330D01*
G01X4579470D02*
Y188606D01*
G01X4577610D02*
X4581330D01*
G01X4591870Y201106D02*
Y188606D01*
G01X4588305Y201106D02*
X4595435D01*
G01X4601015Y190272D02*
X4602255Y189231D01*
X4603650Y188606D01*
X4604890D01*
X4606130Y189231D01*
X4607060Y190272D01*
X4607525Y191731D01*
X4607215Y193189D01*
X4606440Y194439D01*
X4605045Y195273D01*
X4603185Y195689D01*
X4602100Y196523D01*
X4601635Y197981D01*
X4601945Y199439D01*
X4602720Y200481D01*
X4603805Y201106D01*
X4604890D01*
X4605975Y200689D01*
X4606905Y199648D01*
G01X4625195Y188606D02*
X4629070Y201106D01*
X4632945Y188606D01*
G01X4631550Y192981D02*
X4626590D01*
G01X4638370Y188606D02*
Y201106D01*
X4642245D01*
X4643485Y200481D01*
X4644260Y199648D01*
X4644570Y197981D01*
X4644260Y196314D01*
X4643330Y195273D01*
X4642245Y194648D01*
X4638370D01*
G01X4642245D02*
X4644570Y188606D01*
G01X4656970D02*
X4650770D01*
Y201106D01*
X4656970D01*
G01X4654490Y195064D02*
X4650770D01*
G01X4676810Y201106D02*
X4680530D01*
G01X4678670D02*
Y188606D01*
G01X4676810D02*
X4680530D01*
G01X4687505D02*
Y201106D01*
X4694635Y188606D01*
Y201106D01*
G01X4711840Y188606D02*
Y201106D01*
X4715870Y190689D01*
X4719900Y201106D01*
Y188606D01*
G01X4726410Y201106D02*
X4730130D01*
G01X4728270D02*
Y188606D01*
G01X4726410D02*
X4730130D01*
G01X4737570Y201106D02*
Y188606D01*
X4743770D01*
G01X4749815Y190272D02*
X4751055Y189231D01*
X4752450Y188606D01*
X4753690D01*
X4754930Y189231D01*
X4755860Y190272D01*
X4756325Y191731D01*
X4756015Y193189D01*
X4755240Y194439D01*
X4753845Y195273D01*
X4751985Y195689D01*
X4750900Y196523D01*
X4750435Y197981D01*
X4750745Y199439D01*
X4751520Y200481D01*
X4752605Y201106D01*
X4753690D01*
X4754775Y200689D01*
X4755705Y199648D01*
G01X4504695Y459606D02*
X4508570Y472106D01*
X4512445Y459606D01*
G01X4511050Y463981D02*
X4506090D01*
G01X4517870Y472106D02*
Y459606D01*
X4524070D01*
G01X4530270Y472106D02*
Y459606D01*
X4536470D01*
G01X4554760Y472106D02*
Y463148D01*
X4555380Y461272D01*
X4556620Y460023D01*
X4558170Y459606D01*
X4559720Y460023D01*
X4560960Y461272D01*
X4561580Y463148D01*
Y472106D01*
G01X4567005Y459606D02*
Y472106D01*
X4574135Y459606D01*
Y472106D01*
G01X4581110D02*
X4584830D01*
G01X4582970D02*
Y459606D01*
G01X4581110D02*
X4584830D01*
G01X4595370Y472106D02*
Y459606D01*
G01X4591805Y472106D02*
X4598935D01*
G01X4604515Y461272D02*
X4605755Y460231D01*
X4607150Y459606D01*
X4608390D01*
X4609630Y460231D01*
X4610560Y461272D01*
X4611025Y462731D01*
X4610715Y464189D01*
X4609940Y465439D01*
X4608545Y466273D01*
X4606685Y466689D01*
X4605600Y467523D01*
X4605135Y468981D01*
X4605445Y470439D01*
X4606220Y471481D01*
X4607305Y472106D01*
X4608390D01*
X4609475Y471689D01*
X4610405Y470648D01*
G01X4628695Y459606D02*
X4632570Y472106D01*
X4636445Y459606D01*
G01X4635050Y463981D02*
X4630090D01*
G01X4641870Y459606D02*
Y472106D01*
X4645745D01*
X4646985Y471481D01*
X4647760Y470648D01*
X4648070Y468981D01*
X4647760Y467314D01*
X4646830Y466273D01*
X4645745Y465648D01*
X4641870D01*
G01X4645745D02*
X4648070Y459606D01*
G01X4660470D02*
X4654270D01*
Y472106D01*
X4660470D01*
G01X4657990Y466064D02*
X4654270D01*
G01X4680310Y472106D02*
X4684030D01*
G01X4682170D02*
Y459606D01*
G01X4680310D02*
X4684030D01*
G01X4691005D02*
Y472106D01*
X4698135Y459606D01*
Y472106D01*
G01X4715340Y459606D02*
Y472106D01*
X4719370Y461689D01*
X4723400Y472106D01*
Y459606D01*
G01X4729910Y472106D02*
X4733630D01*
G01X4731770D02*
Y459606D01*
G01X4729910D02*
X4733630D01*
G01X4741070Y472106D02*
Y459606D01*
X4747270D01*
G01X4753315Y461272D02*
X4754555Y460231D01*
X4755950Y459606D01*
X4757190D01*
X4758430Y460231D01*
X4759360Y461272D01*
X4759825Y462731D01*
X4759515Y464189D01*
X4758740Y465439D01*
X4757345Y466273D01*
X4755485Y466689D01*
X4754400Y467523D01*
X4753935Y468981D01*
X4754245Y470439D01*
X4755020Y471481D01*
X4756105Y472106D01*
X4757190D01*
X4758275Y471689D01*
X4759205Y470648D01*
G01X4503610Y491273D02*
X4504230Y491898D01*
X4504695Y492939D01*
X4505005Y494398D01*
X4504695Y495648D01*
X4504075Y496481D01*
X4502990Y497106D01*
X4498805D01*
Y484606D01*
X4503920D01*
X4505005Y485439D01*
X4505625Y486689D01*
X4505935Y488148D01*
X4505625Y489606D01*
X4504695Y490856D01*
X4503610Y491273D01*
X4498805D01*
G01X4510895Y484606D02*
X4514770Y497106D01*
X4518645Y484606D01*
G01X4517250Y488981D02*
X4512290D01*
G01X4530580Y496064D02*
X4529650Y496689D01*
X4528565Y497106D01*
X4527325D01*
X4525930Y496481D01*
X4524845Y495439D01*
X4524070Y494189D01*
X4523450Y492106D01*
X4523295Y490231D01*
X4523605Y488356D01*
X4524070Y487106D01*
X4525000Y485856D01*
X4526085Y485023D01*
X4527170Y484606D01*
X4528255D01*
X4529340Y485023D01*
X4530270Y485647D01*
X4531045Y486481D01*
G01X4536160Y484606D02*
Y497106D01*
G01X4542050D02*
X4536160Y489397D01*
G01X4542980Y484606D02*
X4538795Y492939D01*
G01X4548560Y484606D02*
Y497106D01*
X4551660D01*
X4552900Y496481D01*
X4553830Y495648D01*
X4554605Y494398D01*
X4555225Y492939D01*
X4555380Y490856D01*
X4555225Y488773D01*
X4554605Y487314D01*
X4553830Y486064D01*
X4552900Y485231D01*
X4551660Y484606D01*
X4548560D01*
G01X4561270D02*
Y497106D01*
X4565145D01*
X4566385Y496481D01*
X4567160Y495648D01*
X4567470Y493981D01*
X4567160Y492314D01*
X4566230Y491273D01*
X4565145Y490648D01*
X4561270D01*
G01X4565145D02*
X4567470Y484606D01*
G01X4574910Y497106D02*
X4578630D01*
G01X4576770D02*
Y484606D01*
G01X4574910D02*
X4578630D01*
G01X4586070Y497106D02*
Y484606D01*
X4592270D01*
G01X4598470Y497106D02*
Y484606D01*
X4604670D01*
G01X4613970Y484189D02*
X4613660Y484398D01*
Y484814D01*
X4613970Y485023D01*
X4614280Y484814D01*
Y484398D01*
X4613970Y484189D01*
G01Y489814D02*
X4613660Y490023D01*
Y490439D01*
X4613970Y490648D01*
X4614280Y490439D01*
Y490023D01*
X4613970Y489814D01*
G01X4638770Y497106D02*
Y484606D01*
G01X4635205Y497106D02*
X4642335D01*
G01X4651170Y484606D02*
X4649930Y484814D01*
X4648845Y485647D01*
X4647915Y486898D01*
X4647295Y488356D01*
X4646985Y490023D01*
Y491689D01*
X4647295Y493356D01*
X4647915Y494814D01*
X4648845Y496064D01*
X4649930Y496898D01*
X4651170Y497106D01*
X4652410Y496898D01*
X4653495Y496064D01*
X4654425Y494814D01*
X4655045Y493356D01*
X4655355Y491689D01*
Y490023D01*
X4655045Y488356D01*
X4654425Y486898D01*
X4653495Y485647D01*
X4652410Y484814D01*
X4651170Y484606D01*
G01X4660470D02*
Y497106D01*
X4664190D01*
X4665430Y496481D01*
X4666360Y495023D01*
X4666670Y493356D01*
X4666360Y491689D01*
X4665585Y490439D01*
X4664190Y489814D01*
X4660470D01*
G01X4688370Y497106D02*
Y484606D01*
G01X4686200Y492939D02*
X4690540D01*
G01X4700770Y484606D02*
X4699840Y484814D01*
X4698910Y485647D01*
X4698290Y487106D01*
X4697980Y488773D01*
X4698290Y490439D01*
X4698910Y491898D01*
X4699840Y492731D01*
X4700770Y492939D01*
X4701700Y492731D01*
X4702630Y491898D01*
X4703250Y490439D01*
X4703405Y488773D01*
X4703250Y487106D01*
X4702630Y485647D01*
X4701700Y484814D01*
X4700770Y484606D01*
G01X4726500Y490856D02*
X4729600D01*
Y487106D01*
X4728670Y485856D01*
X4727585Y485023D01*
X4726035Y484606D01*
X4724485Y485023D01*
X4723400Y485856D01*
X4722470Y487106D01*
X4721850Y488564D01*
X4721540Y490231D01*
Y491689D01*
X4721850Y492939D01*
X4722470Y494398D01*
X4723400Y495648D01*
X4724330Y496481D01*
X4725570Y497106D01*
X4726655D01*
X4727895Y496689D01*
X4728825Y495856D01*
G01X4734405Y484606D02*
Y497106D01*
X4741535Y484606D01*
Y497106D01*
G01X4746960Y484606D02*
Y497106D01*
X4750060D01*
X4751300Y496481D01*
X4752230Y495648D01*
X4753005Y494398D01*
X4753625Y492939D01*
X4753780Y490856D01*
X4753625Y488773D01*
X4753005Y487314D01*
X4752230Y486064D01*
X4751300Y485231D01*
X4750060Y484606D01*
X4746960D01*
G01X4759360Y486481D02*
X4760290Y485439D01*
X4761375Y484814D01*
X4762770Y484606D01*
X4764165Y485023D01*
X4765250Y485856D01*
X4766025Y487314D01*
X4766180Y488981D01*
X4765870Y490648D01*
X4765095Y491689D01*
X4764010Y492523D01*
X4762925Y492731D01*
X4761840Y492523D01*
X4760445Y491689D01*
X4760910Y497106D01*
X4765095D01*
G01X4505695Y732106D02*
X4509570Y744606D01*
X4513445Y732106D01*
G01X4512050Y736481D02*
X4507090D01*
G01X4518870Y744606D02*
Y732106D01*
X4525070D01*
G01X4531270Y744606D02*
Y732106D01*
X4537470D01*
G01X4555760Y744606D02*
Y735648D01*
X4556380Y733772D01*
X4557620Y732523D01*
X4559170Y732106D01*
X4560720Y732523D01*
X4561960Y733772D01*
X4562580Y735648D01*
Y744606D01*
G01X4568005Y732106D02*
Y744606D01*
X4575135Y732106D01*
Y744606D01*
G01X4582110D02*
X4585830D01*
G01X4583970D02*
Y732106D01*
G01X4582110D02*
X4585830D01*
G01X4596370Y744606D02*
Y732106D01*
G01X4592805Y744606D02*
X4599935D01*
G01X4605515Y733772D02*
X4606755Y732731D01*
X4608150Y732106D01*
X4609390D01*
X4610630Y732731D01*
X4611560Y733772D01*
X4612025Y735231D01*
X4611715Y736689D01*
X4610940Y737939D01*
X4609545Y738773D01*
X4607685Y739189D01*
X4606600Y740023D01*
X4606135Y741481D01*
X4606445Y742939D01*
X4607220Y743981D01*
X4608305Y744606D01*
X4609390D01*
X4610475Y744189D01*
X4611405Y743148D01*
G01X4629695Y732106D02*
X4633570Y744606D01*
X4637445Y732106D01*
G01X4636050Y736481D02*
X4631090D01*
G01X4642870Y732106D02*
Y744606D01*
X4646745D01*
X4647985Y743981D01*
X4648760Y743148D01*
X4649070Y741481D01*
X4648760Y739814D01*
X4647830Y738773D01*
X4646745Y738148D01*
X4642870D01*
G01X4646745D02*
X4649070Y732106D01*
G01X4661470D02*
X4655270D01*
Y744606D01*
X4661470D01*
G01X4658990Y738564D02*
X4655270D01*
G01X4681310Y744606D02*
X4685030D01*
G01X4683170D02*
Y732106D01*
G01X4681310D02*
X4685030D01*
G01X4692005D02*
Y744606D01*
X4699135Y732106D01*
Y744606D01*
G01X4716340Y732106D02*
Y744606D01*
X4720370Y734189D01*
X4724400Y744606D01*
Y732106D01*
G01X4730910Y744606D02*
X4734630D01*
G01X4732770D02*
Y732106D01*
G01X4730910D02*
X4734630D01*
G01X4742070Y744606D02*
Y732106D01*
X4748270D01*
G01X4754315Y733772D02*
X4755555Y732731D01*
X4756950Y732106D01*
X4758190D01*
X4759430Y732731D01*
X4760360Y733772D01*
X4760825Y735231D01*
X4760515Y736689D01*
X4759740Y737939D01*
X4758345Y738773D01*
X4756485Y739189D01*
X4755400Y740023D01*
X4754935Y741481D01*
X4755245Y742939D01*
X4756020Y743981D01*
X4757105Y744606D01*
X4758190D01*
X4759275Y744189D01*
X4760205Y743148D01*
G01X4504610Y763773D02*
X4505230Y764398D01*
X4505695Y765439D01*
X4506005Y766898D01*
X4505695Y768148D01*
X4505075Y768981D01*
X4503990Y769606D01*
X4499805D01*
Y757106D01*
X4504920D01*
X4506005Y757939D01*
X4506625Y759189D01*
X4506935Y760648D01*
X4506625Y762106D01*
X4505695Y763356D01*
X4504610Y763773D01*
X4499805D01*
G01X4511895Y757106D02*
X4515770Y769606D01*
X4519645Y757106D01*
G01X4518250Y761481D02*
X4513290D01*
G01X4531580Y768564D02*
X4530650Y769189D01*
X4529565Y769606D01*
X4528325D01*
X4526930Y768981D01*
X4525845Y767939D01*
X4525070Y766689D01*
X4524450Y764606D01*
X4524295Y762731D01*
X4524605Y760856D01*
X4525070Y759606D01*
X4526000Y758356D01*
X4527085Y757523D01*
X4528170Y757106D01*
X4529255D01*
X4530340Y757523D01*
X4531270Y758147D01*
X4532045Y758981D01*
G01X4537160Y757106D02*
Y769606D01*
G01X4543050D02*
X4537160Y761897D01*
G01X4543980Y757106D02*
X4539795Y765439D01*
G01X4549560Y757106D02*
Y769606D01*
X4552660D01*
X4553900Y768981D01*
X4554830Y768148D01*
X4555605Y766898D01*
X4556225Y765439D01*
X4556380Y763356D01*
X4556225Y761273D01*
X4555605Y759814D01*
X4554830Y758564D01*
X4553900Y757731D01*
X4552660Y757106D01*
X4549560D01*
G01X4562270D02*
Y769606D01*
X4566145D01*
X4567385Y768981D01*
X4568160Y768148D01*
X4568470Y766481D01*
X4568160Y764814D01*
X4567230Y763773D01*
X4566145Y763148D01*
X4562270D01*
G01X4566145D02*
X4568470Y757106D01*
G01X4575910Y769606D02*
X4579630D01*
G01X4577770D02*
Y757106D01*
G01X4575910D02*
X4579630D01*
G01X4587070Y769606D02*
Y757106D01*
X4593270D01*
G01X4599470Y769606D02*
Y757106D01*
X4605670D01*
G01X4614970Y756689D02*
X4614660Y756898D01*
Y757314D01*
X4614970Y757523D01*
X4615280Y757314D01*
Y756898D01*
X4614970Y756689D01*
G01Y762314D02*
X4614660Y762523D01*
Y762939D01*
X4614970Y763148D01*
X4615280Y762939D01*
Y762523D01*
X4614970Y762314D01*
G01X4639770Y769606D02*
Y757106D01*
G01X4636205Y769606D02*
X4643335D01*
G01X4652170Y757106D02*
X4650930Y757314D01*
X4649845Y758147D01*
X4648915Y759398D01*
X4648295Y760856D01*
X4647985Y762523D01*
Y764189D01*
X4648295Y765856D01*
X4648915Y767314D01*
X4649845Y768564D01*
X4650930Y769398D01*
X4652170Y769606D01*
X4653410Y769398D01*
X4654495Y768564D01*
X4655425Y767314D01*
X4656045Y765856D01*
X4656355Y764189D01*
Y762523D01*
X4656045Y760856D01*
X4655425Y759398D01*
X4654495Y758147D01*
X4653410Y757314D01*
X4652170Y757106D01*
G01X4661470D02*
Y769606D01*
X4665190D01*
X4666430Y768981D01*
X4667360Y767523D01*
X4667670Y765856D01*
X4667360Y764189D01*
X4666585Y762939D01*
X4665190Y762314D01*
X4661470D01*
G01X4689370Y769606D02*
Y757106D01*
G01X4687200Y765439D02*
X4691540D01*
G01X4701770Y757106D02*
X4700840Y757314D01*
X4699910Y758147D01*
X4699290Y759606D01*
X4698980Y761273D01*
X4699290Y762939D01*
X4699910Y764398D01*
X4700840Y765231D01*
X4701770Y765439D01*
X4702700Y765231D01*
X4703630Y764398D01*
X4704250Y762939D01*
X4704405Y761273D01*
X4704250Y759606D01*
X4703630Y758147D01*
X4702700Y757314D01*
X4701770Y757106D01*
G01X4727500Y763356D02*
X4730600D01*
Y759606D01*
X4729670Y758356D01*
X4728585Y757523D01*
X4727035Y757106D01*
X4725485Y757523D01*
X4724400Y758356D01*
X4723470Y759606D01*
X4722850Y761064D01*
X4722540Y762731D01*
Y764189D01*
X4722850Y765439D01*
X4723470Y766898D01*
X4724400Y768148D01*
X4725330Y768981D01*
X4726570Y769606D01*
X4727655D01*
X4728895Y769189D01*
X4729825Y768356D01*
G01X4735405Y757106D02*
Y769606D01*
X4742535Y757106D01*
Y769606D01*
G01X4747960Y757106D02*
Y769606D01*
X4751060D01*
X4752300Y768981D01*
X4753230Y768148D01*
X4754005Y766898D01*
X4754625Y765439D01*
X4754780Y763356D01*
X4754625Y761273D01*
X4754005Y759814D01*
X4753230Y758564D01*
X4752300Y757731D01*
X4751060Y757106D01*
X4747960D01*
G01X4765630D02*
Y769606D01*
X4759895Y760648D01*
X4767645D01*
G01X4504195Y1036106D02*
X4508070Y1048606D01*
X4511945Y1036106D01*
G01X4510550Y1040481D02*
X4505590D01*
G01X4517370Y1048606D02*
Y1036106D01*
X4523570D01*
G01X4529770Y1048606D02*
Y1036106D01*
X4535970D01*
G01X4554260Y1048606D02*
Y1039648D01*
X4554880Y1037772D01*
X4556120Y1036523D01*
X4557670Y1036106D01*
X4559220Y1036523D01*
X4560460Y1037772D01*
X4561080Y1039648D01*
Y1048606D01*
G01X4566505Y1036106D02*
Y1048606D01*
X4573635Y1036106D01*
Y1048606D01*
G01X4580610D02*
X4584330D01*
G01X4582470D02*
Y1036106D01*
G01X4580610D02*
X4584330D01*
G01X4594870Y1048606D02*
Y1036106D01*
G01X4591305Y1048606D02*
X4598435D01*
G01X4604015Y1037772D02*
X4605255Y1036731D01*
X4606650Y1036106D01*
X4607890D01*
X4609130Y1036731D01*
X4610060Y1037772D01*
X4610525Y1039231D01*
X4610215Y1040689D01*
X4609440Y1041939D01*
X4608045Y1042773D01*
X4606185Y1043189D01*
X4605100Y1044023D01*
X4604635Y1045481D01*
X4604945Y1046939D01*
X4605720Y1047981D01*
X4606805Y1048606D01*
X4607890D01*
X4608975Y1048189D01*
X4609905Y1047148D01*
G01X4628195Y1036106D02*
X4632070Y1048606D01*
X4635945Y1036106D01*
G01X4634550Y1040481D02*
X4629590D01*
G01X4641370Y1036106D02*
Y1048606D01*
X4645245D01*
X4646485Y1047981D01*
X4647260Y1047148D01*
X4647570Y1045481D01*
X4647260Y1043814D01*
X4646330Y1042773D01*
X4645245Y1042148D01*
X4641370D01*
G01X4645245D02*
X4647570Y1036106D01*
G01X4659970D02*
X4653770D01*
Y1048606D01*
X4659970D01*
G01X4657490Y1042564D02*
X4653770D01*
G01X4679810Y1048606D02*
X4683530D01*
G01X4681670D02*
Y1036106D01*
G01X4679810D02*
X4683530D01*
G01X4690505D02*
Y1048606D01*
X4697635Y1036106D01*
Y1048606D01*
G01X4714840Y1036106D02*
Y1048606D01*
X4718870Y1038189D01*
X4722900Y1048606D01*
Y1036106D01*
G01X4729410Y1048606D02*
X4733130D01*
G01X4731270D02*
Y1036106D01*
G01X4729410D02*
X4733130D01*
G01X4740570Y1048606D02*
Y1036106D01*
X4746770D01*
G01X4752815Y1037772D02*
X4754055Y1036731D01*
X4755450Y1036106D01*
X4756690D01*
X4757930Y1036731D01*
X4758860Y1037772D01*
X4759325Y1039231D01*
X4759015Y1040689D01*
X4758240Y1041939D01*
X4756845Y1042773D01*
X4754985Y1043189D01*
X4753900Y1044023D01*
X4753435Y1045481D01*
X4753745Y1046939D01*
X4754520Y1047981D01*
X4755605Y1048606D01*
X4756690D01*
X4757775Y1048189D01*
X4758705Y1047148D01*
G01X4503110Y1067773D02*
X4503730Y1068398D01*
X4504195Y1069439D01*
X4504505Y1070898D01*
X4504195Y1072148D01*
X4503575Y1072981D01*
X4502490Y1073606D01*
X4498305D01*
Y1061106D01*
X4503420D01*
X4504505Y1061939D01*
X4505125Y1063189D01*
X4505435Y1064648D01*
X4505125Y1066106D01*
X4504195Y1067356D01*
X4503110Y1067773D01*
X4498305D01*
G01X4510395Y1061106D02*
X4514270Y1073606D01*
X4518145Y1061106D01*
G01X4516750Y1065481D02*
X4511790D01*
G01X4530080Y1072564D02*
X4529150Y1073189D01*
X4528065Y1073606D01*
X4526825D01*
X4525430Y1072981D01*
X4524345Y1071939D01*
X4523570Y1070689D01*
X4522950Y1068606D01*
X4522795Y1066731D01*
X4523105Y1064856D01*
X4523570Y1063606D01*
X4524500Y1062356D01*
X4525585Y1061523D01*
X4526670Y1061106D01*
X4527755D01*
X4528840Y1061523D01*
X4529770Y1062147D01*
X4530545Y1062981D01*
G01X4535660Y1061106D02*
Y1073606D01*
G01X4541550D02*
X4535660Y1065897D01*
G01X4542480Y1061106D02*
X4538295Y1069439D01*
G01X4548060Y1061106D02*
Y1073606D01*
X4551160D01*
X4552400Y1072981D01*
X4553330Y1072148D01*
X4554105Y1070898D01*
X4554725Y1069439D01*
X4554880Y1067356D01*
X4554725Y1065273D01*
X4554105Y1063814D01*
X4553330Y1062564D01*
X4552400Y1061731D01*
X4551160Y1061106D01*
X4548060D01*
G01X4560770D02*
Y1073606D01*
X4564645D01*
X4565885Y1072981D01*
X4566660Y1072148D01*
X4566970Y1070481D01*
X4566660Y1068814D01*
X4565730Y1067773D01*
X4564645Y1067148D01*
X4560770D01*
G01X4564645D02*
X4566970Y1061106D01*
G01X4574410Y1073606D02*
X4578130D01*
G01X4576270D02*
Y1061106D01*
G01X4574410D02*
X4578130D01*
G01X4585570Y1073606D02*
Y1061106D01*
X4591770D01*
G01X4597970Y1073606D02*
Y1061106D01*
X4604170D01*
G01X4613470Y1060689D02*
X4613160Y1060898D01*
Y1061314D01*
X4613470Y1061523D01*
X4613780Y1061314D01*
Y1060898D01*
X4613470Y1060689D01*
G01Y1066314D02*
X4613160Y1066523D01*
Y1066939D01*
X4613470Y1067148D01*
X4613780Y1066939D01*
Y1066523D01*
X4613470Y1066314D01*
G01X4638270Y1073606D02*
Y1061106D01*
G01X4634705Y1073606D02*
X4641835D01*
G01X4650670Y1061106D02*
X4649430Y1061314D01*
X4648345Y1062147D01*
X4647415Y1063398D01*
X4646795Y1064856D01*
X4646485Y1066523D01*
Y1068189D01*
X4646795Y1069856D01*
X4647415Y1071314D01*
X4648345Y1072564D01*
X4649430Y1073398D01*
X4650670Y1073606D01*
X4651910Y1073398D01*
X4652995Y1072564D01*
X4653925Y1071314D01*
X4654545Y1069856D01*
X4654855Y1068189D01*
Y1066523D01*
X4654545Y1064856D01*
X4653925Y1063398D01*
X4652995Y1062147D01*
X4651910Y1061314D01*
X4650670Y1061106D01*
G01X4659970D02*
Y1073606D01*
X4663690D01*
X4664930Y1072981D01*
X4665860Y1071523D01*
X4666170Y1069856D01*
X4665860Y1068189D01*
X4665085Y1066939D01*
X4663690Y1066314D01*
X4659970D01*
G01X4687870Y1073606D02*
Y1061106D01*
G01X4685700Y1069439D02*
X4690040D01*
G01X4700270Y1061106D02*
X4699340Y1061314D01*
X4698410Y1062147D01*
X4697790Y1063606D01*
X4697480Y1065273D01*
X4697790Y1066939D01*
X4698410Y1068398D01*
X4699340Y1069231D01*
X4700270Y1069439D01*
X4701200Y1069231D01*
X4702130Y1068398D01*
X4702750Y1066939D01*
X4702905Y1065273D01*
X4702750Y1063606D01*
X4702130Y1062147D01*
X4701200Y1061314D01*
X4700270Y1061106D01*
G01X4726000Y1067356D02*
X4729100D01*
Y1063606D01*
X4728170Y1062356D01*
X4727085Y1061523D01*
X4725535Y1061106D01*
X4723985Y1061523D01*
X4722900Y1062356D01*
X4721970Y1063606D01*
X4721350Y1065064D01*
X4721040Y1066731D01*
Y1068189D01*
X4721350Y1069439D01*
X4721970Y1070898D01*
X4722900Y1072148D01*
X4723830Y1072981D01*
X4725070Y1073606D01*
X4726155D01*
X4727395Y1073189D01*
X4728325Y1072356D01*
G01X4733905Y1061106D02*
Y1073606D01*
X4741035Y1061106D01*
Y1073606D01*
G01X4746460Y1061106D02*
Y1073606D01*
X4749560D01*
X4750800Y1072981D01*
X4751730Y1072148D01*
X4752505Y1070898D01*
X4753125Y1069439D01*
X4753280Y1067356D01*
X4753125Y1065273D01*
X4752505Y1063814D01*
X4751730Y1062564D01*
X4750800Y1061731D01*
X4749560Y1061106D01*
X4746460D01*
G01X4759325Y1071523D02*
X4760255Y1072772D01*
X4761340Y1073398D01*
X4762580Y1073606D01*
X4764130Y1073189D01*
X4765215Y1072148D01*
X4765525Y1070898D01*
X4765370Y1069647D01*
X4764750Y1068606D01*
X4761650Y1066523D01*
X4760255Y1065064D01*
X4759325Y1062981D01*
X4759015Y1061106D01*
X4765525D01*
G01X4509195Y1352606D02*
X4513070Y1365106D01*
X4516945Y1352606D01*
G01X4515550Y1356981D02*
X4510590D01*
G01X4522370Y1365106D02*
Y1352606D01*
X4528570D01*
G01X4534770Y1365106D02*
Y1352606D01*
X4540970D01*
G01X4559260Y1365106D02*
Y1356148D01*
X4559880Y1354272D01*
X4561120Y1353023D01*
X4562670Y1352606D01*
X4564220Y1353023D01*
X4565460Y1354272D01*
X4566080Y1356148D01*
Y1365106D01*
G01X4571505Y1352606D02*
Y1365106D01*
X4578635Y1352606D01*
Y1365106D01*
G01X4585610D02*
X4589330D01*
G01X4587470D02*
Y1352606D01*
G01X4585610D02*
X4589330D01*
G01X4599870Y1365106D02*
Y1352606D01*
G01X4596305Y1365106D02*
X4603435D01*
G01X4609015Y1354272D02*
X4610255Y1353231D01*
X4611650Y1352606D01*
X4612890D01*
X4614130Y1353231D01*
X4615060Y1354272D01*
X4615525Y1355731D01*
X4615215Y1357189D01*
X4614440Y1358439D01*
X4613045Y1359273D01*
X4611185Y1359689D01*
X4610100Y1360523D01*
X4609635Y1361981D01*
X4609945Y1363439D01*
X4610720Y1364481D01*
X4611805Y1365106D01*
X4612890D01*
X4613975Y1364689D01*
X4614905Y1363648D01*
G01X4633195Y1352606D02*
X4637070Y1365106D01*
X4640945Y1352606D01*
G01X4639550Y1356981D02*
X4634590D01*
G01X4646370Y1352606D02*
Y1365106D01*
X4650245D01*
X4651485Y1364481D01*
X4652260Y1363648D01*
X4652570Y1361981D01*
X4652260Y1360314D01*
X4651330Y1359273D01*
X4650245Y1358648D01*
X4646370D01*
G01X4650245D02*
X4652570Y1352606D01*
G01X4664970D02*
X4658770D01*
Y1365106D01*
X4664970D01*
G01X4662490Y1359064D02*
X4658770D01*
G01X4684810Y1365106D02*
X4688530D01*
G01X4686670D02*
Y1352606D01*
G01X4684810D02*
X4688530D01*
G01X4695505D02*
Y1365106D01*
X4702635Y1352606D01*
Y1365106D01*
G01X4719840Y1352606D02*
Y1365106D01*
X4723870Y1354689D01*
X4727900Y1365106D01*
Y1352606D01*
G01X4734410Y1365106D02*
X4738130D01*
G01X4736270D02*
Y1352606D01*
G01X4734410D02*
X4738130D01*
G01X4745570Y1365106D02*
Y1352606D01*
X4751770D01*
G01X4757815Y1354272D02*
X4759055Y1353231D01*
X4760450Y1352606D01*
X4761690D01*
X4762930Y1353231D01*
X4763860Y1354272D01*
X4764325Y1355731D01*
X4764015Y1357189D01*
X4763240Y1358439D01*
X4761845Y1359273D01*
X4759985Y1359689D01*
X4758900Y1360523D01*
X4758435Y1361981D01*
X4758745Y1363439D01*
X4759520Y1364481D01*
X4760605Y1365106D01*
X4761690D01*
X4762775Y1364689D01*
X4763705Y1363648D01*
G01X4508110Y1384273D02*
X4508730Y1384898D01*
X4509195Y1385939D01*
X4509505Y1387398D01*
X4509195Y1388648D01*
X4508575Y1389481D01*
X4507490Y1390106D01*
X4503305D01*
Y1377606D01*
X4508420D01*
X4509505Y1378439D01*
X4510125Y1379689D01*
X4510435Y1381148D01*
X4510125Y1382606D01*
X4509195Y1383856D01*
X4508110Y1384273D01*
X4503305D01*
G01X4515395Y1377606D02*
X4519270Y1390106D01*
X4523145Y1377606D01*
G01X4521750Y1381981D02*
X4516790D01*
G01X4535080Y1389064D02*
X4534150Y1389689D01*
X4533065Y1390106D01*
X4531825D01*
X4530430Y1389481D01*
X4529345Y1388439D01*
X4528570Y1387189D01*
X4527950Y1385106D01*
X4527795Y1383231D01*
X4528105Y1381356D01*
X4528570Y1380106D01*
X4529500Y1378856D01*
X4530585Y1378023D01*
X4531670Y1377606D01*
X4532755D01*
X4533840Y1378023D01*
X4534770Y1378647D01*
X4535545Y1379481D01*
G01X4540660Y1377606D02*
Y1390106D01*
G01X4546550D02*
X4540660Y1382397D01*
G01X4547480Y1377606D02*
X4543295Y1385939D01*
G01X4553060Y1377606D02*
Y1390106D01*
X4556160D01*
X4557400Y1389481D01*
X4558330Y1388648D01*
X4559105Y1387398D01*
X4559725Y1385939D01*
X4559880Y1383856D01*
X4559725Y1381773D01*
X4559105Y1380314D01*
X4558330Y1379064D01*
X4557400Y1378231D01*
X4556160Y1377606D01*
X4553060D01*
G01X4565770D02*
Y1390106D01*
X4569645D01*
X4570885Y1389481D01*
X4571660Y1388648D01*
X4571970Y1386981D01*
X4571660Y1385314D01*
X4570730Y1384273D01*
X4569645Y1383648D01*
X4565770D01*
G01X4569645D02*
X4571970Y1377606D01*
G01X4579410Y1390106D02*
X4583130D01*
G01X4581270D02*
Y1377606D01*
G01X4579410D02*
X4583130D01*
G01X4590570Y1390106D02*
Y1377606D01*
X4596770D01*
G01X4602970Y1390106D02*
Y1377606D01*
X4609170D01*
G01X4618470Y1377189D02*
X4618160Y1377398D01*
Y1377814D01*
X4618470Y1378023D01*
X4618780Y1377814D01*
Y1377398D01*
X4618470Y1377189D01*
G01Y1382814D02*
X4618160Y1383023D01*
Y1383439D01*
X4618470Y1383648D01*
X4618780Y1383439D01*
Y1383023D01*
X4618470Y1382814D01*
G01X4643270Y1390106D02*
Y1377606D01*
G01X4639705Y1390106D02*
X4646835D01*
G01X4655670Y1377606D02*
X4654430Y1377814D01*
X4653345Y1378647D01*
X4652415Y1379898D01*
X4651795Y1381356D01*
X4651485Y1383023D01*
Y1384689D01*
X4651795Y1386356D01*
X4652415Y1387814D01*
X4653345Y1389064D01*
X4654430Y1389898D01*
X4655670Y1390106D01*
X4656910Y1389898D01*
X4657995Y1389064D01*
X4658925Y1387814D01*
X4659545Y1386356D01*
X4659855Y1384689D01*
Y1383023D01*
X4659545Y1381356D01*
X4658925Y1379898D01*
X4657995Y1378647D01*
X4656910Y1377814D01*
X4655670Y1377606D01*
G01X4664970D02*
Y1390106D01*
X4668690D01*
X4669930Y1389481D01*
X4670860Y1388023D01*
X4671170Y1386356D01*
X4670860Y1384689D01*
X4670085Y1383439D01*
X4668690Y1382814D01*
X4664970D01*
G01X4692870Y1390106D02*
Y1377606D01*
G01X4690700Y1385939D02*
X4695040D01*
G01X4705270Y1377606D02*
X4704340Y1377814D01*
X4703410Y1378647D01*
X4702790Y1380106D01*
X4702480Y1381773D01*
X4702790Y1383439D01*
X4703410Y1384898D01*
X4704340Y1385731D01*
X4705270Y1385939D01*
X4706200Y1385731D01*
X4707130Y1384898D01*
X4707750Y1383439D01*
X4707905Y1381773D01*
X4707750Y1380106D01*
X4707130Y1378647D01*
X4706200Y1377814D01*
X4705270Y1377606D01*
G01X4731000Y1383856D02*
X4734100D01*
Y1380106D01*
X4733170Y1378856D01*
X4732085Y1378023D01*
X4730535Y1377606D01*
X4728985Y1378023D01*
X4727900Y1378856D01*
X4726970Y1380106D01*
X4726350Y1381564D01*
X4726040Y1383231D01*
Y1384689D01*
X4726350Y1385939D01*
X4726970Y1387398D01*
X4727900Y1388648D01*
X4728830Y1389481D01*
X4730070Y1390106D01*
X4731155D01*
X4732395Y1389689D01*
X4733325Y1388856D01*
G01X4738905Y1377606D02*
Y1390106D01*
X4746035Y1377606D01*
Y1390106D01*
G01X4751460Y1377606D02*
Y1390106D01*
X4754560D01*
X4755800Y1389481D01*
X4756730Y1388648D01*
X4757505Y1387398D01*
X4758125Y1385939D01*
X4758280Y1383856D01*
X4758125Y1381773D01*
X4757505Y1380314D01*
X4756730Y1379064D01*
X4755800Y1378231D01*
X4754560Y1377606D01*
X4751460D01*
G01X4767270D02*
Y1390106D01*
X4765410Y1387606D01*
G01Y1377606D02*
X4769130D01*
G01X4523877Y-93335D02*
Y-80835D01*
X4527907Y-91252D01*
X4531937Y-80835D01*
Y-93335D01*
G01X4536742D02*
Y-80835D01*
X4543872Y-93335D01*
Y-80835D01*
G01X4556117Y-81877D02*
X4555187Y-81252D01*
X4554102Y-80835D01*
X4552862D01*
X4551467Y-81460D01*
X4550382Y-82502D01*
X4549607Y-83752D01*
X4548987Y-85835D01*
X4548832Y-87710D01*
X4549142Y-89585D01*
X4549607Y-90835D01*
X4550537Y-92085D01*
X4551622Y-92918D01*
X4552707Y-93335D01*
X4553792D01*
X4554877Y-92918D01*
X4555807Y-92294D01*
X4556582Y-91460D01*
G01X4560457Y-97502D02*
X4569757D01*
G01X4574407Y-80835D02*
Y-93335D01*
X4580607D01*
G01X4586032D02*
X4589907Y-80835D01*
X4593782Y-93335D01*
G01X4592387Y-88960D02*
X4587427D01*
G01X4602307Y-93335D02*
Y-87710D01*
X4599207Y-80835D01*
G01X4605407D02*
X4602307Y-87710D01*
G01X4617807Y-93335D02*
X4611607D01*
Y-80835D01*
X4617807D01*
G01X4615327Y-86877D02*
X4611607D01*
G01X4624007Y-93335D02*
Y-80835D01*
X4627882D01*
X4629122Y-81460D01*
X4629897Y-82293D01*
X4630207Y-83960D01*
X4629897Y-85627D01*
X4628967Y-86668D01*
X4627882Y-87293D01*
X4624007D01*
G01X4627882D02*
X4630207Y-93335D01*
G01X4518090Y163606D02*
Y176106D01*
X4522120Y165689D01*
X4526150Y176106D01*
Y163606D01*
G01X4530955D02*
Y176106D01*
X4538085Y163606D01*
Y176106D01*
G01X4550330Y175064D02*
X4549400Y175689D01*
X4548315Y176106D01*
X4547075D01*
X4545680Y175481D01*
X4544595Y174439D01*
X4543820Y173189D01*
X4543200Y171106D01*
X4543045Y169231D01*
X4543355Y167356D01*
X4543820Y166106D01*
X4544750Y164856D01*
X4545835Y164023D01*
X4546920Y163606D01*
X4548005D01*
X4549090Y164023D01*
X4550020Y164647D01*
X4550795Y165481D01*
G01X4554670Y159439D02*
X4563970D01*
G01X4568620Y176106D02*
Y163606D01*
X4574820D01*
G01X4580245D02*
X4584120Y176106D01*
X4587995Y163606D01*
G01X4586600Y167981D02*
X4581640D01*
G01X4596520Y163606D02*
Y169231D01*
X4593420Y176106D01*
G01X4599620D02*
X4596520Y169231D01*
G01X4612020Y163606D02*
X4605820D01*
Y176106D01*
X4612020D01*
G01X4609540Y170064D02*
X4605820D01*
G01X4618220Y163606D02*
Y176106D01*
X4622095D01*
X4623335Y175481D01*
X4624110Y174648D01*
X4624420Y172981D01*
X4624110Y171314D01*
X4623180Y170273D01*
X4622095Y169648D01*
X4618220D01*
G01X4622095D02*
X4624420Y163606D01*
G01X4521590Y434606D02*
Y447106D01*
X4525620Y436689D01*
X4529650Y447106D01*
Y434606D01*
G01X4534455D02*
Y447106D01*
X4541585Y434606D01*
Y447106D01*
G01X4553830Y446064D02*
X4552900Y446689D01*
X4551815Y447106D01*
X4550575D01*
X4549180Y446481D01*
X4548095Y445439D01*
X4547320Y444189D01*
X4546700Y442106D01*
X4546545Y440231D01*
X4546855Y438356D01*
X4547320Y437106D01*
X4548250Y435856D01*
X4549335Y435023D01*
X4550420Y434606D01*
X4551505D01*
X4552590Y435023D01*
X4553520Y435647D01*
X4554295Y436481D01*
G01X4558170Y430439D02*
X4567470D01*
G01X4572120Y447106D02*
Y434606D01*
X4578320D01*
G01X4583745D02*
X4587620Y447106D01*
X4591495Y434606D01*
G01X4590100Y438981D02*
X4585140D01*
G01X4600020Y434606D02*
Y440231D01*
X4596920Y447106D01*
G01X4603120D02*
X4600020Y440231D01*
G01X4615520Y434606D02*
X4609320D01*
Y447106D01*
X4615520D01*
G01X4613040Y441064D02*
X4609320D01*
G01X4621720Y434606D02*
Y447106D01*
X4625595D01*
X4626835Y446481D01*
X4627610Y445648D01*
X4627920Y443981D01*
X4627610Y442314D01*
X4626680Y441273D01*
X4625595Y440648D01*
X4621720D01*
G01X4625595D02*
X4627920Y434606D01*
G01X4522590Y707106D02*
Y719606D01*
X4526620Y709189D01*
X4530650Y719606D01*
Y707106D01*
G01X4535455D02*
Y719606D01*
X4542585Y707106D01*
Y719606D01*
G01X4554830Y718564D02*
X4553900Y719189D01*
X4552815Y719606D01*
X4551575D01*
X4550180Y718981D01*
X4549095Y717939D01*
X4548320Y716689D01*
X4547700Y714606D01*
X4547545Y712731D01*
X4547855Y710856D01*
X4548320Y709606D01*
X4549250Y708356D01*
X4550335Y707523D01*
X4551420Y707106D01*
X4552505D01*
X4553590Y707523D01*
X4554520Y708147D01*
X4555295Y708981D01*
G01X4559170Y702939D02*
X4568470D01*
G01X4573120Y719606D02*
Y707106D01*
X4579320D01*
G01X4584745D02*
X4588620Y719606D01*
X4592495Y707106D01*
G01X4591100Y711481D02*
X4586140D01*
G01X4601020Y707106D02*
Y712731D01*
X4597920Y719606D01*
G01X4604120D02*
X4601020Y712731D01*
G01X4616520Y707106D02*
X4610320D01*
Y719606D01*
X4616520D01*
G01X4614040Y713564D02*
X4610320D01*
G01X4622720Y707106D02*
Y719606D01*
X4626595D01*
X4627835Y718981D01*
X4628610Y718148D01*
X4628920Y716481D01*
X4628610Y714814D01*
X4627680Y713773D01*
X4626595Y713148D01*
X4622720D01*
G01X4626595D02*
X4628920Y707106D01*
G01X4521090Y1011106D02*
Y1023606D01*
X4525120Y1013189D01*
X4529150Y1023606D01*
Y1011106D01*
G01X4533955D02*
Y1023606D01*
X4541085Y1011106D01*
Y1023606D01*
G01X4553330Y1022564D02*
X4552400Y1023189D01*
X4551315Y1023606D01*
X4550075D01*
X4548680Y1022981D01*
X4547595Y1021939D01*
X4546820Y1020689D01*
X4546200Y1018606D01*
X4546045Y1016731D01*
X4546355Y1014856D01*
X4546820Y1013606D01*
X4547750Y1012356D01*
X4548835Y1011523D01*
X4549920Y1011106D01*
X4551005D01*
X4552090Y1011523D01*
X4553020Y1012147D01*
X4553795Y1012981D01*
G01X4557670Y1006939D02*
X4566970D01*
G01X4571620Y1023606D02*
Y1011106D01*
X4577820D01*
G01X4583245D02*
X4587120Y1023606D01*
X4590995Y1011106D01*
G01X4589600Y1015481D02*
X4584640D01*
G01X4599520Y1011106D02*
Y1016731D01*
X4596420Y1023606D01*
G01X4602620D02*
X4599520Y1016731D01*
G01X4615020Y1011106D02*
X4608820D01*
Y1023606D01*
X4615020D01*
G01X4612540Y1017564D02*
X4608820D01*
G01X4621220Y1011106D02*
Y1023606D01*
X4625095D01*
X4626335Y1022981D01*
X4627110Y1022148D01*
X4627420Y1020481D01*
X4627110Y1018814D01*
X4626180Y1017773D01*
X4625095Y1017148D01*
X4621220D01*
G01X4625095D02*
X4627420Y1011106D01*
G01X4511873Y1668045D02*
X4515748Y1680545D01*
X4519623Y1668045D01*
G01X4518228Y1672420D02*
X4513268D01*
G01X4525048Y1680545D02*
Y1668045D01*
X4531248D01*
G01X4537448Y1680545D02*
Y1668045D01*
X4543648D01*
G01X4561938Y1680545D02*
Y1671587D01*
X4562558Y1669711D01*
X4563798Y1668462D01*
X4565348Y1668045D01*
X4566898Y1668462D01*
X4568138Y1669711D01*
X4568758Y1671587D01*
Y1680545D01*
G01X4574183Y1668045D02*
Y1680545D01*
X4581313Y1668045D01*
Y1680545D01*
G01X4588288D02*
X4592008D01*
G01X4590148D02*
Y1668045D01*
G01X4588288D02*
X4592008D01*
G01X4602548Y1680545D02*
Y1668045D01*
G01X4598983Y1680545D02*
X4606113D01*
G01X4611693Y1669711D02*
X4612933Y1668670D01*
X4614328Y1668045D01*
X4615568D01*
X4616808Y1668670D01*
X4617738Y1669711D01*
X4618203Y1671170D01*
X4617893Y1672628D01*
X4617118Y1673878D01*
X4615723Y1674712D01*
X4613863Y1675128D01*
X4612778Y1675962D01*
X4612313Y1677420D01*
X4612623Y1678878D01*
X4613398Y1679920D01*
X4614483Y1680545D01*
X4615568D01*
X4616653Y1680128D01*
X4617583Y1679087D01*
G01X4635873Y1668045D02*
X4639748Y1680545D01*
X4643623Y1668045D01*
G01X4642228Y1672420D02*
X4637268D01*
G01X4649048Y1668045D02*
Y1680545D01*
X4652923D01*
X4654163Y1679920D01*
X4654938Y1679087D01*
X4655248Y1677420D01*
X4654938Y1675753D01*
X4654008Y1674712D01*
X4652923Y1674087D01*
X4649048D01*
G01X4652923D02*
X4655248Y1668045D01*
G01X4667648D02*
X4661448D01*
Y1680545D01*
X4667648D01*
G01X4665168Y1674503D02*
X4661448D01*
G01X4687488Y1680545D02*
X4691208D01*
G01X4689348D02*
Y1668045D01*
G01X4687488D02*
X4691208D01*
G01X4698183D02*
Y1680545D01*
X4705313Y1668045D01*
Y1680545D01*
G01X4722518Y1668045D02*
Y1680545D01*
X4726548Y1670128D01*
X4730578Y1680545D01*
Y1668045D01*
G01X4737088Y1680545D02*
X4740808D01*
G01X4738948D02*
Y1668045D01*
G01X4737088D02*
X4740808D01*
G01X4748248Y1680545D02*
Y1668045D01*
X4754448D01*
G01X4760493Y1669711D02*
X4761733Y1668670D01*
X4763128Y1668045D01*
X4764368D01*
X4765608Y1668670D01*
X4766538Y1669711D01*
X4767003Y1671170D01*
X4766693Y1672628D01*
X4765918Y1673878D01*
X4764523Y1674712D01*
X4762663Y1675128D01*
X4761578Y1675962D01*
X4761113Y1677420D01*
X4761423Y1678878D01*
X4762198Y1679920D01*
X4763283Y1680545D01*
X4764368D01*
X4765453Y1680128D01*
X4766383Y1679087D01*
G01X4516988Y1699712D02*
X4517608Y1700337D01*
X4518073Y1701378D01*
X4518383Y1702837D01*
X4518073Y1704087D01*
X4517453Y1704920D01*
X4516368Y1705545D01*
X4512183D01*
Y1693045D01*
X4517298D01*
X4518383Y1693878D01*
X4519003Y1695128D01*
X4519313Y1696587D01*
X4519003Y1698045D01*
X4518073Y1699295D01*
X4516988Y1699712D01*
X4512183D01*
G01X4524273Y1693045D02*
X4528148Y1705545D01*
X4532023Y1693045D01*
G01X4530628Y1697420D02*
X4525668D01*
G01X4543958Y1704503D02*
X4543028Y1705128D01*
X4541943Y1705545D01*
X4540703D01*
X4539308Y1704920D01*
X4538223Y1703878D01*
X4537448Y1702628D01*
X4536828Y1700545D01*
X4536673Y1698670D01*
X4536983Y1696795D01*
X4537448Y1695545D01*
X4538378Y1694295D01*
X4539463Y1693462D01*
X4540548Y1693045D01*
X4541633D01*
X4542718Y1693462D01*
X4543648Y1694086D01*
X4544423Y1694920D01*
G01X4549538Y1693045D02*
Y1705545D01*
G01X4555428D02*
X4549538Y1697836D01*
G01X4556358Y1693045D02*
X4552173Y1701378D01*
G01X4561938Y1693045D02*
Y1705545D01*
X4565038D01*
X4566278Y1704920D01*
X4567208Y1704087D01*
X4567983Y1702837D01*
X4568603Y1701378D01*
X4568758Y1699295D01*
X4568603Y1697212D01*
X4567983Y1695753D01*
X4567208Y1694503D01*
X4566278Y1693670D01*
X4565038Y1693045D01*
X4561938D01*
G01X4574648D02*
Y1705545D01*
X4578523D01*
X4579763Y1704920D01*
X4580538Y1704087D01*
X4580848Y1702420D01*
X4580538Y1700753D01*
X4579608Y1699712D01*
X4578523Y1699087D01*
X4574648D01*
G01X4578523D02*
X4580848Y1693045D01*
G01X4588288Y1705545D02*
X4592008D01*
G01X4590148D02*
Y1693045D01*
G01X4588288D02*
X4592008D01*
G01X4599448Y1705545D02*
Y1693045D01*
X4605648D01*
G01X4611848Y1705545D02*
Y1693045D01*
X4618048D01*
G01X4627348Y1692628D02*
X4627038Y1692837D01*
Y1693253D01*
X4627348Y1693462D01*
X4627658Y1693253D01*
Y1692837D01*
X4627348Y1692628D01*
G01Y1698253D02*
X4627038Y1698462D01*
Y1698878D01*
X4627348Y1699087D01*
X4627658Y1698878D01*
Y1698462D01*
X4627348Y1698253D01*
G01X4652148Y1705545D02*
Y1693045D01*
G01X4648583Y1705545D02*
X4655713D01*
G01X4664548Y1693045D02*
X4663308Y1693253D01*
X4662223Y1694086D01*
X4661293Y1695337D01*
X4660673Y1696795D01*
X4660363Y1698462D01*
Y1700128D01*
X4660673Y1701795D01*
X4661293Y1703253D01*
X4662223Y1704503D01*
X4663308Y1705337D01*
X4664548Y1705545D01*
X4665788Y1705337D01*
X4666873Y1704503D01*
X4667803Y1703253D01*
X4668423Y1701795D01*
X4668733Y1700128D01*
Y1698462D01*
X4668423Y1696795D01*
X4667803Y1695337D01*
X4666873Y1694086D01*
X4665788Y1693253D01*
X4664548Y1693045D01*
G01X4673848D02*
Y1705545D01*
X4677568D01*
X4678808Y1704920D01*
X4679738Y1703462D01*
X4680048Y1701795D01*
X4679738Y1700128D01*
X4678963Y1698878D01*
X4677568Y1698253D01*
X4673848D01*
G01X4701748Y1705545D02*
Y1693045D01*
G01X4699578Y1701378D02*
X4703918D01*
G01X4714148Y1693045D02*
X4713218Y1693253D01*
X4712288Y1694086D01*
X4711668Y1695545D01*
X4711358Y1697212D01*
X4711668Y1698878D01*
X4712288Y1700337D01*
X4713218Y1701170D01*
X4714148Y1701378D01*
X4715078Y1701170D01*
X4716008Y1700337D01*
X4716628Y1698878D01*
X4716783Y1697212D01*
X4716628Y1695545D01*
X4716008Y1694086D01*
X4715078Y1693253D01*
X4714148Y1693045D01*
G01X4739878Y1699295D02*
X4742978D01*
Y1695545D01*
X4742048Y1694295D01*
X4740963Y1693462D01*
X4739413Y1693045D01*
X4737863Y1693462D01*
X4736778Y1694295D01*
X4735848Y1695545D01*
X4735228Y1697003D01*
X4734918Y1698670D01*
Y1700128D01*
X4735228Y1701378D01*
X4735848Y1702837D01*
X4736778Y1704087D01*
X4737708Y1704920D01*
X4738948Y1705545D01*
X4740033D01*
X4741273Y1705128D01*
X4742203Y1704295D01*
G01X4747783Y1693045D02*
Y1705545D01*
X4754913Y1693045D01*
Y1705545D01*
G01X4760338Y1693045D02*
Y1705545D01*
X4763438D01*
X4764678Y1704920D01*
X4765608Y1704087D01*
X4766383Y1702837D01*
X4767003Y1701378D01*
X4767158Y1699295D01*
X4767003Y1697212D01*
X4766383Y1695753D01*
X4765608Y1694503D01*
X4764678Y1693670D01*
X4763438Y1693045D01*
X4760338D01*
G01X4526090Y1327606D02*
Y1340106D01*
X4530120Y1329689D01*
X4534150Y1340106D01*
Y1327606D01*
G01X4538955D02*
Y1340106D01*
X4546085Y1327606D01*
Y1340106D01*
G01X4558330Y1339064D02*
X4557400Y1339689D01*
X4556315Y1340106D01*
X4555075D01*
X4553680Y1339481D01*
X4552595Y1338439D01*
X4551820Y1337189D01*
X4551200Y1335106D01*
X4551045Y1333231D01*
X4551355Y1331356D01*
X4551820Y1330106D01*
X4552750Y1328856D01*
X4553835Y1328023D01*
X4554920Y1327606D01*
X4556005D01*
X4557090Y1328023D01*
X4558020Y1328647D01*
X4558795Y1329481D01*
G01X4562670Y1323439D02*
X4571970D01*
G01X4576620Y1340106D02*
Y1327606D01*
X4582820D01*
G01X4588245D02*
X4592120Y1340106D01*
X4595995Y1327606D01*
G01X4594600Y1331981D02*
X4589640D01*
G01X4604520Y1327606D02*
Y1333231D01*
X4601420Y1340106D01*
G01X4607620D02*
X4604520Y1333231D01*
G01X4620020Y1327606D02*
X4613820D01*
Y1340106D01*
X4620020D01*
G01X4617540Y1334064D02*
X4613820D01*
G01X4626220Y1327606D02*
Y1340106D01*
X4630095D01*
X4631335Y1339481D01*
X4632110Y1338648D01*
X4632420Y1336981D01*
X4632110Y1335314D01*
X4631180Y1334273D01*
X4630095Y1333648D01*
X4626220D01*
G01X4630095D02*
X4632420Y1327606D01*
G01X4528768Y1643045D02*
Y1655545D01*
X4532798Y1645128D01*
X4536828Y1655545D01*
Y1643045D01*
G01X4541633D02*
Y1655545D01*
X4548763Y1643045D01*
Y1655545D01*
G01X4561008Y1654503D02*
X4560078Y1655128D01*
X4558993Y1655545D01*
X4557753D01*
X4556358Y1654920D01*
X4555273Y1653878D01*
X4554498Y1652628D01*
X4553878Y1650545D01*
X4553723Y1648670D01*
X4554033Y1646795D01*
X4554498Y1645545D01*
X4555428Y1644295D01*
X4556513Y1643462D01*
X4557598Y1643045D01*
X4558683D01*
X4559768Y1643462D01*
X4560698Y1644086D01*
X4561473Y1644920D01*
G01X4565348Y1638878D02*
X4574648D01*
G01X4579298Y1655545D02*
Y1643045D01*
X4585498D01*
G01X4590923D02*
X4594798Y1655545D01*
X4598673Y1643045D01*
G01X4597278Y1647420D02*
X4592318D01*
G01X4607198Y1643045D02*
Y1648670D01*
X4604098Y1655545D01*
G01X4610298D02*
X4607198Y1648670D01*
G01X4622698Y1643045D02*
X4616498D01*
Y1655545D01*
X4622698D01*
G01X4620218Y1649503D02*
X4616498D01*
G01X4628898Y1643045D02*
Y1655545D01*
X4632773D01*
X4634013Y1654920D01*
X4634788Y1654087D01*
X4635098Y1652420D01*
X4634788Y1650753D01*
X4633858Y1649712D01*
X4632773Y1649087D01*
X4628898D01*
G01X4632773D02*
X4635098Y1643045D01*
G01X4559837Y-112085D02*
X4562937D01*
Y-115835D01*
X4562007Y-117085D01*
X4560922Y-117918D01*
X4559372Y-118335D01*
X4557822Y-117918D01*
X4556737Y-117085D01*
X4555807Y-115835D01*
X4555187Y-114377D01*
X4554877Y-112710D01*
Y-111252D01*
X4555187Y-110002D01*
X4555807Y-108543D01*
X4556737Y-107293D01*
X4557667Y-106460D01*
X4558907Y-105835D01*
X4559992D01*
X4561232Y-106252D01*
X4562162Y-107085D01*
G01X4567742Y-118335D02*
Y-105835D01*
X4574872Y-118335D01*
Y-105835D01*
G01X4580297Y-118335D02*
Y-105835D01*
X4583397D01*
X4584637Y-106460D01*
X4585567Y-107293D01*
X4586342Y-108543D01*
X4586962Y-110002D01*
X4587117Y-112085D01*
X4586962Y-114168D01*
X4586342Y-115627D01*
X4585567Y-116877D01*
X4584637Y-117710D01*
X4583397Y-118335D01*
X4580297D01*
G01X4592697Y-115835D02*
X4593627Y-117294D01*
X4594867Y-118127D01*
X4596262Y-118335D01*
X4597502Y-118127D01*
X4598742Y-117085D01*
X4599517Y-115835D01*
X4599672Y-114585D01*
X4599362Y-113127D01*
X4598277Y-112085D01*
X4597192Y-111668D01*
X4595797D01*
G01X4597192D02*
X4598122Y-111043D01*
X4598897Y-110002D01*
X4599207Y-108752D01*
X4598897Y-107502D01*
X4598122Y-106460D01*
X4596727Y-105835D01*
X4595332Y-106043D01*
X4593937Y-106877D01*
G01X4557460Y151106D02*
X4561180D01*
G01X4559320D02*
Y138606D01*
G01X4557460D02*
X4561180D01*
G01X4568155D02*
Y151106D01*
X4575285Y138606D01*
Y151106D01*
G01X4581175Y143814D02*
X4582260Y145273D01*
X4583190Y146106D01*
X4584430Y146523D01*
X4585515Y146106D01*
X4586290Y145273D01*
X4586910Y144023D01*
X4587065Y142564D01*
X4586910Y141314D01*
X4586290Y140064D01*
X4585360Y139023D01*
X4584275Y138606D01*
X4583035Y139023D01*
X4581950Y140272D01*
X4581330Y142148D01*
X4581175Y144231D01*
X4581485Y146939D01*
X4581950Y148398D01*
X4582725Y149856D01*
X4583810Y150898D01*
X4584895Y151106D01*
X4585980Y150689D01*
X4586755Y149648D01*
G01X4560960Y422106D02*
X4564680D01*
G01X4562820D02*
Y409606D01*
G01X4560960D02*
X4564680D01*
G01X4571655D02*
Y422106D01*
X4578785Y409606D01*
Y422106D01*
G01X4584210Y411481D02*
X4585140Y410439D01*
X4586225Y409814D01*
X4587620Y409606D01*
X4589015Y410023D01*
X4590100Y410856D01*
X4590875Y412314D01*
X4591030Y413981D01*
X4590720Y415648D01*
X4589945Y416689D01*
X4588860Y417523D01*
X4587775Y417731D01*
X4586690Y417523D01*
X4585295Y416689D01*
X4585760Y422106D01*
X4589945D01*
G01X4561960Y694606D02*
X4565680D01*
G01X4563820D02*
Y682106D01*
G01X4561960D02*
X4565680D01*
G01X4572655D02*
Y694606D01*
X4579785Y682106D01*
Y694606D01*
G01X4590480Y682106D02*
Y694606D01*
X4584745Y685648D01*
X4592495D01*
G01X4560460Y998606D02*
X4564180D01*
G01X4562320D02*
Y986106D01*
G01X4560460D02*
X4564180D01*
G01X4571155D02*
Y998606D01*
X4578285Y986106D01*
Y998606D01*
G01X4583710Y988606D02*
X4584640Y987147D01*
X4585880Y986314D01*
X4587275Y986106D01*
X4588515Y986314D01*
X4589755Y987356D01*
X4590530Y988606D01*
X4590685Y989856D01*
X4590375Y991314D01*
X4589290Y992356D01*
X4588205Y992773D01*
X4586810D01*
G01X4588205D02*
X4589135Y993398D01*
X4589910Y994439D01*
X4590220Y995689D01*
X4589910Y996939D01*
X4589135Y997981D01*
X4587740Y998606D01*
X4586345Y998398D01*
X4584950Y997564D01*
G01X4565460Y1315106D02*
X4569180D01*
G01X4567320D02*
Y1302606D01*
G01X4565460D02*
X4569180D01*
G01X4576155D02*
Y1315106D01*
X4583285Y1302606D01*
Y1315106D01*
G01X4589175Y1313023D02*
X4590105Y1314272D01*
X4591190Y1314898D01*
X4592430Y1315106D01*
X4593980Y1314689D01*
X4595065Y1313648D01*
X4595375Y1312398D01*
X4595220Y1311147D01*
X4594600Y1310106D01*
X4591500Y1308023D01*
X4590105Y1306564D01*
X4589175Y1304481D01*
X4588865Y1302606D01*
X4595375D01*
G01X4568138Y1630545D02*
X4571858D01*
G01X4569998D02*
Y1618045D01*
G01X4568138D02*
X4571858D01*
G01X4578833D02*
Y1630545D01*
X4585963Y1618045D01*
Y1630545D01*
G01X4594798Y1618045D02*
Y1630545D01*
X4592938Y1628045D01*
G01Y1618045D02*
X4596658D01*
G01X4688177Y-93335D02*
Y-80835D01*
X4692207Y-91252D01*
X4696237Y-80835D01*
Y-93335D01*
G01X4700732D02*
X4704607Y-80835D01*
X4708482Y-93335D01*
G01X4707087Y-88960D02*
X4702127D01*
G01X4713752Y-93335D02*
X4720262Y-80835D01*
G01X4713752D02*
X4720262Y-93335D01*
G01X4724757Y-97502D02*
X4734057D01*
G01X4738397Y-93335D02*
Y-80835D01*
X4741497D01*
X4742737Y-81460D01*
X4743667Y-82293D01*
X4744442Y-83543D01*
X4745062Y-85002D01*
X4745217Y-87085D01*
X4745062Y-89168D01*
X4744442Y-90627D01*
X4743667Y-91877D01*
X4742737Y-92710D01*
X4741497Y-93335D01*
X4738397D01*
G01X4757307D02*
X4751107D01*
Y-80835D01*
X4757307D01*
G01X4754827Y-86877D02*
X4751107D01*
G01X4763507Y-93335D02*
Y-80835D01*
X4767227D01*
X4768467Y-81460D01*
X4769397Y-82918D01*
X4769707Y-84585D01*
X4769397Y-86252D01*
X4768622Y-87502D01*
X4767227Y-88127D01*
X4763507D01*
G01X4779007Y-80835D02*
Y-93335D01*
G01X4775442Y-80835D02*
X4782572D01*
G01X4788152Y-93335D02*
Y-80835D01*
G01X4794662D02*
Y-93335D01*
G01Y-87085D02*
X4788152D01*
G01X4682390Y163606D02*
Y176106D01*
X4686420Y165689D01*
X4690450Y176106D01*
Y163606D01*
G01X4694945D02*
X4698820Y176106D01*
X4702695Y163606D01*
G01X4701300Y167981D02*
X4696340D01*
G01X4707965Y163606D02*
X4714475Y176106D01*
G01X4707965D02*
X4714475Y163606D01*
G01X4718970Y159439D02*
X4728270D01*
G01X4732610Y163606D02*
Y176106D01*
X4735710D01*
X4736950Y175481D01*
X4737880Y174648D01*
X4738655Y173398D01*
X4739275Y171939D01*
X4739430Y169856D01*
X4739275Y167773D01*
X4738655Y166314D01*
X4737880Y165064D01*
X4736950Y164231D01*
X4735710Y163606D01*
X4732610D01*
G01X4751520D02*
X4745320D01*
Y176106D01*
X4751520D01*
G01X4749040Y170064D02*
X4745320D01*
G01X4757720Y163606D02*
Y176106D01*
X4761440D01*
X4762680Y175481D01*
X4763610Y174023D01*
X4763920Y172356D01*
X4763610Y170689D01*
X4762835Y169439D01*
X4761440Y168814D01*
X4757720D01*
G01X4773220Y176106D02*
Y163606D01*
G01X4769655Y176106D02*
X4776785D01*
G01X4782365Y163606D02*
Y176106D01*
G01X4788875D02*
Y163606D01*
G01Y169856D02*
X4782365D01*
G01X4685890Y434606D02*
Y447106D01*
X4689920Y436689D01*
X4693950Y447106D01*
Y434606D01*
G01X4698445D02*
X4702320Y447106D01*
X4706195Y434606D01*
G01X4704800Y438981D02*
X4699840D01*
G01X4711465Y434606D02*
X4717975Y447106D01*
G01X4711465D02*
X4717975Y434606D01*
G01X4722470Y430439D02*
X4731770D01*
G01X4736110Y434606D02*
Y447106D01*
X4739210D01*
X4740450Y446481D01*
X4741380Y445648D01*
X4742155Y444398D01*
X4742775Y442939D01*
X4742930Y440856D01*
X4742775Y438773D01*
X4742155Y437314D01*
X4741380Y436064D01*
X4740450Y435231D01*
X4739210Y434606D01*
X4736110D01*
G01X4755020D02*
X4748820D01*
Y447106D01*
X4755020D01*
G01X4752540Y441064D02*
X4748820D01*
G01X4761220Y434606D02*
Y447106D01*
X4764940D01*
X4766180Y446481D01*
X4767110Y445023D01*
X4767420Y443356D01*
X4767110Y441689D01*
X4766335Y440439D01*
X4764940Y439814D01*
X4761220D01*
G01X4776720Y447106D02*
Y434606D01*
G01X4773155Y447106D02*
X4780285D01*
G01X4785865Y434606D02*
Y447106D01*
G01X4792375D02*
Y434606D01*
G01Y440856D02*
X4785865D01*
G01X4686890Y707106D02*
Y719606D01*
X4690920Y709189D01*
X4694950Y719606D01*
Y707106D01*
G01X4699445D02*
X4703320Y719606D01*
X4707195Y707106D01*
G01X4705800Y711481D02*
X4700840D01*
G01X4712465Y707106D02*
X4718975Y719606D01*
G01X4712465D02*
X4718975Y707106D01*
G01X4723470Y702939D02*
X4732770D01*
G01X4737110Y707106D02*
Y719606D01*
X4740210D01*
X4741450Y718981D01*
X4742380Y718148D01*
X4743155Y716898D01*
X4743775Y715439D01*
X4743930Y713356D01*
X4743775Y711273D01*
X4743155Y709814D01*
X4742380Y708564D01*
X4741450Y707731D01*
X4740210Y707106D01*
X4737110D01*
G01X4756020D02*
X4749820D01*
Y719606D01*
X4756020D01*
G01X4753540Y713564D02*
X4749820D01*
G01X4762220Y707106D02*
Y719606D01*
X4765940D01*
X4767180Y718981D01*
X4768110Y717523D01*
X4768420Y715856D01*
X4768110Y714189D01*
X4767335Y712939D01*
X4765940Y712314D01*
X4762220D01*
G01X4777720Y719606D02*
Y707106D01*
G01X4774155Y719606D02*
X4781285D01*
G01X4786865Y707106D02*
Y719606D01*
G01X4793375D02*
Y707106D01*
G01Y713356D02*
X4786865D01*
G01X4685390Y1011106D02*
Y1023606D01*
X4689420Y1013189D01*
X4693450Y1023606D01*
Y1011106D01*
G01X4697945D02*
X4701820Y1023606D01*
X4705695Y1011106D01*
G01X4704300Y1015481D02*
X4699340D01*
G01X4710965Y1011106D02*
X4717475Y1023606D01*
G01X4710965D02*
X4717475Y1011106D01*
G01X4721970Y1006939D02*
X4731270D01*
G01X4735610Y1011106D02*
Y1023606D01*
X4738710D01*
X4739950Y1022981D01*
X4740880Y1022148D01*
X4741655Y1020898D01*
X4742275Y1019439D01*
X4742430Y1017356D01*
X4742275Y1015273D01*
X4741655Y1013814D01*
X4740880Y1012564D01*
X4739950Y1011731D01*
X4738710Y1011106D01*
X4735610D01*
G01X4754520D02*
X4748320D01*
Y1023606D01*
X4754520D01*
G01X4752040Y1017564D02*
X4748320D01*
G01X4760720Y1011106D02*
Y1023606D01*
X4764440D01*
X4765680Y1022981D01*
X4766610Y1021523D01*
X4766920Y1019856D01*
X4766610Y1018189D01*
X4765835Y1016939D01*
X4764440Y1016314D01*
X4760720D01*
G01X4776220Y1023606D02*
Y1011106D01*
G01X4772655Y1023606D02*
X4779785D01*
G01X4785365Y1011106D02*
Y1023606D01*
G01X4791875D02*
Y1011106D01*
G01Y1017356D02*
X4785365D01*
G01X4690390Y1327606D02*
Y1340106D01*
X4694420Y1329689D01*
X4698450Y1340106D01*
Y1327606D01*
G01X4702945D02*
X4706820Y1340106D01*
X4710695Y1327606D01*
G01X4709300Y1331981D02*
X4704340D01*
G01X4715965Y1327606D02*
X4722475Y1340106D01*
G01X4715965D02*
X4722475Y1327606D01*
G01X4726970Y1323439D02*
X4736270D01*
G01X4740610Y1327606D02*
Y1340106D01*
X4743710D01*
X4744950Y1339481D01*
X4745880Y1338648D01*
X4746655Y1337398D01*
X4747275Y1335939D01*
X4747430Y1333856D01*
X4747275Y1331773D01*
X4746655Y1330314D01*
X4745880Y1329064D01*
X4744950Y1328231D01*
X4743710Y1327606D01*
X4740610D01*
G01X4759520D02*
X4753320D01*
Y1340106D01*
X4759520D01*
G01X4757040Y1334064D02*
X4753320D01*
G01X4765720Y1327606D02*
Y1340106D01*
X4769440D01*
X4770680Y1339481D01*
X4771610Y1338023D01*
X4771920Y1336356D01*
X4771610Y1334689D01*
X4770835Y1333439D01*
X4769440Y1332814D01*
X4765720D01*
G01X4781220Y1340106D02*
Y1327606D01*
G01X4777655Y1340106D02*
X4784785D01*
G01X4790365Y1327606D02*
Y1340106D01*
G01X4796875D02*
Y1327606D01*
G01Y1333856D02*
X4790365D01*
G01X4693068Y1643045D02*
Y1655545D01*
X4697098Y1645128D01*
X4701128Y1655545D01*
Y1643045D01*
G01X4705623D02*
X4709498Y1655545D01*
X4713373Y1643045D01*
G01X4711978Y1647420D02*
X4707018D01*
G01X4718643Y1643045D02*
X4725153Y1655545D01*
G01X4718643D02*
X4725153Y1643045D01*
G01X4729648Y1638878D02*
X4738948D01*
G01X4743288Y1643045D02*
Y1655545D01*
X4746388D01*
X4747628Y1654920D01*
X4748558Y1654087D01*
X4749333Y1652837D01*
X4749953Y1651378D01*
X4750108Y1649295D01*
X4749953Y1647212D01*
X4749333Y1645753D01*
X4748558Y1644503D01*
X4747628Y1643670D01*
X4746388Y1643045D01*
X4743288D01*
G01X4762198D02*
X4755998D01*
Y1655545D01*
X4762198D01*
G01X4759718Y1649503D02*
X4755998D01*
G01X4768398Y1643045D02*
Y1655545D01*
X4772118D01*
X4773358Y1654920D01*
X4774288Y1653462D01*
X4774598Y1651795D01*
X4774288Y1650128D01*
X4773513Y1648878D01*
X4772118Y1648253D01*
X4768398D01*
G01X4783898Y1655545D02*
Y1643045D01*
G01X4780333Y1655545D02*
X4787463D01*
G01X4793043Y1643045D02*
Y1655545D01*
G01X4799553D02*
Y1643045D01*
G01Y1649295D02*
X4793043D01*
G01X4717420Y138606D02*
X4718505Y138814D01*
X4719745Y139439D01*
X4720520Y140481D01*
X4720830Y141939D01*
X4720520Y143397D01*
X4719590Y144648D01*
X4718195Y145273D01*
X4716645D01*
X4715715Y145689D01*
X4714940Y146731D01*
X4714630Y148189D01*
X4715095Y149648D01*
X4716180Y150689D01*
X4717420Y151106D01*
X4718660Y150689D01*
X4719745Y149648D01*
X4720210Y148189D01*
X4719900Y146731D01*
X4719125Y145689D01*
X4718195Y145273D01*
X4716645D01*
X4715250Y144648D01*
X4714320Y143397D01*
X4714010Y141939D01*
X4714320Y140481D01*
X4715095Y139439D01*
X4716335Y138814D01*
X4717420Y138606D01*
G01X4726410Y141106D02*
X4727340Y139647D01*
X4728580Y138814D01*
X4729975Y138606D01*
X4731215Y138814D01*
X4732455Y139856D01*
X4733230Y141106D01*
X4733385Y142356D01*
X4733075Y143814D01*
X4731990Y144856D01*
X4730905Y145273D01*
X4729510D01*
G01X4730905D02*
X4731835Y145898D01*
X4732610Y146939D01*
X4732920Y148189D01*
X4732610Y149439D01*
X4731835Y150481D01*
X4730440Y151106D01*
X4729045Y150898D01*
X4727650Y150064D01*
G01X4742220Y138189D02*
X4741910Y138398D01*
Y138814D01*
X4742220Y139023D01*
X4742530Y138814D01*
Y138398D01*
X4742220Y138189D01*
G01X4751675Y143814D02*
X4752760Y145273D01*
X4753690Y146106D01*
X4754930Y146523D01*
X4756015Y146106D01*
X4756790Y145273D01*
X4757410Y144023D01*
X4757565Y142564D01*
X4757410Y141314D01*
X4756790Y140064D01*
X4755860Y139023D01*
X4754775Y138606D01*
X4753535Y139023D01*
X4752450Y140272D01*
X4751830Y142148D01*
X4751675Y144231D01*
X4751985Y146939D01*
X4752450Y148398D01*
X4753225Y149856D01*
X4754310Y150898D01*
X4755395Y151106D01*
X4756480Y150689D01*
X4757255Y149648D01*
G01X4714410Y409606D02*
X4714720Y412314D01*
X4715185Y414606D01*
X4715805Y416689D01*
X4716580Y418981D01*
X4717820Y422106D01*
X4711620D01*
G01X4724175Y420023D02*
X4725105Y421272D01*
X4726190Y421898D01*
X4727430Y422106D01*
X4728980Y421689D01*
X4730065Y420648D01*
X4730375Y419398D01*
X4730220Y418147D01*
X4729600Y417106D01*
X4726500Y415023D01*
X4725105Y413564D01*
X4724175Y411481D01*
X4723865Y409606D01*
X4730375D01*
G01X4739520Y409189D02*
X4739210Y409398D01*
Y409814D01*
X4739520Y410023D01*
X4739830Y409814D01*
Y409398D01*
X4739520Y409189D01*
G01X4748975Y414814D02*
X4750060Y416273D01*
X4750990Y417106D01*
X4752230Y417523D01*
X4753315Y417106D01*
X4754090Y416273D01*
X4754710Y415023D01*
X4754865Y413564D01*
X4754710Y412314D01*
X4754090Y411064D01*
X4753160Y410023D01*
X4752075Y409606D01*
X4750835Y410023D01*
X4749750Y411272D01*
X4749130Y413148D01*
X4748975Y415231D01*
X4749285Y417939D01*
X4749750Y419398D01*
X4750525Y420856D01*
X4751610Y421898D01*
X4752695Y422106D01*
X4753780Y421689D01*
X4754555Y420648D01*
G01X4760910Y411481D02*
X4761840Y410439D01*
X4762925Y409814D01*
X4764320Y409606D01*
X4765715Y410023D01*
X4766800Y410856D01*
X4767575Y412314D01*
X4767730Y413981D01*
X4767420Y415648D01*
X4766645Y416689D01*
X4765560Y417523D01*
X4764475Y417731D01*
X4763390Y417523D01*
X4761995Y416689D01*
X4762460Y422106D01*
X4766645D01*
G01X4718975Y687314D02*
X4720060Y688773D01*
X4720990Y689606D01*
X4722230Y690023D01*
X4723315Y689606D01*
X4724090Y688773D01*
X4724710Y687523D01*
X4724865Y686064D01*
X4724710Y684814D01*
X4724090Y683564D01*
X4723160Y682523D01*
X4722075Y682106D01*
X4720835Y682523D01*
X4719750Y683772D01*
X4719130Y685648D01*
X4718975Y687731D01*
X4719285Y690439D01*
X4719750Y691898D01*
X4720525Y693356D01*
X4721610Y694398D01*
X4722695Y694606D01*
X4723780Y694189D01*
X4724555Y693148D01*
G01X4734320Y682106D02*
Y694606D01*
X4732460Y692106D01*
G01Y682106D02*
X4736180D01*
G01X4746720Y681689D02*
X4746410Y681898D01*
Y682314D01*
X4746720Y682523D01*
X4747030Y682314D01*
Y681898D01*
X4746720Y681689D01*
G01X4758810Y682106D02*
X4759120Y684814D01*
X4759585Y687106D01*
X4760205Y689189D01*
X4760980Y691481D01*
X4762220Y694606D01*
X4756020D01*
G01X4717010Y988606D02*
X4717940Y987147D01*
X4719180Y986314D01*
X4720575Y986106D01*
X4721815Y986314D01*
X4723055Y987356D01*
X4723830Y988606D01*
X4723985Y989856D01*
X4723675Y991314D01*
X4722590Y992356D01*
X4721505Y992773D01*
X4720110D01*
G01X4721505D02*
X4722435Y993398D01*
X4723210Y994439D01*
X4723520Y995689D01*
X4723210Y996939D01*
X4722435Y997981D01*
X4721040Y998606D01*
X4719645Y998398D01*
X4718250Y997564D01*
G01X4732820Y998606D02*
X4731580Y998189D01*
X4730650Y997148D01*
X4730030Y995898D01*
X4729565Y994231D01*
X4729410Y992356D01*
X4729565Y990481D01*
X4730030Y988814D01*
X4730650Y987564D01*
X4731580Y986523D01*
X4732820Y986106D01*
X4734060Y986523D01*
X4734990Y987564D01*
X4735610Y988814D01*
X4736075Y990481D01*
X4736230Y992356D01*
X4736075Y994231D01*
X4735610Y995898D01*
X4734990Y997148D01*
X4734060Y998189D01*
X4732820Y998606D01*
G01X4745220Y985689D02*
X4744910Y985898D01*
Y986314D01*
X4745220Y986523D01*
X4745530Y986314D01*
Y985898D01*
X4745220Y985689D01*
G01X4757620Y986106D02*
X4758705Y986314D01*
X4759945Y986939D01*
X4760720Y987981D01*
X4761030Y989439D01*
X4760720Y990897D01*
X4759790Y992148D01*
X4758395Y992773D01*
X4756845D01*
X4755915Y993189D01*
X4755140Y994231D01*
X4754830Y995689D01*
X4755295Y997148D01*
X4756380Y998189D01*
X4757620Y998606D01*
X4758860Y998189D01*
X4759945Y997148D01*
X4760410Y995689D01*
X4760100Y994231D01*
X4759325Y993189D01*
X4758395Y992773D01*
X4756845D01*
X4755450Y992148D01*
X4754520Y990897D01*
X4754210Y989439D01*
X4754520Y987981D01*
X4755295Y986939D01*
X4756535Y986314D01*
X4757620Y986106D01*
G01X4719220Y1302606D02*
Y1315106D01*
X4717360Y1312606D01*
G01Y1302606D02*
X4721080D01*
G01X4728985Y1304064D02*
X4730070Y1303023D01*
X4731310Y1302606D01*
X4732550Y1303023D01*
X4733635Y1304272D01*
X4734410Y1306148D01*
X4734720Y1308023D01*
Y1310314D01*
X4734410Y1312189D01*
X4733635Y1313856D01*
X4732705Y1314689D01*
X4731620Y1315106D01*
X4730380Y1314689D01*
X4729450Y1313856D01*
X4728830Y1312606D01*
X4728520Y1310939D01*
X4728830Y1309481D01*
X4729605Y1308023D01*
X4730535Y1307189D01*
X4731620Y1306981D01*
X4732860Y1307397D01*
X4733790Y1308439D01*
X4734720Y1310314D01*
G01X4744020Y1302189D02*
X4743710Y1302398D01*
Y1302814D01*
X4744020Y1303023D01*
X4744330Y1302814D01*
Y1302398D01*
X4744020Y1302189D01*
G01X4756420Y1302606D02*
X4757505Y1302814D01*
X4758745Y1303439D01*
X4759520Y1304481D01*
X4759830Y1305939D01*
X4759520Y1307397D01*
X4758590Y1308648D01*
X4757195Y1309273D01*
X4755645D01*
X4754715Y1309689D01*
X4753940Y1310731D01*
X4753630Y1312189D01*
X4754095Y1313648D01*
X4755180Y1314689D01*
X4756420Y1315106D01*
X4757660Y1314689D01*
X4758745Y1313648D01*
X4759210Y1312189D01*
X4758900Y1310731D01*
X4758125Y1309689D01*
X4757195Y1309273D01*
X4755645D01*
X4754250Y1308648D01*
X4753320Y1307397D01*
X4753010Y1305939D01*
X4753320Y1304481D01*
X4754095Y1303439D01*
X4755335Y1302814D01*
X4756420Y1302606D01*
G01X4765410Y1304481D02*
X4766340Y1303439D01*
X4767425Y1302814D01*
X4768820Y1302606D01*
X4770215Y1303023D01*
X4771300Y1303856D01*
X4772075Y1305314D01*
X4772230Y1306981D01*
X4771920Y1308648D01*
X4771145Y1309689D01*
X4770060Y1310523D01*
X4768975Y1310731D01*
X4767890Y1310523D01*
X4766495Y1309689D01*
X4766960Y1315106D01*
X4771145D01*
G01X4719797Y-116460D02*
X4720727Y-117502D01*
X4721812Y-118127D01*
X4723207Y-118335D01*
X4724602Y-117918D01*
X4725687Y-117085D01*
X4726462Y-115627D01*
X4726617Y-113960D01*
X4726307Y-112293D01*
X4725532Y-111252D01*
X4724447Y-110418D01*
X4723362Y-110210D01*
X4722277Y-110418D01*
X4720882Y-111252D01*
X4721347Y-105835D01*
X4725532D01*
G01X4732197Y-116460D02*
X4733127Y-117502D01*
X4734212Y-118127D01*
X4735607Y-118335D01*
X4737002Y-117918D01*
X4738087Y-117085D01*
X4738862Y-115627D01*
X4739017Y-113960D01*
X4738707Y-112293D01*
X4737932Y-111252D01*
X4736847Y-110418D01*
X4735762Y-110210D01*
X4734677Y-110418D01*
X4733282Y-111252D01*
X4733747Y-105835D01*
X4737932D01*
G01X4748007Y-118752D02*
X4747697Y-118543D01*
Y-118127D01*
X4748007Y-117918D01*
X4748317Y-118127D01*
Y-118543D01*
X4748007Y-118752D01*
G01X4762267Y-118335D02*
Y-105835D01*
X4756532Y-114793D01*
X4764282D01*
G01X4734298Y1618045D02*
X4735383Y1618253D01*
X4736623Y1618878D01*
X4737398Y1619920D01*
X4737708Y1621378D01*
X4737398Y1622836D01*
X4736468Y1624087D01*
X4735073Y1624712D01*
X4733523D01*
X4732593Y1625128D01*
X4731818Y1626170D01*
X4731508Y1627628D01*
X4731973Y1629087D01*
X4733058Y1630128D01*
X4734298Y1630545D01*
X4735538Y1630128D01*
X4736623Y1629087D01*
X4737088Y1627628D01*
X4736778Y1626170D01*
X4736003Y1625128D01*
X4735073Y1624712D01*
X4733523D01*
X4732128Y1624087D01*
X4731198Y1622836D01*
X4730888Y1621378D01*
X4731198Y1619920D01*
X4731973Y1618878D01*
X4733213Y1618253D01*
X4734298Y1618045D01*
G01X4746698Y1617628D02*
X4746388Y1617837D01*
Y1618253D01*
X4746698Y1618462D01*
X4747008Y1618253D01*
Y1617837D01*
X4746698Y1617628D01*
G01X4756463Y1619503D02*
X4757548Y1618462D01*
X4758788Y1618045D01*
X4760028Y1618462D01*
X4761113Y1619711D01*
X4761888Y1621587D01*
X4762198Y1623462D01*
Y1625753D01*
X4761888Y1627628D01*
X4761113Y1629295D01*
X4760183Y1630128D01*
X4759098Y1630545D01*
X4757858Y1630128D01*
X4756928Y1629295D01*
X4756308Y1628045D01*
X4755998Y1626378D01*
X4756308Y1624920D01*
X4757083Y1623462D01*
X4758013Y1622628D01*
X4759098Y1622420D01*
X4760338Y1622836D01*
X4761268Y1623878D01*
X4762198Y1625753D01*
G01X4744807Y-130835D02*
Y-143335D01*
G01X4741242Y-130835D02*
X4748372D01*
G01X4757207Y-143335D02*
X4755967Y-143127D01*
X4754882Y-142294D01*
X4753952Y-141043D01*
X4753332Y-139585D01*
X4753022Y-137918D01*
Y-136252D01*
X4753332Y-134585D01*
X4753952Y-133127D01*
X4754882Y-131877D01*
X4755967Y-131043D01*
X4757207Y-130835D01*
X4758447Y-131043D01*
X4759532Y-131877D01*
X4760462Y-133127D01*
X4761082Y-134585D01*
X4761392Y-136252D01*
Y-137918D01*
X4761082Y-139585D01*
X4760462Y-141043D01*
X4759532Y-142294D01*
X4758447Y-143127D01*
X4757207Y-143335D01*
G01X4769607Y-130835D02*
Y-143335D01*
G01X4766042Y-130835D02*
X4773172D01*
G01X4778132Y-143335D02*
X4782007Y-130835D01*
X4785882Y-143335D01*
G01X4784487Y-138960D02*
X4779527D01*
G01X4791307Y-130835D02*
Y-143335D01*
X4797507D01*
G01X4820447Y-136668D02*
X4821067Y-136043D01*
X4821532Y-135002D01*
X4821842Y-133543D01*
X4821532Y-132293D01*
X4820912Y-131460D01*
X4819827Y-130835D01*
X4815642D01*
Y-143335D01*
X4820757D01*
X4821842Y-142502D01*
X4822462Y-141252D01*
X4822772Y-139793D01*
X4822462Y-138335D01*
X4821532Y-137085D01*
X4820447Y-136668D01*
X4815642D01*
G01X4827732Y-143335D02*
X4831607Y-130835D01*
X4835482Y-143335D01*
G01X4834087Y-138960D02*
X4829127D01*
G01X4847417Y-131877D02*
X4846487Y-131252D01*
X4845402Y-130835D01*
X4844162D01*
X4842767Y-131460D01*
X4841682Y-132502D01*
X4840907Y-133752D01*
X4840287Y-135835D01*
X4840132Y-137710D01*
X4840442Y-139585D01*
X4840907Y-140835D01*
X4841837Y-142085D01*
X4842922Y-142918D01*
X4844007Y-143335D01*
X4845092D01*
X4846177Y-142918D01*
X4847107Y-142294D01*
X4847882Y-141460D01*
G01X4852997Y-143335D02*
Y-130835D01*
G01X4858887D02*
X4852997Y-138544D01*
G01X4859817Y-143335D02*
X4855632Y-135002D01*
G01X4865397Y-143335D02*
Y-130835D01*
X4868497D01*
X4869737Y-131460D01*
X4870667Y-132293D01*
X4871442Y-133543D01*
X4872062Y-135002D01*
X4872217Y-137085D01*
X4872062Y-139168D01*
X4871442Y-140627D01*
X4870667Y-141877D01*
X4869737Y-142710D01*
X4868497Y-143335D01*
X4865397D01*
G01X4878107D02*
Y-130835D01*
X4881982D01*
X4883222Y-131460D01*
X4883997Y-132293D01*
X4884307Y-133960D01*
X4883997Y-135627D01*
X4883067Y-136668D01*
X4881982Y-137293D01*
X4878107D01*
G01X4881982D02*
X4884307Y-143335D01*
G01X4891747Y-130835D02*
X4895467D01*
G01X4893607D02*
Y-143335D01*
G01X4891747D02*
X4895467D01*
G01X4902907Y-130835D02*
Y-143335D01*
X4909107D01*
G01X4915307Y-130835D02*
Y-143335D01*
X4921507D01*
G01X4927552Y-141669D02*
X4928792Y-142710D01*
X4930187Y-143335D01*
X4931427D01*
X4932667Y-142710D01*
X4933597Y-141669D01*
X4934062Y-140210D01*
X4933752Y-138752D01*
X4932977Y-137502D01*
X4931582Y-136668D01*
X4929722Y-136252D01*
X4928637Y-135418D01*
X4928172Y-133960D01*
X4928482Y-132502D01*
X4929257Y-131460D01*
X4930342Y-130835D01*
X4931427D01*
X4932512Y-131252D01*
X4933442Y-132293D01*
G01X4943207Y-143752D02*
X4942897Y-143543D01*
Y-143127D01*
X4943207Y-142918D01*
X4943517Y-143127D01*
Y-143543D01*
X4943207Y-143752D01*
G01Y-138127D02*
X4942897Y-137918D01*
Y-137502D01*
X4943207Y-137293D01*
X4943517Y-137502D01*
Y-137918D01*
X4943207Y-138127D01*
G01X4968007Y-143335D02*
Y-130835D01*
X4966147Y-133335D01*
G01Y-143335D02*
X4969867D01*
G01X4976997Y-141460D02*
X4977927Y-142502D01*
X4979012Y-143127D01*
X4980407Y-143335D01*
X4981802Y-142918D01*
X4982887Y-142085D01*
X4983662Y-140627D01*
X4983817Y-138960D01*
X4983507Y-137293D01*
X4982732Y-136252D01*
X4981647Y-135418D01*
X4980562Y-135210D01*
X4979477Y-135418D01*
X4978082Y-136252D01*
X4978547Y-130835D01*
X4982732D01*
G01X4992807D02*
X4991567Y-131252D01*
X4990637Y-132293D01*
X4990017Y-133543D01*
X4989552Y-135210D01*
X4989397Y-137085D01*
X4989552Y-138960D01*
X4990017Y-140627D01*
X4990637Y-141877D01*
X4991567Y-142918D01*
X4992807Y-143335D01*
X4994047Y-142918D01*
X4994977Y-141877D01*
X4995597Y-140627D01*
X4996062Y-138960D01*
X4996217Y-137085D01*
X4996062Y-135210D01*
X4995597Y-133543D01*
X4994977Y-132293D01*
X4994047Y-131252D01*
X4992807Y-130835D01*
G01X4742020Y973606D02*
Y961106D01*
G01X4738455Y973606D02*
X4745585D01*
G01X4754420Y961106D02*
X4753180Y961314D01*
X4752095Y962147D01*
X4751165Y963398D01*
X4750545Y964856D01*
X4750235Y966523D01*
Y968189D01*
X4750545Y969856D01*
X4751165Y971314D01*
X4752095Y972564D01*
X4753180Y973398D01*
X4754420Y973606D01*
X4755660Y973398D01*
X4756745Y972564D01*
X4757675Y971314D01*
X4758295Y969856D01*
X4758605Y968189D01*
Y966523D01*
X4758295Y964856D01*
X4757675Y963398D01*
X4756745Y962147D01*
X4755660Y961314D01*
X4754420Y961106D01*
G01X4766820Y973606D02*
Y961106D01*
G01X4763255Y973606D02*
X4770385D01*
G01X4775345Y961106D02*
X4779220Y973606D01*
X4783095Y961106D01*
G01X4781700Y965481D02*
X4776740D01*
G01X4788520Y973606D02*
Y961106D01*
X4794720D01*
G01X4817660Y967773D02*
X4818280Y968398D01*
X4818745Y969439D01*
X4819055Y970898D01*
X4818745Y972148D01*
X4818125Y972981D01*
X4817040Y973606D01*
X4812855D01*
Y961106D01*
X4817970D01*
X4819055Y961939D01*
X4819675Y963189D01*
X4819985Y964648D01*
X4819675Y966106D01*
X4818745Y967356D01*
X4817660Y967773D01*
X4812855D01*
G01X4824945Y961106D02*
X4828820Y973606D01*
X4832695Y961106D01*
G01X4831300Y965481D02*
X4826340D01*
G01X4844630Y972564D02*
X4843700Y973189D01*
X4842615Y973606D01*
X4841375D01*
X4839980Y972981D01*
X4838895Y971939D01*
X4838120Y970689D01*
X4837500Y968606D01*
X4837345Y966731D01*
X4837655Y964856D01*
X4838120Y963606D01*
X4839050Y962356D01*
X4840135Y961523D01*
X4841220Y961106D01*
X4842305D01*
X4843390Y961523D01*
X4844320Y962147D01*
X4845095Y962981D01*
G01X4850210Y961106D02*
Y973606D01*
G01X4856100D02*
X4850210Y965897D01*
G01X4857030Y961106D02*
X4852845Y969439D01*
G01X4862610Y961106D02*
Y973606D01*
X4865710D01*
X4866950Y972981D01*
X4867880Y972148D01*
X4868655Y970898D01*
X4869275Y969439D01*
X4869430Y967356D01*
X4869275Y965273D01*
X4868655Y963814D01*
X4867880Y962564D01*
X4866950Y961731D01*
X4865710Y961106D01*
X4862610D01*
G01X4875320D02*
Y973606D01*
X4879195D01*
X4880435Y972981D01*
X4881210Y972148D01*
X4881520Y970481D01*
X4881210Y968814D01*
X4880280Y967773D01*
X4879195Y967148D01*
X4875320D01*
G01X4879195D02*
X4881520Y961106D01*
G01X4888960Y973606D02*
X4892680D01*
G01X4890820D02*
Y961106D01*
G01X4888960D02*
X4892680D01*
G01X4900120Y973606D02*
Y961106D01*
X4906320D01*
G01X4912520Y973606D02*
Y961106D01*
X4918720D01*
G01X4924765Y962772D02*
X4926005Y961731D01*
X4927400Y961106D01*
X4928640D01*
X4929880Y961731D01*
X4930810Y962772D01*
X4931275Y964231D01*
X4930965Y965689D01*
X4930190Y966939D01*
X4928795Y967773D01*
X4926935Y968189D01*
X4925850Y969023D01*
X4925385Y970481D01*
X4925695Y971939D01*
X4926470Y972981D01*
X4927555Y973606D01*
X4928640D01*
X4929725Y973189D01*
X4930655Y972148D01*
G01X4940420Y960689D02*
X4940110Y960898D01*
Y961314D01*
X4940420Y961523D01*
X4940730Y961314D01*
Y960898D01*
X4940420Y960689D01*
G01Y966314D02*
X4940110Y966523D01*
Y966939D01*
X4940420Y967148D01*
X4940730Y966939D01*
Y966523D01*
X4940420Y966314D01*
G01X4962275Y971523D02*
X4963205Y972772D01*
X4964290Y973398D01*
X4965530Y973606D01*
X4967080Y973189D01*
X4968165Y972148D01*
X4968475Y970898D01*
X4968320Y969647D01*
X4967700Y968606D01*
X4964600Y966523D01*
X4963205Y965064D01*
X4962275Y962981D01*
X4961965Y961106D01*
X4968475D01*
G01X4979480D02*
Y973606D01*
X4973745Y964648D01*
X4981495D01*
G01X4990020Y973606D02*
X4988780Y973189D01*
X4987850Y972148D01*
X4987230Y970898D01*
X4986765Y969231D01*
X4986610Y967356D01*
X4986765Y965481D01*
X4987230Y963814D01*
X4987850Y962564D01*
X4988780Y961523D01*
X4990020Y961106D01*
X4991260Y961523D01*
X4992190Y962564D01*
X4992810Y963814D01*
X4993275Y965481D01*
X4993430Y967356D01*
X4993275Y969231D01*
X4992810Y970898D01*
X4992190Y972148D01*
X4991260Y973189D01*
X4990020Y973606D01*
G01X4763820Y126106D02*
Y113606D01*
G01X4760255Y126106D02*
X4767385D01*
G01X4776220Y113606D02*
X4774980Y113814D01*
X4773895Y114647D01*
X4772965Y115898D01*
X4772345Y117356D01*
X4772035Y119023D01*
Y120689D01*
X4772345Y122356D01*
X4772965Y123814D01*
X4773895Y125064D01*
X4774980Y125898D01*
X4776220Y126106D01*
X4777460Y125898D01*
X4778545Y125064D01*
X4779475Y123814D01*
X4780095Y122356D01*
X4780405Y120689D01*
Y119023D01*
X4780095Y117356D01*
X4779475Y115898D01*
X4778545Y114647D01*
X4777460Y113814D01*
X4776220Y113606D01*
G01X4788620Y126106D02*
Y113606D01*
G01X4785055Y126106D02*
X4792185D01*
G01X4797145Y113606D02*
X4801020Y126106D01*
X4804895Y113606D01*
G01X4803500Y117981D02*
X4798540D01*
G01X4810320Y126106D02*
Y113606D01*
X4816520D01*
G01X4839460Y120273D02*
X4840080Y120898D01*
X4840545Y121939D01*
X4840855Y123398D01*
X4840545Y124648D01*
X4839925Y125481D01*
X4838840Y126106D01*
X4834655D01*
Y113606D01*
X4839770D01*
X4840855Y114439D01*
X4841475Y115689D01*
X4841785Y117148D01*
X4841475Y118606D01*
X4840545Y119856D01*
X4839460Y120273D01*
X4834655D01*
G01X4846745Y113606D02*
X4850620Y126106D01*
X4854495Y113606D01*
G01X4853100Y117981D02*
X4848140D01*
G01X4866430Y125064D02*
X4865500Y125689D01*
X4864415Y126106D01*
X4863175D01*
X4861780Y125481D01*
X4860695Y124439D01*
X4859920Y123189D01*
X4859300Y121106D01*
X4859145Y119231D01*
X4859455Y117356D01*
X4859920Y116106D01*
X4860850Y114856D01*
X4861935Y114023D01*
X4863020Y113606D01*
X4864105D01*
X4865190Y114023D01*
X4866120Y114647D01*
X4866895Y115481D01*
G01X4872010Y113606D02*
Y126106D01*
G01X4877900D02*
X4872010Y118397D01*
G01X4878830Y113606D02*
X4874645Y121939D01*
G01X4884410Y113606D02*
Y126106D01*
X4887510D01*
X4888750Y125481D01*
X4889680Y124648D01*
X4890455Y123398D01*
X4891075Y121939D01*
X4891230Y119856D01*
X4891075Y117773D01*
X4890455Y116314D01*
X4889680Y115064D01*
X4888750Y114231D01*
X4887510Y113606D01*
X4884410D01*
G01X4897120D02*
Y126106D01*
X4900995D01*
X4902235Y125481D01*
X4903010Y124648D01*
X4903320Y122981D01*
X4903010Y121314D01*
X4902080Y120273D01*
X4900995Y119648D01*
X4897120D01*
G01X4900995D02*
X4903320Y113606D01*
G01X4910760Y126106D02*
X4914480D01*
G01X4912620D02*
Y113606D01*
G01X4910760D02*
X4914480D01*
G01X4921920Y126106D02*
Y113606D01*
X4928120D01*
G01X4934320Y126106D02*
Y113606D01*
X4940520D01*
G01X4946565Y115272D02*
X4947805Y114231D01*
X4949200Y113606D01*
X4950440D01*
X4951680Y114231D01*
X4952610Y115272D01*
X4953075Y116731D01*
X4952765Y118189D01*
X4951990Y119439D01*
X4950595Y120273D01*
X4948735Y120689D01*
X4947650Y121523D01*
X4947185Y122981D01*
X4947495Y124439D01*
X4948270Y125481D01*
X4949355Y126106D01*
X4950440D01*
X4951525Y125689D01*
X4952455Y124648D01*
G01X4962220Y113189D02*
X4961910Y113398D01*
Y113814D01*
X4962220Y114023D01*
X4962530Y113814D01*
Y113398D01*
X4962220Y113189D01*
G01Y118814D02*
X4961910Y119023D01*
Y119439D01*
X4962220Y119648D01*
X4962530Y119439D01*
Y119023D01*
X4962220Y118814D01*
G01X4987020Y113606D02*
X4988105Y113814D01*
X4989345Y114439D01*
X4990120Y115481D01*
X4990430Y116939D01*
X4990120Y118397D01*
X4989190Y119648D01*
X4987795Y120273D01*
X4986245D01*
X4985315Y120689D01*
X4984540Y121731D01*
X4984230Y123189D01*
X4984695Y124648D01*
X4985780Y125689D01*
X4987020Y126106D01*
X4988260Y125689D01*
X4989345Y124648D01*
X4989810Y123189D01*
X4989500Y121731D01*
X4988725Y120689D01*
X4987795Y120273D01*
X4986245D01*
X4984850Y119648D01*
X4983920Y118397D01*
X4983610Y116939D01*
X4983920Y115481D01*
X4984695Y114439D01*
X4985935Y113814D01*
X4987020Y113606D01*
G01X4754920Y397106D02*
Y384606D01*
G01X4751355Y397106D02*
X4758485D01*
G01X4767320Y384606D02*
X4766080Y384814D01*
X4764995Y385647D01*
X4764065Y386898D01*
X4763445Y388356D01*
X4763135Y390023D01*
Y391689D01*
X4763445Y393356D01*
X4764065Y394814D01*
X4764995Y396064D01*
X4766080Y396898D01*
X4767320Y397106D01*
X4768560Y396898D01*
X4769645Y396064D01*
X4770575Y394814D01*
X4771195Y393356D01*
X4771505Y391689D01*
Y390023D01*
X4771195Y388356D01*
X4770575Y386898D01*
X4769645Y385647D01*
X4768560Y384814D01*
X4767320Y384606D01*
G01X4779720Y397106D02*
Y384606D01*
G01X4776155Y397106D02*
X4783285D01*
G01X4788245Y384606D02*
X4792120Y397106D01*
X4795995Y384606D01*
G01X4794600Y388981D02*
X4789640D01*
G01X4801420Y397106D02*
Y384606D01*
X4807620D01*
G01X4830560Y391273D02*
X4831180Y391898D01*
X4831645Y392939D01*
X4831955Y394398D01*
X4831645Y395648D01*
X4831025Y396481D01*
X4829940Y397106D01*
X4825755D01*
Y384606D01*
X4830870D01*
X4831955Y385439D01*
X4832575Y386689D01*
X4832885Y388148D01*
X4832575Y389606D01*
X4831645Y390856D01*
X4830560Y391273D01*
X4825755D01*
G01X4837845Y384606D02*
X4841720Y397106D01*
X4845595Y384606D01*
G01X4844200Y388981D02*
X4839240D01*
G01X4857530Y396064D02*
X4856600Y396689D01*
X4855515Y397106D01*
X4854275D01*
X4852880Y396481D01*
X4851795Y395439D01*
X4851020Y394189D01*
X4850400Y392106D01*
X4850245Y390231D01*
X4850555Y388356D01*
X4851020Y387106D01*
X4851950Y385856D01*
X4853035Y385023D01*
X4854120Y384606D01*
X4855205D01*
X4856290Y385023D01*
X4857220Y385647D01*
X4857995Y386481D01*
G01X4863110Y384606D02*
Y397106D01*
G01X4869000D02*
X4863110Y389397D01*
G01X4869930Y384606D02*
X4865745Y392939D01*
G01X4875510Y384606D02*
Y397106D01*
X4878610D01*
X4879850Y396481D01*
X4880780Y395648D01*
X4881555Y394398D01*
X4882175Y392939D01*
X4882330Y390856D01*
X4882175Y388773D01*
X4881555Y387314D01*
X4880780Y386064D01*
X4879850Y385231D01*
X4878610Y384606D01*
X4875510D01*
G01X4888220D02*
Y397106D01*
X4892095D01*
X4893335Y396481D01*
X4894110Y395648D01*
X4894420Y393981D01*
X4894110Y392314D01*
X4893180Y391273D01*
X4892095Y390648D01*
X4888220D01*
G01X4892095D02*
X4894420Y384606D01*
G01X4901860Y397106D02*
X4905580D01*
G01X4903720D02*
Y384606D01*
G01X4901860D02*
X4905580D01*
G01X4913020Y397106D02*
Y384606D01*
X4919220D01*
G01X4925420Y397106D02*
Y384606D01*
X4931620D01*
G01X4937665Y386272D02*
X4938905Y385231D01*
X4940300Y384606D01*
X4941540D01*
X4942780Y385231D01*
X4943710Y386272D01*
X4944175Y387731D01*
X4943865Y389189D01*
X4943090Y390439D01*
X4941695Y391273D01*
X4939835Y391689D01*
X4938750Y392523D01*
X4938285Y393981D01*
X4938595Y395439D01*
X4939370Y396481D01*
X4940455Y397106D01*
X4941540D01*
X4942625Y396689D01*
X4943555Y395648D01*
G01X4953320Y384189D02*
X4953010Y384398D01*
Y384814D01*
X4953320Y385023D01*
X4953630Y384814D01*
Y384398D01*
X4953320Y384189D01*
G01Y389814D02*
X4953010Y390023D01*
Y390439D01*
X4953320Y390648D01*
X4953630Y390439D01*
Y390023D01*
X4953320Y389814D01*
G01X4978120Y384606D02*
Y397106D01*
X4976260Y394606D01*
G01Y384606D02*
X4979980D01*
G01X4987575Y395023D02*
X4988505Y396272D01*
X4989590Y396898D01*
X4990830Y397106D01*
X4992380Y396689D01*
X4993465Y395648D01*
X4993775Y394398D01*
X4993620Y393147D01*
X4993000Y392106D01*
X4989900Y390023D01*
X4988505Y388564D01*
X4987575Y386481D01*
X4987265Y384606D01*
X4993775D01*
G01X4755920Y669606D02*
Y657106D01*
G01X4752355Y669606D02*
X4759485D01*
G01X4768320Y657106D02*
X4767080Y657314D01*
X4765995Y658147D01*
X4765065Y659398D01*
X4764445Y660856D01*
X4764135Y662523D01*
Y664189D01*
X4764445Y665856D01*
X4765065Y667314D01*
X4765995Y668564D01*
X4767080Y669398D01*
X4768320Y669606D01*
X4769560Y669398D01*
X4770645Y668564D01*
X4771575Y667314D01*
X4772195Y665856D01*
X4772505Y664189D01*
Y662523D01*
X4772195Y660856D01*
X4771575Y659398D01*
X4770645Y658147D01*
X4769560Y657314D01*
X4768320Y657106D01*
G01X4780720Y669606D02*
Y657106D01*
G01X4777155Y669606D02*
X4784285D01*
G01X4789245Y657106D02*
X4793120Y669606D01*
X4796995Y657106D01*
G01X4795600Y661481D02*
X4790640D01*
G01X4802420Y669606D02*
Y657106D01*
X4808620D01*
G01X4831560Y663773D02*
X4832180Y664398D01*
X4832645Y665439D01*
X4832955Y666898D01*
X4832645Y668148D01*
X4832025Y668981D01*
X4830940Y669606D01*
X4826755D01*
Y657106D01*
X4831870D01*
X4832955Y657939D01*
X4833575Y659189D01*
X4833885Y660648D01*
X4833575Y662106D01*
X4832645Y663356D01*
X4831560Y663773D01*
X4826755D01*
G01X4838845Y657106D02*
X4842720Y669606D01*
X4846595Y657106D01*
G01X4845200Y661481D02*
X4840240D01*
G01X4858530Y668564D02*
X4857600Y669189D01*
X4856515Y669606D01*
X4855275D01*
X4853880Y668981D01*
X4852795Y667939D01*
X4852020Y666689D01*
X4851400Y664606D01*
X4851245Y662731D01*
X4851555Y660856D01*
X4852020Y659606D01*
X4852950Y658356D01*
X4854035Y657523D01*
X4855120Y657106D01*
X4856205D01*
X4857290Y657523D01*
X4858220Y658147D01*
X4858995Y658981D01*
G01X4864110Y657106D02*
Y669606D01*
G01X4870000D02*
X4864110Y661897D01*
G01X4870930Y657106D02*
X4866745Y665439D01*
G01X4876510Y657106D02*
Y669606D01*
X4879610D01*
X4880850Y668981D01*
X4881780Y668148D01*
X4882555Y666898D01*
X4883175Y665439D01*
X4883330Y663356D01*
X4883175Y661273D01*
X4882555Y659814D01*
X4881780Y658564D01*
X4880850Y657731D01*
X4879610Y657106D01*
X4876510D01*
G01X4889220D02*
Y669606D01*
X4893095D01*
X4894335Y668981D01*
X4895110Y668148D01*
X4895420Y666481D01*
X4895110Y664814D01*
X4894180Y663773D01*
X4893095Y663148D01*
X4889220D01*
G01X4893095D02*
X4895420Y657106D01*
G01X4902860Y669606D02*
X4906580D01*
G01X4904720D02*
Y657106D01*
G01X4902860D02*
X4906580D01*
G01X4914020Y669606D02*
Y657106D01*
X4920220D01*
G01X4926420Y669606D02*
Y657106D01*
X4932620D01*
G01X4938665Y658772D02*
X4939905Y657731D01*
X4941300Y657106D01*
X4942540D01*
X4943780Y657731D01*
X4944710Y658772D01*
X4945175Y660231D01*
X4944865Y661689D01*
X4944090Y662939D01*
X4942695Y663773D01*
X4940835Y664189D01*
X4939750Y665023D01*
X4939285Y666481D01*
X4939595Y667939D01*
X4940370Y668981D01*
X4941455Y669606D01*
X4942540D01*
X4943625Y669189D01*
X4944555Y668148D01*
G01X4954320Y656689D02*
X4954010Y656898D01*
Y657314D01*
X4954320Y657523D01*
X4954630Y657314D01*
Y656898D01*
X4954320Y656689D01*
G01Y662314D02*
X4954010Y662523D01*
Y662939D01*
X4954320Y663148D01*
X4954630Y662939D01*
Y662523D01*
X4954320Y662314D01*
G01X4980980Y657106D02*
Y669606D01*
X4975245Y660648D01*
X4982995D01*
G01X4993380Y657106D02*
Y669606D01*
X4987645Y660648D01*
X4995395D01*
G01X4762098Y1605545D02*
Y1593045D01*
G01X4758533Y1605545D02*
X4765663D01*
G01X4774498Y1593045D02*
X4773258Y1593253D01*
X4772173Y1594086D01*
X4771243Y1595337D01*
X4770623Y1596795D01*
X4770313Y1598462D01*
Y1600128D01*
X4770623Y1601795D01*
X4771243Y1603253D01*
X4772173Y1604503D01*
X4773258Y1605337D01*
X4774498Y1605545D01*
X4775738Y1605337D01*
X4776823Y1604503D01*
X4777753Y1603253D01*
X4778373Y1601795D01*
X4778683Y1600128D01*
Y1598462D01*
X4778373Y1596795D01*
X4777753Y1595337D01*
X4776823Y1594086D01*
X4775738Y1593253D01*
X4774498Y1593045D01*
G01X4786898Y1605545D02*
Y1593045D01*
G01X4783333Y1605545D02*
X4790463D01*
G01X4795423Y1593045D02*
X4799298Y1605545D01*
X4803173Y1593045D01*
G01X4801778Y1597420D02*
X4796818D01*
G01X4808598Y1605545D02*
Y1593045D01*
X4814798D01*
G01X4837738Y1599712D02*
X4838358Y1600337D01*
X4838823Y1601378D01*
X4839133Y1602837D01*
X4838823Y1604087D01*
X4838203Y1604920D01*
X4837118Y1605545D01*
X4832933D01*
Y1593045D01*
X4838048D01*
X4839133Y1593878D01*
X4839753Y1595128D01*
X4840063Y1596587D01*
X4839753Y1598045D01*
X4838823Y1599295D01*
X4837738Y1599712D01*
X4832933D01*
G01X4845023Y1593045D02*
X4848898Y1605545D01*
X4852773Y1593045D01*
G01X4851378Y1597420D02*
X4846418D01*
G01X4864708Y1604503D02*
X4863778Y1605128D01*
X4862693Y1605545D01*
X4861453D01*
X4860058Y1604920D01*
X4858973Y1603878D01*
X4858198Y1602628D01*
X4857578Y1600545D01*
X4857423Y1598670D01*
X4857733Y1596795D01*
X4858198Y1595545D01*
X4859128Y1594295D01*
X4860213Y1593462D01*
X4861298Y1593045D01*
X4862383D01*
X4863468Y1593462D01*
X4864398Y1594086D01*
X4865173Y1594920D01*
G01X4870288Y1593045D02*
Y1605545D01*
G01X4876178D02*
X4870288Y1597836D01*
G01X4877108Y1593045D02*
X4872923Y1601378D01*
G01X4882688Y1593045D02*
Y1605545D01*
X4885788D01*
X4887028Y1604920D01*
X4887958Y1604087D01*
X4888733Y1602837D01*
X4889353Y1601378D01*
X4889508Y1599295D01*
X4889353Y1597212D01*
X4888733Y1595753D01*
X4887958Y1594503D01*
X4887028Y1593670D01*
X4885788Y1593045D01*
X4882688D01*
G01X4895398D02*
Y1605545D01*
X4899273D01*
X4900513Y1604920D01*
X4901288Y1604087D01*
X4901598Y1602420D01*
X4901288Y1600753D01*
X4900358Y1599712D01*
X4899273Y1599087D01*
X4895398D01*
G01X4899273D02*
X4901598Y1593045D01*
G01X4909038Y1605545D02*
X4912758D01*
G01X4910898D02*
Y1593045D01*
G01X4909038D02*
X4912758D01*
G01X4920198Y1605545D02*
Y1593045D01*
X4926398D01*
G01X4932598Y1605545D02*
Y1593045D01*
X4938798D01*
G01X4944843Y1594711D02*
X4946083Y1593670D01*
X4947478Y1593045D01*
X4948718D01*
X4949958Y1593670D01*
X4950888Y1594711D01*
X4951353Y1596170D01*
X4951043Y1597628D01*
X4950268Y1598878D01*
X4948873Y1599712D01*
X4947013Y1600128D01*
X4945928Y1600962D01*
X4945463Y1602420D01*
X4945773Y1603878D01*
X4946548Y1604920D01*
X4947633Y1605545D01*
X4948718D01*
X4949803Y1605128D01*
X4950733Y1604087D01*
G01X4960498Y1592628D02*
X4960188Y1592837D01*
Y1593253D01*
X4960498Y1593462D01*
X4960808Y1593253D01*
Y1592837D01*
X4960498Y1592628D01*
G01Y1598253D02*
X4960188Y1598462D01*
Y1598878D01*
X4960498Y1599087D01*
X4960808Y1598878D01*
Y1598462D01*
X4960498Y1598253D01*
G01X4981888Y1595545D02*
X4982818Y1594086D01*
X4984058Y1593253D01*
X4985453Y1593045D01*
X4986693Y1593253D01*
X4987933Y1594295D01*
X4988708Y1595545D01*
X4988863Y1596795D01*
X4988553Y1598253D01*
X4987468Y1599295D01*
X4986383Y1599712D01*
X4984988D01*
G01X4986383D02*
X4987313Y1600337D01*
X4988088Y1601378D01*
X4988398Y1602628D01*
X4988088Y1603878D01*
X4987313Y1604920D01*
X4985918Y1605545D01*
X4984523Y1605337D01*
X4983128Y1604503D01*
G01X4994753Y1603462D02*
X4995683Y1604711D01*
X4996768Y1605337D01*
X4998008Y1605545D01*
X4999558Y1605128D01*
X5000643Y1604087D01*
X5000953Y1602837D01*
X5000798Y1601586D01*
X5000178Y1600545D01*
X4997078Y1598462D01*
X4995683Y1597003D01*
X4994753Y1594920D01*
X4994443Y1593045D01*
X5000953D01*
G01X4771820Y1290106D02*
Y1277606D01*
G01X4768255Y1290106D02*
X4775385D01*
G01X4784220Y1277606D02*
X4782980Y1277814D01*
X4781895Y1278647D01*
X4780965Y1279898D01*
X4780345Y1281356D01*
X4780035Y1283023D01*
Y1284689D01*
X4780345Y1286356D01*
X4780965Y1287814D01*
X4781895Y1289064D01*
X4782980Y1289898D01*
X4784220Y1290106D01*
X4785460Y1289898D01*
X4786545Y1289064D01*
X4787475Y1287814D01*
X4788095Y1286356D01*
X4788405Y1284689D01*
Y1283023D01*
X4788095Y1281356D01*
X4787475Y1279898D01*
X4786545Y1278647D01*
X4785460Y1277814D01*
X4784220Y1277606D01*
G01X4796620Y1290106D02*
Y1277606D01*
G01X4793055Y1290106D02*
X4800185D01*
G01X4805145Y1277606D02*
X4809020Y1290106D01*
X4812895Y1277606D01*
G01X4811500Y1281981D02*
X4806540D01*
G01X4818320Y1290106D02*
Y1277606D01*
X4824520D01*
G01X4847460Y1284273D02*
X4848080Y1284898D01*
X4848545Y1285939D01*
X4848855Y1287398D01*
X4848545Y1288648D01*
X4847925Y1289481D01*
X4846840Y1290106D01*
X4842655D01*
Y1277606D01*
X4847770D01*
X4848855Y1278439D01*
X4849475Y1279689D01*
X4849785Y1281148D01*
X4849475Y1282606D01*
X4848545Y1283856D01*
X4847460Y1284273D01*
X4842655D01*
G01X4854745Y1277606D02*
X4858620Y1290106D01*
X4862495Y1277606D01*
G01X4861100Y1281981D02*
X4856140D01*
G01X4874430Y1289064D02*
X4873500Y1289689D01*
X4872415Y1290106D01*
X4871175D01*
X4869780Y1289481D01*
X4868695Y1288439D01*
X4867920Y1287189D01*
X4867300Y1285106D01*
X4867145Y1283231D01*
X4867455Y1281356D01*
X4867920Y1280106D01*
X4868850Y1278856D01*
X4869935Y1278023D01*
X4871020Y1277606D01*
X4872105D01*
X4873190Y1278023D01*
X4874120Y1278647D01*
X4874895Y1279481D01*
G01X4880010Y1277606D02*
Y1290106D01*
G01X4885900D02*
X4880010Y1282397D01*
G01X4886830Y1277606D02*
X4882645Y1285939D01*
G01X4892410Y1277606D02*
Y1290106D01*
X4895510D01*
X4896750Y1289481D01*
X4897680Y1288648D01*
X4898455Y1287398D01*
X4899075Y1285939D01*
X4899230Y1283856D01*
X4899075Y1281773D01*
X4898455Y1280314D01*
X4897680Y1279064D01*
X4896750Y1278231D01*
X4895510Y1277606D01*
X4892410D01*
G01X4905120D02*
Y1290106D01*
X4908995D01*
X4910235Y1289481D01*
X4911010Y1288648D01*
X4911320Y1286981D01*
X4911010Y1285314D01*
X4910080Y1284273D01*
X4908995Y1283648D01*
X4905120D01*
G01X4908995D02*
X4911320Y1277606D01*
G01X4918760Y1290106D02*
X4922480D01*
G01X4920620D02*
Y1277606D01*
G01X4918760D02*
X4922480D01*
G01X4929920Y1290106D02*
Y1277606D01*
X4936120D01*
G01X4942320Y1290106D02*
Y1277606D01*
X4948520D01*
G01X4954565Y1279272D02*
X4955805Y1278231D01*
X4957200Y1277606D01*
X4958440D01*
X4959680Y1278231D01*
X4960610Y1279272D01*
X4961075Y1280731D01*
X4960765Y1282189D01*
X4959990Y1283439D01*
X4958595Y1284273D01*
X4956735Y1284689D01*
X4955650Y1285523D01*
X4955185Y1286981D01*
X4955495Y1288439D01*
X4956270Y1289481D01*
X4957355Y1290106D01*
X4958440D01*
X4959525Y1289689D01*
X4960455Y1288648D01*
G01X4970220Y1277189D02*
X4969910Y1277398D01*
Y1277814D01*
X4970220Y1278023D01*
X4970530Y1277814D01*
Y1277398D01*
X4970220Y1277189D01*
G01Y1282814D02*
X4969910Y1283023D01*
Y1283439D01*
X4970220Y1283648D01*
X4970530Y1283439D01*
Y1283023D01*
X4970220Y1282814D01*
G01X4995020Y1277606D02*
X4996105Y1277814D01*
X4997345Y1278439D01*
X4998120Y1279481D01*
X4998430Y1280939D01*
X4998120Y1282397D01*
X4997190Y1283648D01*
X4995795Y1284273D01*
X4994245D01*
X4993315Y1284689D01*
X4992540Y1285731D01*
X4992230Y1287189D01*
X4992695Y1288648D01*
X4993780Y1289689D01*
X4995020Y1290106D01*
X4996260Y1289689D01*
X4997345Y1288648D01*
X4997810Y1287189D01*
X4997500Y1285731D01*
X4996725Y1284689D01*
X4995795Y1284273D01*
X4994245D01*
X4992850Y1283648D01*
X4991920Y1282397D01*
X4991610Y1280939D01*
X4991920Y1279481D01*
X4992695Y1278439D01*
X4993935Y1277814D01*
X4995020Y1277606D01*
G01X4821477Y-93335D02*
Y-80835D01*
X4825507Y-91252D01*
X4829537Y-80835D01*
Y-93335D01*
G01X4834962D02*
Y-80835D01*
X4840852D01*
G01X4838682Y-86877D02*
X4834962D01*
G01X4851237Y-87085D02*
X4854337D01*
Y-90835D01*
X4853407Y-92085D01*
X4852322Y-92918D01*
X4850772Y-93335D01*
X4849222Y-92918D01*
X4848137Y-92085D01*
X4847207Y-90835D01*
X4846587Y-89377D01*
X4846277Y-87710D01*
Y-86252D01*
X4846587Y-85002D01*
X4847207Y-83543D01*
X4848137Y-82293D01*
X4849067Y-81460D01*
X4850307Y-80835D01*
X4851392D01*
X4852632Y-81252D01*
X4853562Y-82085D01*
G01X4858057Y-97502D02*
X4867357D01*
G01X4871852Y-91669D02*
X4873092Y-92710D01*
X4874487Y-93335D01*
X4875727D01*
X4876967Y-92710D01*
X4877897Y-91669D01*
X4878362Y-90210D01*
X4878052Y-88752D01*
X4877277Y-87502D01*
X4875882Y-86668D01*
X4874022Y-86252D01*
X4872937Y-85418D01*
X4872472Y-83960D01*
X4872782Y-82502D01*
X4873557Y-81460D01*
X4874642Y-80835D01*
X4875727D01*
X4876812Y-81252D01*
X4877742Y-82293D01*
G01X4887507Y-80835D02*
Y-93335D01*
G01X4883942Y-80835D02*
X4891072D01*
G01X4896497D02*
Y-89793D01*
X4897117Y-91669D01*
X4898357Y-92918D01*
X4899907Y-93335D01*
X4901457Y-92918D01*
X4902697Y-91669D01*
X4903317Y-89793D01*
Y-80835D01*
G01X4913547Y-86668D02*
X4914167Y-86043D01*
X4914632Y-85002D01*
X4914942Y-83543D01*
X4914632Y-82293D01*
X4914012Y-81460D01*
X4912927Y-80835D01*
X4908742D01*
Y-93335D01*
X4913857D01*
X4914942Y-92502D01*
X4915562Y-91252D01*
X4915872Y-89793D01*
X4915562Y-88335D01*
X4914632Y-87085D01*
X4913547Y-86668D01*
X4908742D01*
G01X4815690Y163606D02*
Y176106D01*
X4819720Y165689D01*
X4823750Y176106D01*
Y163606D01*
G01X4829175D02*
Y176106D01*
X4835065D01*
G01X4832895Y170064D02*
X4829175D01*
G01X4845450Y169856D02*
X4848550D01*
Y166106D01*
X4847620Y164856D01*
X4846535Y164023D01*
X4844985Y163606D01*
X4843435Y164023D01*
X4842350Y164856D01*
X4841420Y166106D01*
X4840800Y167564D01*
X4840490Y169231D01*
Y170689D01*
X4840800Y171939D01*
X4841420Y173398D01*
X4842350Y174648D01*
X4843280Y175481D01*
X4844520Y176106D01*
X4845605D01*
X4846845Y175689D01*
X4847775Y174856D01*
G01X4852270Y159439D02*
X4861570D01*
G01X4866065Y165272D02*
X4867305Y164231D01*
X4868700Y163606D01*
X4869940D01*
X4871180Y164231D01*
X4872110Y165272D01*
X4872575Y166731D01*
X4872265Y168189D01*
X4871490Y169439D01*
X4870095Y170273D01*
X4868235Y170689D01*
X4867150Y171523D01*
X4866685Y172981D01*
X4866995Y174439D01*
X4867770Y175481D01*
X4868855Y176106D01*
X4869940D01*
X4871025Y175689D01*
X4871955Y174648D01*
G01X4881720Y176106D02*
Y163606D01*
G01X4878155Y176106D02*
X4885285D01*
G01X4890710D02*
Y167148D01*
X4891330Y165272D01*
X4892570Y164023D01*
X4894120Y163606D01*
X4895670Y164023D01*
X4896910Y165272D01*
X4897530Y167148D01*
Y176106D01*
G01X4907760Y170273D02*
X4908380Y170898D01*
X4908845Y171939D01*
X4909155Y173398D01*
X4908845Y174648D01*
X4908225Y175481D01*
X4907140Y176106D01*
X4902955D01*
Y163606D01*
X4908070D01*
X4909155Y164439D01*
X4909775Y165689D01*
X4910085Y167148D01*
X4909775Y168606D01*
X4908845Y169856D01*
X4907760Y170273D01*
X4902955D01*
G01X4819190Y434606D02*
Y447106D01*
X4823220Y436689D01*
X4827250Y447106D01*
Y434606D01*
G01X4832675D02*
Y447106D01*
X4838565D01*
G01X4836395Y441064D02*
X4832675D01*
G01X4848950Y440856D02*
X4852050D01*
Y437106D01*
X4851120Y435856D01*
X4850035Y435023D01*
X4848485Y434606D01*
X4846935Y435023D01*
X4845850Y435856D01*
X4844920Y437106D01*
X4844300Y438564D01*
X4843990Y440231D01*
Y441689D01*
X4844300Y442939D01*
X4844920Y444398D01*
X4845850Y445648D01*
X4846780Y446481D01*
X4848020Y447106D01*
X4849105D01*
X4850345Y446689D01*
X4851275Y445856D01*
G01X4855770Y430439D02*
X4865070D01*
G01X4869565Y436272D02*
X4870805Y435231D01*
X4872200Y434606D01*
X4873440D01*
X4874680Y435231D01*
X4875610Y436272D01*
X4876075Y437731D01*
X4875765Y439189D01*
X4874990Y440439D01*
X4873595Y441273D01*
X4871735Y441689D01*
X4870650Y442523D01*
X4870185Y443981D01*
X4870495Y445439D01*
X4871270Y446481D01*
X4872355Y447106D01*
X4873440D01*
X4874525Y446689D01*
X4875455Y445648D01*
G01X4885220Y447106D02*
Y434606D01*
G01X4881655Y447106D02*
X4888785D01*
G01X4894210D02*
Y438148D01*
X4894830Y436272D01*
X4896070Y435023D01*
X4897620Y434606D01*
X4899170Y435023D01*
X4900410Y436272D01*
X4901030Y438148D01*
Y447106D01*
G01X4911260Y441273D02*
X4911880Y441898D01*
X4912345Y442939D01*
X4912655Y444398D01*
X4912345Y445648D01*
X4911725Y446481D01*
X4910640Y447106D01*
X4906455D01*
Y434606D01*
X4911570D01*
X4912655Y435439D01*
X4913275Y436689D01*
X4913585Y438148D01*
X4913275Y439606D01*
X4912345Y440856D01*
X4911260Y441273D01*
X4906455D01*
G01X4820190Y707106D02*
Y719606D01*
X4824220Y709189D01*
X4828250Y719606D01*
Y707106D01*
G01X4833675D02*
Y719606D01*
X4839565D01*
G01X4837395Y713564D02*
X4833675D01*
G01X4849950Y713356D02*
X4853050D01*
Y709606D01*
X4852120Y708356D01*
X4851035Y707523D01*
X4849485Y707106D01*
X4847935Y707523D01*
X4846850Y708356D01*
X4845920Y709606D01*
X4845300Y711064D01*
X4844990Y712731D01*
Y714189D01*
X4845300Y715439D01*
X4845920Y716898D01*
X4846850Y718148D01*
X4847780Y718981D01*
X4849020Y719606D01*
X4850105D01*
X4851345Y719189D01*
X4852275Y718356D01*
G01X4856770Y702939D02*
X4866070D01*
G01X4870565Y708772D02*
X4871805Y707731D01*
X4873200Y707106D01*
X4874440D01*
X4875680Y707731D01*
X4876610Y708772D01*
X4877075Y710231D01*
X4876765Y711689D01*
X4875990Y712939D01*
X4874595Y713773D01*
X4872735Y714189D01*
X4871650Y715023D01*
X4871185Y716481D01*
X4871495Y717939D01*
X4872270Y718981D01*
X4873355Y719606D01*
X4874440D01*
X4875525Y719189D01*
X4876455Y718148D01*
G01X4886220Y719606D02*
Y707106D01*
G01X4882655Y719606D02*
X4889785D01*
G01X4895210D02*
Y710648D01*
X4895830Y708772D01*
X4897070Y707523D01*
X4898620Y707106D01*
X4900170Y707523D01*
X4901410Y708772D01*
X4902030Y710648D01*
Y719606D01*
G01X4912260Y713773D02*
X4912880Y714398D01*
X4913345Y715439D01*
X4913655Y716898D01*
X4913345Y718148D01*
X4912725Y718981D01*
X4911640Y719606D01*
X4907455D01*
Y707106D01*
X4912570D01*
X4913655Y707939D01*
X4914275Y709189D01*
X4914585Y710648D01*
X4914275Y712106D01*
X4913345Y713356D01*
X4912260Y713773D01*
X4907455D01*
G01X4818690Y1011106D02*
Y1023606D01*
X4822720Y1013189D01*
X4826750Y1023606D01*
Y1011106D01*
G01X4832175D02*
Y1023606D01*
X4838065D01*
G01X4835895Y1017564D02*
X4832175D01*
G01X4848450Y1017356D02*
X4851550D01*
Y1013606D01*
X4850620Y1012356D01*
X4849535Y1011523D01*
X4847985Y1011106D01*
X4846435Y1011523D01*
X4845350Y1012356D01*
X4844420Y1013606D01*
X4843800Y1015064D01*
X4843490Y1016731D01*
Y1018189D01*
X4843800Y1019439D01*
X4844420Y1020898D01*
X4845350Y1022148D01*
X4846280Y1022981D01*
X4847520Y1023606D01*
X4848605D01*
X4849845Y1023189D01*
X4850775Y1022356D01*
G01X4855270Y1006939D02*
X4864570D01*
G01X4869065Y1012772D02*
X4870305Y1011731D01*
X4871700Y1011106D01*
X4872940D01*
X4874180Y1011731D01*
X4875110Y1012772D01*
X4875575Y1014231D01*
X4875265Y1015689D01*
X4874490Y1016939D01*
X4873095Y1017773D01*
X4871235Y1018189D01*
X4870150Y1019023D01*
X4869685Y1020481D01*
X4869995Y1021939D01*
X4870770Y1022981D01*
X4871855Y1023606D01*
X4872940D01*
X4874025Y1023189D01*
X4874955Y1022148D01*
G01X4884720Y1023606D02*
Y1011106D01*
G01X4881155Y1023606D02*
X4888285D01*
G01X4893710D02*
Y1014648D01*
X4894330Y1012772D01*
X4895570Y1011523D01*
X4897120Y1011106D01*
X4898670Y1011523D01*
X4899910Y1012772D01*
X4900530Y1014648D01*
Y1023606D01*
G01X4910760Y1017773D02*
X4911380Y1018398D01*
X4911845Y1019439D01*
X4912155Y1020898D01*
X4911845Y1022148D01*
X4911225Y1022981D01*
X4910140Y1023606D01*
X4905955D01*
Y1011106D01*
X4911070D01*
X4912155Y1011939D01*
X4912775Y1013189D01*
X4913085Y1014648D01*
X4912775Y1016106D01*
X4911845Y1017356D01*
X4910760Y1017773D01*
X4905955D01*
G01X4823690Y1327606D02*
Y1340106D01*
X4827720Y1329689D01*
X4831750Y1340106D01*
Y1327606D01*
G01X4837175D02*
Y1340106D01*
X4843065D01*
G01X4840895Y1334064D02*
X4837175D01*
G01X4853450Y1333856D02*
X4856550D01*
Y1330106D01*
X4855620Y1328856D01*
X4854535Y1328023D01*
X4852985Y1327606D01*
X4851435Y1328023D01*
X4850350Y1328856D01*
X4849420Y1330106D01*
X4848800Y1331564D01*
X4848490Y1333231D01*
Y1334689D01*
X4848800Y1335939D01*
X4849420Y1337398D01*
X4850350Y1338648D01*
X4851280Y1339481D01*
X4852520Y1340106D01*
X4853605D01*
X4854845Y1339689D01*
X4855775Y1338856D01*
G01X4860270Y1323439D02*
X4869570D01*
G01X4874065Y1329272D02*
X4875305Y1328231D01*
X4876700Y1327606D01*
X4877940D01*
X4879180Y1328231D01*
X4880110Y1329272D01*
X4880575Y1330731D01*
X4880265Y1332189D01*
X4879490Y1333439D01*
X4878095Y1334273D01*
X4876235Y1334689D01*
X4875150Y1335523D01*
X4874685Y1336981D01*
X4874995Y1338439D01*
X4875770Y1339481D01*
X4876855Y1340106D01*
X4877940D01*
X4879025Y1339689D01*
X4879955Y1338648D01*
G01X4889720Y1340106D02*
Y1327606D01*
G01X4886155Y1340106D02*
X4893285D01*
G01X4898710D02*
Y1331148D01*
X4899330Y1329272D01*
X4900570Y1328023D01*
X4902120Y1327606D01*
X4903670Y1328023D01*
X4904910Y1329272D01*
X4905530Y1331148D01*
Y1340106D01*
G01X4915760Y1334273D02*
X4916380Y1334898D01*
X4916845Y1335939D01*
X4917155Y1337398D01*
X4916845Y1338648D01*
X4916225Y1339481D01*
X4915140Y1340106D01*
X4910955D01*
Y1327606D01*
X4916070D01*
X4917155Y1328439D01*
X4917775Y1329689D01*
X4918085Y1331148D01*
X4917775Y1332606D01*
X4916845Y1333856D01*
X4915760Y1334273D01*
X4910955D01*
G01X4826368Y1643045D02*
Y1655545D01*
X4830398Y1645128D01*
X4834428Y1655545D01*
Y1643045D01*
G01X4839853D02*
Y1655545D01*
X4845743D01*
G01X4843573Y1649503D02*
X4839853D01*
G01X4856128Y1649295D02*
X4859228D01*
Y1645545D01*
X4858298Y1644295D01*
X4857213Y1643462D01*
X4855663Y1643045D01*
X4854113Y1643462D01*
X4853028Y1644295D01*
X4852098Y1645545D01*
X4851478Y1647003D01*
X4851168Y1648670D01*
Y1650128D01*
X4851478Y1651378D01*
X4852098Y1652837D01*
X4853028Y1654087D01*
X4853958Y1654920D01*
X4855198Y1655545D01*
X4856283D01*
X4857523Y1655128D01*
X4858453Y1654295D01*
G01X4862948Y1638878D02*
X4872248D01*
G01X4876743Y1644711D02*
X4877983Y1643670D01*
X4879378Y1643045D01*
X4880618D01*
X4881858Y1643670D01*
X4882788Y1644711D01*
X4883253Y1646170D01*
X4882943Y1647628D01*
X4882168Y1648878D01*
X4880773Y1649712D01*
X4878913Y1650128D01*
X4877828Y1650962D01*
X4877363Y1652420D01*
X4877673Y1653878D01*
X4878448Y1654920D01*
X4879533Y1655545D01*
X4880618D01*
X4881703Y1655128D01*
X4882633Y1654087D01*
G01X4892398Y1655545D02*
Y1643045D01*
G01X4888833Y1655545D02*
X4895963D01*
G01X4901388D02*
Y1646587D01*
X4902008Y1644711D01*
X4903248Y1643462D01*
X4904798Y1643045D01*
X4906348Y1643462D01*
X4907588Y1644711D01*
X4908208Y1646587D01*
Y1655545D01*
G01X4918438Y1649712D02*
X4919058Y1650337D01*
X4919523Y1651378D01*
X4919833Y1652837D01*
X4919523Y1654087D01*
X4918903Y1654920D01*
X4917818Y1655545D01*
X4913633D01*
Y1643045D01*
X4918748D01*
X4919833Y1643878D01*
X4920453Y1645128D01*
X4920763Y1646587D01*
X4920453Y1648045D01*
X4919523Y1649295D01*
X4918438Y1649712D01*
X4913633D01*
G01X4866892Y-114168D02*
X4870922D01*
G01X4861105Y142773D02*
X4865135D01*
G01X4864605Y413773D02*
X4868635D01*
G01X4865605Y686273D02*
X4869635D01*
G01X4864105Y990273D02*
X4868135D01*
G01X4869105Y1306773D02*
X4873135D01*
G01X4871783Y1622212D02*
X4875813D01*
G01X4958807Y-118335D02*
Y-105835D01*
X4956947Y-108335D01*
G01Y-118335D02*
X4960667D01*
G01X4967797Y-116460D02*
X4968727Y-117502D01*
X4969812Y-118127D01*
X4971207Y-118335D01*
X4972602Y-117918D01*
X4973687Y-117085D01*
X4974462Y-115627D01*
X4974617Y-113960D01*
X4974307Y-112293D01*
X4973532Y-111252D01*
X4972447Y-110418D01*
X4971362Y-110210D01*
X4970277Y-110418D01*
X4968882Y-111252D01*
X4969347Y-105835D01*
X4973532D01*
G01X4983607D02*
X4982367Y-106252D01*
X4981437Y-107293D01*
X4980817Y-108543D01*
X4980352Y-110210D01*
X4980197Y-112085D01*
X4980352Y-113960D01*
X4980817Y-115627D01*
X4981437Y-116877D01*
X4982367Y-117918D01*
X4983607Y-118335D01*
X4984847Y-117918D01*
X4985777Y-116877D01*
X4986397Y-115627D01*
X4986862Y-113960D01*
X4987017Y-112085D01*
X4986862Y-110210D01*
X4986397Y-108543D01*
X4985777Y-107293D01*
X4984847Y-106252D01*
X4983607Y-105835D01*
G01X4958807Y-93335D02*
X4957567Y-93127D01*
X4956482Y-92294D01*
X4955552Y-91043D01*
X4954932Y-89585D01*
X4954622Y-87918D01*
Y-86252D01*
X4954932Y-84585D01*
X4955552Y-83127D01*
X4956482Y-81877D01*
X4957567Y-81043D01*
X4958807Y-80835D01*
X4960047Y-81043D01*
X4961132Y-81877D01*
X4962062Y-83127D01*
X4962682Y-84585D01*
X4962992Y-86252D01*
Y-87918D01*
X4962682Y-89585D01*
X4962062Y-91043D01*
X4961132Y-92294D01*
X4960047Y-93127D01*
X4958807Y-93335D01*
G01X4960047Y-90002D02*
X4961907Y-93335D01*
G01X4971207Y-80835D02*
Y-93335D01*
G01X4967642Y-80835D02*
X4974772D01*
G01X4983607Y-93335D02*
Y-87710D01*
X4980507Y-80835D01*
G01X4986707D02*
X4983607Y-87710D01*
G01X4953020Y163606D02*
X4951780Y163814D01*
X4950695Y164647D01*
X4949765Y165898D01*
X4949145Y167356D01*
X4948835Y169023D01*
Y170689D01*
X4949145Y172356D01*
X4949765Y173814D01*
X4950695Y175064D01*
X4951780Y175898D01*
X4953020Y176106D01*
X4954260Y175898D01*
X4955345Y175064D01*
X4956275Y173814D01*
X4956895Y172356D01*
X4957205Y170689D01*
Y169023D01*
X4956895Y167356D01*
X4956275Y165898D01*
X4955345Y164647D01*
X4954260Y163814D01*
X4953020Y163606D01*
G01X4954260Y166939D02*
X4956120Y163606D01*
G01X4965420Y176106D02*
Y163606D01*
G01X4961855Y176106D02*
X4968985D01*
G01X4977820Y163606D02*
Y169231D01*
X4974720Y176106D01*
G01X4980920D02*
X4977820Y169231D01*
G01X4956520Y434606D02*
X4955280Y434814D01*
X4954195Y435647D01*
X4953265Y436898D01*
X4952645Y438356D01*
X4952335Y440023D01*
Y441689D01*
X4952645Y443356D01*
X4953265Y444814D01*
X4954195Y446064D01*
X4955280Y446898D01*
X4956520Y447106D01*
X4957760Y446898D01*
X4958845Y446064D01*
X4959775Y444814D01*
X4960395Y443356D01*
X4960705Y441689D01*
Y440023D01*
X4960395Y438356D01*
X4959775Y436898D01*
X4958845Y435647D01*
X4957760Y434814D01*
X4956520Y434606D01*
G01X4957760Y437939D02*
X4959620Y434606D01*
G01X4968920Y447106D02*
Y434606D01*
G01X4965355Y447106D02*
X4972485D01*
G01X4981320Y434606D02*
Y440231D01*
X4978220Y447106D01*
G01X4984420D02*
X4981320Y440231D01*
G01X4957520Y707106D02*
X4956280Y707314D01*
X4955195Y708147D01*
X4954265Y709398D01*
X4953645Y710856D01*
X4953335Y712523D01*
Y714189D01*
X4953645Y715856D01*
X4954265Y717314D01*
X4955195Y718564D01*
X4956280Y719398D01*
X4957520Y719606D01*
X4958760Y719398D01*
X4959845Y718564D01*
X4960775Y717314D01*
X4961395Y715856D01*
X4961705Y714189D01*
Y712523D01*
X4961395Y710856D01*
X4960775Y709398D01*
X4959845Y708147D01*
X4958760Y707314D01*
X4957520Y707106D01*
G01X4958760Y710439D02*
X4960620Y707106D01*
G01X4969920Y719606D02*
Y707106D01*
G01X4966355Y719606D02*
X4973485D01*
G01X4982320Y707106D02*
Y712731D01*
X4979220Y719606D01*
G01X4985420D02*
X4982320Y712731D01*
G01X4953075Y996523D02*
X4954005Y997772D01*
X4955090Y998398D01*
X4956330Y998606D01*
X4957880Y998189D01*
X4958965Y997148D01*
X4959275Y995898D01*
X4959120Y994647D01*
X4958500Y993606D01*
X4955400Y991523D01*
X4954005Y990064D01*
X4953075Y987981D01*
X4952765Y986106D01*
X4959275D01*
G01X4970280D02*
Y998606D01*
X4964545Y989648D01*
X4972295D01*
G01X4980820Y998606D02*
X4979580Y998189D01*
X4978650Y997148D01*
X4978030Y995898D01*
X4977565Y994231D01*
X4977410Y992356D01*
X4977565Y990481D01*
X4978030Y988814D01*
X4978650Y987564D01*
X4979580Y986523D01*
X4980820Y986106D01*
X4982060Y986523D01*
X4982990Y987564D01*
X4983610Y988814D01*
X4984075Y990481D01*
X4984230Y992356D01*
X4984075Y994231D01*
X4983610Y995898D01*
X4982990Y997148D01*
X4982060Y998189D01*
X4980820Y998606D01*
G01X4956020Y1011106D02*
X4954780Y1011314D01*
X4953695Y1012147D01*
X4952765Y1013398D01*
X4952145Y1014856D01*
X4951835Y1016523D01*
Y1018189D01*
X4952145Y1019856D01*
X4952765Y1021314D01*
X4953695Y1022564D01*
X4954780Y1023398D01*
X4956020Y1023606D01*
X4957260Y1023398D01*
X4958345Y1022564D01*
X4959275Y1021314D01*
X4959895Y1019856D01*
X4960205Y1018189D01*
Y1016523D01*
X4959895Y1014856D01*
X4959275Y1013398D01*
X4958345Y1012147D01*
X4957260Y1011314D01*
X4956020Y1011106D01*
G01X4957260Y1014439D02*
X4959120Y1011106D01*
G01X4968420Y1023606D02*
Y1011106D01*
G01X4964855Y1023606D02*
X4971985D01*
G01X4980820Y1011106D02*
Y1016731D01*
X4977720Y1023606D01*
G01X4983920D02*
X4980820Y1016731D01*
G01X4961020Y1327606D02*
X4959780Y1327814D01*
X4958695Y1328647D01*
X4957765Y1329898D01*
X4957145Y1331356D01*
X4956835Y1333023D01*
Y1334689D01*
X4957145Y1336356D01*
X4957765Y1337814D01*
X4958695Y1339064D01*
X4959780Y1339898D01*
X4961020Y1340106D01*
X4962260Y1339898D01*
X4963345Y1339064D01*
X4964275Y1337814D01*
X4964895Y1336356D01*
X4965205Y1334689D01*
Y1333023D01*
X4964895Y1331356D01*
X4964275Y1329898D01*
X4963345Y1328647D01*
X4962260Y1327814D01*
X4961020Y1327606D01*
G01X4962260Y1330939D02*
X4964120Y1327606D01*
G01X4973420Y1340106D02*
Y1327606D01*
G01X4969855Y1340106D02*
X4976985D01*
G01X4985820Y1327606D02*
Y1333231D01*
X4982720Y1340106D01*
G01X4988920D02*
X4985820Y1333231D01*
G01X4965420Y138606D02*
X4966505Y138814D01*
X4967745Y139439D01*
X4968520Y140481D01*
X4968830Y141939D01*
X4968520Y143397D01*
X4967590Y144648D01*
X4966195Y145273D01*
X4964645D01*
X4963715Y145689D01*
X4962940Y146731D01*
X4962630Y148189D01*
X4963095Y149648D01*
X4964180Y150689D01*
X4965420Y151106D01*
X4966660Y150689D01*
X4967745Y149648D01*
X4968210Y148189D01*
X4967900Y146731D01*
X4967125Y145689D01*
X4966195Y145273D01*
X4964645D01*
X4963250Y144648D01*
X4962320Y143397D01*
X4962010Y141939D01*
X4962320Y140481D01*
X4963095Y139439D01*
X4964335Y138814D01*
X4965420Y138606D01*
G01X4962720Y409606D02*
Y422106D01*
X4960860Y419606D01*
G01Y409606D02*
X4964580D01*
G01X4972175Y420023D02*
X4973105Y421272D01*
X4974190Y421898D01*
X4975430Y422106D01*
X4976980Y421689D01*
X4978065Y420648D01*
X4978375Y419398D01*
X4978220Y418147D01*
X4977600Y417106D01*
X4974500Y415023D01*
X4973105Y413564D01*
X4972175Y411481D01*
X4971865Y409606D01*
X4978375D01*
G01X4965580Y682106D02*
Y694606D01*
X4959845Y685648D01*
X4967595D01*
G01X4977980Y682106D02*
Y694606D01*
X4972245Y685648D01*
X4979995D01*
G01X4973420Y1302606D02*
X4974505Y1302814D01*
X4975745Y1303439D01*
X4976520Y1304481D01*
X4976830Y1305939D01*
X4976520Y1307397D01*
X4975590Y1308648D01*
X4974195Y1309273D01*
X4972645D01*
X4971715Y1309689D01*
X4970940Y1310731D01*
X4970630Y1312189D01*
X4971095Y1313648D01*
X4972180Y1314689D01*
X4973420Y1315106D01*
X4974660Y1314689D01*
X4975745Y1313648D01*
X4976210Y1312189D01*
X4975900Y1310731D01*
X4975125Y1309689D01*
X4974195Y1309273D01*
X4972645D01*
X4971250Y1308648D01*
X4970320Y1307397D01*
X4970010Y1305939D01*
X4970320Y1304481D01*
X4971095Y1303439D01*
X4972335Y1302814D01*
X4973420Y1302606D01*
G01X4966488Y1620545D02*
X4967418Y1619086D01*
X4968658Y1618253D01*
X4970053Y1618045D01*
X4971293Y1618253D01*
X4972533Y1619295D01*
X4973308Y1620545D01*
X4973463Y1621795D01*
X4973153Y1623253D01*
X4972068Y1624295D01*
X4970983Y1624712D01*
X4969588D01*
G01X4970983D02*
X4971913Y1625337D01*
X4972688Y1626378D01*
X4972998Y1627628D01*
X4972688Y1628878D01*
X4971913Y1629920D01*
X4970518Y1630545D01*
X4969123Y1630337D01*
X4967728Y1629503D01*
G01X4979353Y1628462D02*
X4980283Y1629711D01*
X4981368Y1630337D01*
X4982608Y1630545D01*
X4984158Y1630128D01*
X4985243Y1629087D01*
X4985553Y1627837D01*
X4985398Y1626586D01*
X4984778Y1625545D01*
X4981678Y1623462D01*
X4980283Y1622003D01*
X4979353Y1619920D01*
X4979043Y1618045D01*
X4985553D01*
G01X4963698Y1643045D02*
X4962458Y1643253D01*
X4961373Y1644086D01*
X4960443Y1645337D01*
X4959823Y1646795D01*
X4959513Y1648462D01*
Y1650128D01*
X4959823Y1651795D01*
X4960443Y1653253D01*
X4961373Y1654503D01*
X4962458Y1655337D01*
X4963698Y1655545D01*
X4964938Y1655337D01*
X4966023Y1654503D01*
X4966953Y1653253D01*
X4967573Y1651795D01*
X4967883Y1650128D01*
Y1648462D01*
X4967573Y1646795D01*
X4966953Y1645337D01*
X4966023Y1644086D01*
X4964938Y1643253D01*
X4963698Y1643045D01*
G01X4964938Y1646378D02*
X4966798Y1643045D01*
G01X4976098Y1655545D02*
Y1643045D01*
G01X4972533Y1655545D02*
X4979663D01*
G01X4988498Y1643045D02*
Y1648670D01*
X4985398Y1655545D01*
G01X4991598D02*
X4988498Y1648670D01*
G01X5238704Y-17717D02*
X5239324Y-17092D01*
X5239789Y-16051D01*
X5240099Y-14592D01*
X5239789Y-13342D01*
X5239169Y-12509D01*
X5238084Y-11884D01*
X5233899D01*
Y-24384D01*
X5239014D01*
X5240099Y-23551D01*
X5240719Y-22301D01*
X5241029Y-20842D01*
X5240719Y-19384D01*
X5239789Y-18134D01*
X5238704Y-17717D01*
X5233899D01*
G01X5245989Y-24384D02*
X5249864Y-11884D01*
X5253739Y-24384D01*
G01X5252344Y-20009D02*
X5247384D01*
G01X5265674Y-12926D02*
X5264744Y-12301D01*
X5263659Y-11884D01*
X5262419D01*
X5261024Y-12509D01*
X5259939Y-13551D01*
X5259164Y-14801D01*
X5258544Y-16884D01*
X5258389Y-18759D01*
X5258699Y-20634D01*
X5259164Y-21884D01*
X5260094Y-23134D01*
X5261179Y-23967D01*
X5262264Y-24384D01*
X5263349D01*
X5264434Y-23967D01*
X5265364Y-23343D01*
X5266139Y-22509D01*
G01X5271254Y-24384D02*
Y-11884D01*
G01X5277144D02*
X5271254Y-19593D01*
G01X5278074Y-24384D02*
X5273889Y-16051D01*
G01X5283654Y-24384D02*
Y-11884D01*
X5286754D01*
X5287994Y-12509D01*
X5288924Y-13342D01*
X5289699Y-14592D01*
X5290319Y-16051D01*
X5290474Y-18134D01*
X5290319Y-20217D01*
X5289699Y-21676D01*
X5288924Y-22926D01*
X5287994Y-23759D01*
X5286754Y-24384D01*
X5283654D01*
G01X5296364D02*
Y-11884D01*
X5300239D01*
X5301479Y-12509D01*
X5302254Y-13342D01*
X5302564Y-15009D01*
X5302254Y-16676D01*
X5301324Y-17717D01*
X5300239Y-18342D01*
X5296364D01*
G01X5300239D02*
X5302564Y-24384D01*
G01X5310004Y-11884D02*
X5313724D01*
G01X5311864D02*
Y-24384D01*
G01X5310004D02*
X5313724D01*
G01X5321164Y-11884D02*
Y-24384D01*
X5327364D01*
G01X5333564Y-11884D02*
Y-24384D01*
X5339764D01*
G01X5358209Y-22718D02*
X5359449Y-23759D01*
X5360844Y-24384D01*
X5362084D01*
X5363324Y-23759D01*
X5364254Y-22718D01*
X5364719Y-21259D01*
X5364409Y-19801D01*
X5363634Y-18551D01*
X5362239Y-17717D01*
X5360379Y-17301D01*
X5359294Y-16467D01*
X5358829Y-15009D01*
X5359139Y-13551D01*
X5359914Y-12509D01*
X5360999Y-11884D01*
X5362084D01*
X5363169Y-12301D01*
X5364099Y-13342D01*
G01X5373864Y-11884D02*
Y-24384D01*
G01X5370299Y-11884D02*
X5377429D01*
G01X5382854D02*
Y-20842D01*
X5383474Y-22718D01*
X5384714Y-23967D01*
X5386264Y-24384D01*
X5387814Y-23967D01*
X5389054Y-22718D01*
X5389674Y-20842D01*
Y-11884D01*
G01X5399904Y-17717D02*
X5400524Y-17092D01*
X5400989Y-16051D01*
X5401299Y-14592D01*
X5400989Y-13342D01*
X5400369Y-12509D01*
X5399284Y-11884D01*
X5395099D01*
Y-24384D01*
X5400214D01*
X5401299Y-23551D01*
X5401919Y-22301D01*
X5402229Y-20842D01*
X5401919Y-19384D01*
X5400989Y-18134D01*
X5399904Y-17717D01*
X5395099D01*
G01X5420364Y-11884D02*
Y-24384D01*
X5426564D01*
G01X5438964D02*
X5432764D01*
Y-11884D01*
X5438964D01*
G01X5436484Y-17926D02*
X5432764D01*
G01X5444699Y-24384D02*
Y-11884D01*
X5451829Y-24384D01*
Y-11884D01*
G01X5461594Y-18134D02*
X5464694D01*
Y-21884D01*
X5463764Y-23134D01*
X5462679Y-23967D01*
X5461129Y-24384D01*
X5459579Y-23967D01*
X5458494Y-23134D01*
X5457564Y-21884D01*
X5456944Y-20426D01*
X5456634Y-18759D01*
Y-17301D01*
X5456944Y-16051D01*
X5457564Y-14592D01*
X5458494Y-13342D01*
X5459424Y-12509D01*
X5460664Y-11884D01*
X5461749D01*
X5462989Y-12301D01*
X5463919Y-13134D01*
G01X5473064Y-11884D02*
Y-24384D01*
G01X5469499Y-11884D02*
X5476629D01*
G01X5482209Y-24384D02*
Y-11884D01*
G01X5488719D02*
Y-24384D01*
G01Y-18134D02*
X5482209D01*
G01X5510264Y-11884D02*
Y-24384D01*
G01X5506699Y-11884D02*
X5513829D01*
G01X5522664Y-24384D02*
X5521424Y-24176D01*
X5520339Y-23343D01*
X5519409Y-22092D01*
X5518789Y-20634D01*
X5518479Y-18967D01*
Y-17301D01*
X5518789Y-15634D01*
X5519409Y-14176D01*
X5520339Y-12926D01*
X5521424Y-12092D01*
X5522664Y-11884D01*
X5523904Y-12092D01*
X5524989Y-12926D01*
X5525919Y-14176D01*
X5526539Y-15634D01*
X5526849Y-17301D01*
Y-18967D01*
X5526539Y-20634D01*
X5525919Y-22092D01*
X5524989Y-23343D01*
X5523904Y-24176D01*
X5522664Y-24384D01*
G01X5531964Y-11884D02*
Y-24384D01*
X5538164D01*
G01X5550564D02*
X5544364D01*
Y-11884D01*
X5550564D01*
G01X5548084Y-17926D02*
X5544364D01*
G01X5556764Y-24384D02*
Y-11884D01*
X5560639D01*
X5561879Y-12509D01*
X5562654Y-13342D01*
X5562964Y-15009D01*
X5562654Y-16676D01*
X5561724Y-17717D01*
X5560639Y-18342D01*
X5556764D01*
G01X5560639D02*
X5562964Y-24384D01*
G01X5568389D02*
X5572264Y-11884D01*
X5576139Y-24384D01*
G01X5574744Y-20009D02*
X5569784D01*
G01X5581099Y-24384D02*
Y-11884D01*
X5588229Y-24384D01*
Y-11884D01*
G01X5600474Y-12926D02*
X5599544Y-12301D01*
X5598459Y-11884D01*
X5597219D01*
X5595824Y-12509D01*
X5594739Y-13551D01*
X5593964Y-14801D01*
X5593344Y-16884D01*
X5593189Y-18759D01*
X5593499Y-20634D01*
X5593964Y-21884D01*
X5594894Y-23134D01*
X5595979Y-23967D01*
X5597064Y-24384D01*
X5598149D01*
X5599234Y-23967D01*
X5600164Y-23343D01*
X5600939Y-22509D01*
G01X5612564Y-24384D02*
X5606364D01*
Y-11884D01*
X5612564D01*
G01X5610084Y-17926D02*
X5606364D01*
G01X5634264Y-11884D02*
Y-24384D01*
G01X5630699Y-11884D02*
X5637829D01*
G01X5646664Y-24384D02*
X5645424Y-24176D01*
X5644339Y-23343D01*
X5643409Y-22092D01*
X5642789Y-20634D01*
X5642479Y-18967D01*
Y-17301D01*
X5642789Y-15634D01*
X5643409Y-14176D01*
X5644339Y-12926D01*
X5645424Y-12092D01*
X5646664Y-11884D01*
X5647904Y-12092D01*
X5648989Y-12926D01*
X5649919Y-14176D01*
X5650539Y-15634D01*
X5650849Y-17301D01*
Y-18967D01*
X5650539Y-20634D01*
X5649919Y-22092D01*
X5648989Y-23343D01*
X5647904Y-24176D01*
X5646664Y-24384D01*
G01X5672704Y-17717D02*
X5673324Y-17092D01*
X5673789Y-16051D01*
X5674099Y-14592D01*
X5673789Y-13342D01*
X5673169Y-12509D01*
X5672084Y-11884D01*
X5667899D01*
Y-24384D01*
X5673014D01*
X5674099Y-23551D01*
X5674719Y-22301D01*
X5675029Y-20842D01*
X5674719Y-19384D01*
X5673789Y-18134D01*
X5672704Y-17717D01*
X5667899D01*
G01X5686964Y-24384D02*
X5680764D01*
Y-11884D01*
X5686964D01*
G01X5684484Y-17926D02*
X5680764D01*
G01X5708354Y-24384D02*
X5708664Y-21676D01*
X5709129Y-19384D01*
X5709749Y-17301D01*
X5710524Y-15009D01*
X5711764Y-11884D01*
X5705564D01*
G01X5731759Y-20217D02*
X5735479D01*
G01X5733464Y-17509D02*
Y-22926D01*
G01X5743074Y-24801D02*
X5748654Y-11884D01*
G01X5756249Y-20217D02*
X5760279D01*
G01X5767254Y-22509D02*
X5768184Y-23551D01*
X5769269Y-24176D01*
X5770664Y-24384D01*
X5772059Y-23967D01*
X5773144Y-23134D01*
X5773919Y-21676D01*
X5774074Y-20009D01*
X5773764Y-18342D01*
X5772989Y-17301D01*
X5771904Y-16467D01*
X5770819Y-16259D01*
X5769734Y-16467D01*
X5768339Y-17301D01*
X5768804Y-11884D01*
X5772989D01*
G01X5791434Y-24384D02*
Y-11884D01*
X5795464Y-22301D01*
X5799494Y-11884D01*
Y-24384D01*
G01X5806004Y-11884D02*
X5809724D01*
G01X5807864D02*
Y-24384D01*
G01X5806004D02*
X5809724D01*
G01X5817164Y-11884D02*
Y-24384D01*
X5823364D01*
G01X5829409Y-22718D02*
X5830649Y-23759D01*
X5832044Y-24384D01*
X5833284D01*
X5834524Y-23759D01*
X5835454Y-22718D01*
X5835919Y-21259D01*
X5835609Y-19801D01*
X5834834Y-18551D01*
X5833439Y-17717D01*
X5831579Y-17301D01*
X5830494Y-16467D01*
X5830029Y-15009D01*
X5830339Y-13551D01*
X5831114Y-12509D01*
X5832199Y-11884D01*
X5833284D01*
X5834369Y-12301D01*
X5835299Y-13342D01*
G01X5074249Y-1467D02*
X5078279D01*
G01X5097034Y-5634D02*
Y6866D01*
X5101064Y-3551D01*
X5105094Y6866D01*
Y-5634D01*
G01X5110519D02*
Y6866D01*
X5116409D01*
G01X5114239Y824D02*
X5110519D01*
G01X5126794Y616D02*
X5129894D01*
Y-3134D01*
X5128964Y-4384D01*
X5127879Y-5217D01*
X5126329Y-5634D01*
X5124779Y-5217D01*
X5123694Y-4384D01*
X5122764Y-3134D01*
X5122144Y-1676D01*
X5121834Y-9D01*
Y1449D01*
X5122144Y2699D01*
X5122764Y4158D01*
X5123694Y5408D01*
X5124624Y6241D01*
X5125864Y6866D01*
X5126949D01*
X5128189Y6449D01*
X5129119Y5616D01*
G01X5133614Y-9801D02*
X5142914D01*
G01X5147409Y-3968D02*
X5148649Y-5009D01*
X5150044Y-5634D01*
X5151284D01*
X5152524Y-5009D01*
X5153454Y-3968D01*
X5153919Y-2509D01*
X5153609Y-1051D01*
X5152834Y199D01*
X5151439Y1033D01*
X5149579Y1449D01*
X5148494Y2283D01*
X5148029Y3741D01*
X5148339Y5199D01*
X5149114Y6241D01*
X5150199Y6866D01*
X5151284D01*
X5152369Y6449D01*
X5153299Y5408D01*
G01X5163064Y6866D02*
Y-5634D01*
G01X5159499Y6866D02*
X5166629D01*
G01X5172054D02*
Y-2092D01*
X5172674Y-3968D01*
X5173914Y-5217D01*
X5175464Y-5634D01*
X5177014Y-5217D01*
X5178254Y-3968D01*
X5178874Y-2092D01*
Y6866D01*
G01X5189104Y1033D02*
X5189724Y1658D01*
X5190189Y2699D01*
X5190499Y4158D01*
X5190189Y5408D01*
X5189569Y6241D01*
X5188484Y6866D01*
X5184299D01*
Y-5634D01*
X5189414D01*
X5190499Y-4801D01*
X5191119Y-3551D01*
X5191429Y-2092D01*
X5191119Y-634D01*
X5190189Y616D01*
X5189104Y1033D01*
X5184299D01*
G01X5212664Y-6051D02*
X5212354Y-5842D01*
Y-5426D01*
X5212664Y-5217D01*
X5212974Y-5426D01*
Y-5842D01*
X5212664Y-6051D01*
G01Y-426D02*
X5212354Y-217D01*
Y199D01*
X5212664Y408D01*
X5212974Y199D01*
Y-217D01*
X5212664Y-426D01*
G01X5233434Y-5634D02*
Y6866D01*
X5237464Y-3551D01*
X5241494Y6866D01*
Y-5634D01*
G01X5245989D02*
X5249864Y6866D01*
X5253739Y-5634D01*
G01X5252344Y-1259D02*
X5247384D01*
G01X5258699Y-5634D02*
Y6866D01*
X5265829Y-5634D01*
Y6866D01*
G01X5271254D02*
Y-2092D01*
X5271874Y-3968D01*
X5273114Y-5217D01*
X5274664Y-5634D01*
X5276214Y-5217D01*
X5277454Y-3968D01*
X5278074Y-2092D01*
Y6866D01*
G01X5284119Y-5634D02*
Y6866D01*
X5290009D01*
G01X5287839Y824D02*
X5284119D01*
G01X5295589Y-5634D02*
X5299464Y6866D01*
X5303339Y-5634D01*
G01X5301944Y-1259D02*
X5296984D01*
G01X5315274Y5824D02*
X5314344Y6449D01*
X5313259Y6866D01*
X5312019D01*
X5310624Y6241D01*
X5309539Y5199D01*
X5308764Y3949D01*
X5308144Y1866D01*
X5307989Y-9D01*
X5308299Y-1884D01*
X5308764Y-3134D01*
X5309694Y-4384D01*
X5310779Y-5217D01*
X5311864Y-5634D01*
X5312949D01*
X5314034Y-5217D01*
X5314964Y-4593D01*
X5315739Y-3759D01*
G01X5324264Y6866D02*
Y-5634D01*
G01X5320699Y6866D02*
X5327829D01*
G01X5333254D02*
Y-2092D01*
X5333874Y-3968D01*
X5335114Y-5217D01*
X5336664Y-5634D01*
X5338214Y-5217D01*
X5339454Y-3968D01*
X5340074Y-2092D01*
Y6866D01*
G01X5345964Y-5634D02*
Y6866D01*
X5349839D01*
X5351079Y6241D01*
X5351854Y5408D01*
X5352164Y3741D01*
X5351854Y2074D01*
X5350924Y1033D01*
X5349839Y408D01*
X5345964D01*
G01X5349839D02*
X5352164Y-5634D01*
G01X5359604Y6866D02*
X5363324D01*
G01X5361464D02*
Y-5634D01*
G01X5359604D02*
X5363324D01*
G01X5370299D02*
Y6866D01*
X5377429Y-5634D01*
Y6866D01*
G01X5387194Y616D02*
X5390294D01*
Y-3134D01*
X5389364Y-4384D01*
X5388279Y-5217D01*
X5386729Y-5634D01*
X5385179Y-5217D01*
X5384094Y-4384D01*
X5383164Y-3134D01*
X5382544Y-1676D01*
X5382234Y-9D01*
Y1449D01*
X5382544Y2699D01*
X5383164Y4158D01*
X5384094Y5408D01*
X5385024Y6241D01*
X5386264Y6866D01*
X5387349D01*
X5388589Y6449D01*
X5389519Y5616D01*
G01X5407809Y-3968D02*
X5409049Y-5009D01*
X5410444Y-5634D01*
X5411684D01*
X5412924Y-5009D01*
X5413854Y-3968D01*
X5414319Y-2509D01*
X5414009Y-1051D01*
X5413234Y199D01*
X5411839Y1033D01*
X5409979Y1449D01*
X5408894Y2283D01*
X5408429Y3741D01*
X5408739Y5199D01*
X5409514Y6241D01*
X5410599Y6866D01*
X5411684D01*
X5412769Y6449D01*
X5413699Y5408D01*
G01X5423464Y6866D02*
Y-5634D01*
G01X5419899Y6866D02*
X5427029D01*
G01X5432454D02*
Y-2092D01*
X5433074Y-3968D01*
X5434314Y-5217D01*
X5435864Y-5634D01*
X5437414Y-5217D01*
X5438654Y-3968D01*
X5439274Y-2092D01*
Y6866D01*
G01X5449504Y1033D02*
X5450124Y1658D01*
X5450589Y2699D01*
X5450899Y4158D01*
X5450589Y5408D01*
X5449969Y6241D01*
X5448884Y6866D01*
X5444699D01*
Y-5634D01*
X5449814D01*
X5450899Y-4801D01*
X5451519Y-3551D01*
X5451829Y-2092D01*
X5451519Y-634D01*
X5450589Y616D01*
X5449504Y1033D01*
X5444699D01*
G01X5469964Y6866D02*
Y-5634D01*
X5476164D01*
G01X5488564D02*
X5482364D01*
Y6866D01*
X5488564D01*
G01X5486084Y824D02*
X5482364D01*
G01X5494299Y-5634D02*
Y6866D01*
X5501429Y-5634D01*
Y6866D01*
G01X5511194Y616D02*
X5514294D01*
Y-3134D01*
X5513364Y-4384D01*
X5512279Y-5217D01*
X5510729Y-5634D01*
X5509179Y-5217D01*
X5508094Y-4384D01*
X5507164Y-3134D01*
X5506544Y-1676D01*
X5506234Y-9D01*
Y1449D01*
X5506544Y2699D01*
X5507164Y4158D01*
X5508094Y5408D01*
X5509024Y6241D01*
X5510264Y6866D01*
X5511349D01*
X5512589Y6449D01*
X5513519Y5616D01*
G01X5522664Y6866D02*
Y-5634D01*
G01X5519099Y6866D02*
X5526229D01*
G01X5531809Y-5634D02*
Y6866D01*
G01X5538319D02*
Y-5634D01*
G01Y616D02*
X5531809D01*
G01X5234209Y14782D02*
X5235449Y13741D01*
X5236844Y13116D01*
X5238084D01*
X5239324Y13741D01*
X5240254Y14782D01*
X5240719Y16241D01*
X5240409Y17699D01*
X5239634Y18949D01*
X5238239Y19783D01*
X5236379Y20199D01*
X5235294Y21033D01*
X5234829Y22491D01*
X5235139Y23949D01*
X5235914Y24991D01*
X5236999Y25616D01*
X5238084D01*
X5239169Y25199D01*
X5240099Y24158D01*
G01X5246454Y25616D02*
Y16658D01*
X5247074Y14782D01*
X5248314Y13533D01*
X5249864Y13116D01*
X5251414Y13533D01*
X5252654Y14782D01*
X5253274Y16658D01*
Y25616D01*
G01X5259164Y13116D02*
Y25616D01*
X5263039D01*
X5264279Y24991D01*
X5265054Y24158D01*
X5265364Y22491D01*
X5265054Y20824D01*
X5264124Y19783D01*
X5263039Y19158D01*
X5259164D01*
G01X5263039D02*
X5265364Y13116D01*
G01X5271719D02*
Y25616D01*
X5277609D01*
G01X5275439Y19574D02*
X5271719D01*
G01X5283189Y13116D02*
X5287064Y25616D01*
X5290939Y13116D01*
G01X5289544Y17491D02*
X5284584D01*
G01X5302874Y24574D02*
X5301944Y25199D01*
X5300859Y25616D01*
X5299619D01*
X5298224Y24991D01*
X5297139Y23949D01*
X5296364Y22699D01*
X5295744Y20616D01*
X5295589Y18741D01*
X5295899Y16866D01*
X5296364Y15616D01*
X5297294Y14366D01*
X5298379Y13533D01*
X5299464Y13116D01*
X5300549D01*
X5301634Y13533D01*
X5302564Y14157D01*
X5303339Y14991D01*
G01X5314964Y13116D02*
X5308764D01*
Y25616D01*
X5314964D01*
G01X5312484Y19574D02*
X5308764D01*
G01X5336664Y13116D02*
X5335424Y13324D01*
X5334339Y14157D01*
X5333409Y15408D01*
X5332789Y16866D01*
X5332479Y18533D01*
Y20199D01*
X5332789Y21866D01*
X5333409Y23324D01*
X5334339Y24574D01*
X5335424Y25408D01*
X5336664Y25616D01*
X5337904Y25408D01*
X5338989Y24574D01*
X5339919Y23324D01*
X5340539Y21866D01*
X5340849Y20199D01*
Y18533D01*
X5340539Y16866D01*
X5339919Y15408D01*
X5338989Y14157D01*
X5337904Y13324D01*
X5336664Y13116D01*
G01X5346119D02*
Y25616D01*
X5352009D01*
G01X5349839Y19574D02*
X5346119D01*
G01X5369834Y13116D02*
Y25616D01*
X5373864Y15199D01*
X5377894Y25616D01*
Y13116D01*
G01X5382854Y25616D02*
Y16658D01*
X5383474Y14782D01*
X5384714Y13533D01*
X5386264Y13116D01*
X5387814Y13533D01*
X5389054Y14782D01*
X5389674Y16658D01*
Y25616D01*
G01X5395409Y14782D02*
X5396649Y13741D01*
X5398044Y13116D01*
X5399284D01*
X5400524Y13741D01*
X5401454Y14782D01*
X5401919Y16241D01*
X5401609Y17699D01*
X5400834Y18949D01*
X5399439Y19783D01*
X5397579Y20199D01*
X5396494Y21033D01*
X5396029Y22491D01*
X5396339Y23949D01*
X5397114Y24991D01*
X5398199Y25616D01*
X5399284D01*
X5400369Y25199D01*
X5401299Y24158D01*
G01X5411064Y25616D02*
Y13116D01*
G01X5407499Y25616D02*
X5414629D01*
G01X5421449Y17283D02*
X5425479D01*
G01X5432299Y13116D02*
Y25616D01*
X5439429Y13116D01*
Y25616D01*
G01X5448264Y13116D02*
X5447024Y13324D01*
X5445939Y14157D01*
X5445009Y15408D01*
X5444389Y16866D01*
X5444079Y18533D01*
Y20199D01*
X5444389Y21866D01*
X5445009Y23324D01*
X5445939Y24574D01*
X5447024Y25408D01*
X5448264Y25616D01*
X5449504Y25408D01*
X5450589Y24574D01*
X5451519Y23324D01*
X5452139Y21866D01*
X5452449Y20199D01*
Y18533D01*
X5452139Y16866D01*
X5451519Y15408D01*
X5450589Y14157D01*
X5449504Y13324D01*
X5448264Y13116D01*
G01X5460664Y25616D02*
Y13116D01*
G01X5457099Y25616D02*
X5464229D01*
G01X5471049Y17283D02*
X5475079D01*
G01X5488874Y24574D02*
X5487944Y25199D01*
X5486859Y25616D01*
X5485619D01*
X5484224Y24991D01*
X5483139Y23949D01*
X5482364Y22699D01*
X5481744Y20616D01*
X5481589Y18741D01*
X5481899Y16866D01*
X5482364Y15616D01*
X5483294Y14366D01*
X5484379Y13533D01*
X5485464Y13116D01*
X5486549D01*
X5487634Y13533D01*
X5488564Y14157D01*
X5489339Y14991D01*
G01X5494454Y25616D02*
Y16658D01*
X5495074Y14782D01*
X5496314Y13533D01*
X5497864Y13116D01*
X5499414Y13533D01*
X5500654Y14782D01*
X5501274Y16658D01*
Y25616D01*
G01X5510264D02*
Y13116D01*
G01X5506699Y25616D02*
X5513829D01*
G01X5520649Y17283D02*
X5524679D01*
G01X5531964Y25616D02*
Y13116D01*
X5538164D01*
G01X5543589D02*
X5547464Y25616D01*
X5551339Y13116D01*
G01X5549944Y17491D02*
X5544984D01*
G01X5559864Y13116D02*
Y18741D01*
X5556764Y25616D01*
G01X5562964D02*
X5559864Y18741D01*
G01X5575364Y13116D02*
X5569164D01*
Y25616D01*
X5575364D01*
G01X5572884Y19574D02*
X5569164D01*
G01X5581564Y13116D02*
Y25616D01*
X5585439D01*
X5586679Y24991D01*
X5587454Y24158D01*
X5587764Y22491D01*
X5587454Y20824D01*
X5586524Y19783D01*
X5585439Y19158D01*
X5581564D01*
G01X5585439D02*
X5587764Y13116D01*
G01X5074249Y36033D02*
X5078279D01*
G01X5097034Y31866D02*
Y44366D01*
X5101064Y33949D01*
X5105094Y44366D01*
Y31866D01*
G01X5109589D02*
X5113464Y44366D01*
X5117339Y31866D01*
G01X5115944Y36241D02*
X5110984D01*
G01X5122609Y31866D02*
X5129119Y44366D01*
G01X5122609D02*
X5129119Y31866D01*
G01X5133614Y27699D02*
X5142914D01*
G01X5147254Y31866D02*
Y44366D01*
X5150354D01*
X5151594Y43741D01*
X5152524Y42908D01*
X5153299Y41658D01*
X5153919Y40199D01*
X5154074Y38116D01*
X5153919Y36033D01*
X5153299Y34574D01*
X5152524Y33324D01*
X5151594Y32491D01*
X5150354Y31866D01*
X5147254D01*
G01X5166164D02*
X5159964D01*
Y44366D01*
X5166164D01*
G01X5163684Y38324D02*
X5159964D01*
G01X5172364Y31866D02*
Y44366D01*
X5176084D01*
X5177324Y43741D01*
X5178254Y42283D01*
X5178564Y40616D01*
X5178254Y38949D01*
X5177479Y37699D01*
X5176084Y37074D01*
X5172364D01*
G01X5187864Y44366D02*
Y31866D01*
G01X5184299Y44366D02*
X5191429D01*
G01X5197009Y31866D02*
Y44366D01*
G01X5203519D02*
Y31866D01*
G01Y38116D02*
X5197009D01*
G01X5212664Y31449D02*
X5212354Y31658D01*
Y32074D01*
X5212664Y32283D01*
X5212974Y32074D01*
Y31658D01*
X5212664Y31449D01*
G01Y37074D02*
X5212354Y37283D01*
Y37699D01*
X5212664Y37908D01*
X5212974Y37699D01*
Y37283D01*
X5212664Y37074D01*
G01X5234054Y31866D02*
Y44366D01*
X5237154D01*
X5238394Y43741D01*
X5239324Y42908D01*
X5240099Y41658D01*
X5240719Y40199D01*
X5240874Y38116D01*
X5240719Y36033D01*
X5240099Y34574D01*
X5239324Y33324D01*
X5238394Y32491D01*
X5237154Y31866D01*
X5234054D01*
G01X5252964D02*
X5246764D01*
Y44366D01*
X5252964D01*
G01X5250484Y38324D02*
X5246764D01*
G01X5259164Y31866D02*
Y44366D01*
X5262884D01*
X5264124Y43741D01*
X5265054Y42283D01*
X5265364Y40616D01*
X5265054Y38949D01*
X5264279Y37699D01*
X5262884Y37074D01*
X5259164D01*
G01X5274664Y44366D02*
Y31866D01*
G01X5271099Y44366D02*
X5278229D01*
G01X5283809Y31866D02*
Y44366D01*
G01X5290319D02*
Y31866D01*
G01Y38116D02*
X5283809D01*
G01X5308919Y31866D02*
Y44366D01*
X5314809D01*
G01X5312639Y38324D02*
X5308919D01*
G01X5321164Y31866D02*
Y44366D01*
X5325039D01*
X5326279Y43741D01*
X5327054Y42908D01*
X5327364Y41241D01*
X5327054Y39574D01*
X5326124Y38533D01*
X5325039Y37908D01*
X5321164D01*
G01X5325039D02*
X5327364Y31866D01*
G01X5336664D02*
X5335424Y32074D01*
X5334339Y32907D01*
X5333409Y34158D01*
X5332789Y35616D01*
X5332479Y37283D01*
Y38949D01*
X5332789Y40616D01*
X5333409Y42074D01*
X5334339Y43324D01*
X5335424Y44158D01*
X5336664Y44366D01*
X5337904Y44158D01*
X5338989Y43324D01*
X5339919Y42074D01*
X5340539Y40616D01*
X5340849Y38949D01*
Y37283D01*
X5340539Y35616D01*
X5339919Y34158D01*
X5338989Y32907D01*
X5337904Y32074D01*
X5336664Y31866D01*
G01X5345034D02*
Y44366D01*
X5349064Y33949D01*
X5353094Y44366D01*
Y31866D01*
G01X5370609Y33532D02*
X5371849Y32491D01*
X5373244Y31866D01*
X5374484D01*
X5375724Y32491D01*
X5376654Y33532D01*
X5377119Y34991D01*
X5376809Y36449D01*
X5376034Y37699D01*
X5374639Y38533D01*
X5372779Y38949D01*
X5371694Y39783D01*
X5371229Y41241D01*
X5371539Y42699D01*
X5372314Y43741D01*
X5373399Y44366D01*
X5374484D01*
X5375569Y43949D01*
X5376499Y42908D01*
G01X5386264Y44366D02*
Y31866D01*
G01X5382699Y44366D02*
X5389829D01*
G01X5394789Y31866D02*
X5398664Y44366D01*
X5402539Y31866D01*
G01X5401144Y36241D02*
X5396184D01*
G01X5407964Y31866D02*
Y44366D01*
X5411839D01*
X5413079Y43741D01*
X5413854Y42908D01*
X5414164Y41241D01*
X5413854Y39574D01*
X5412924Y38533D01*
X5411839Y37908D01*
X5407964D01*
G01X5411839D02*
X5414164Y31866D01*
G01X5423464Y44366D02*
Y31866D01*
G01X5419899Y44366D02*
X5427029D01*
G01X5445164D02*
Y31866D01*
X5451364D01*
G01X5456789D02*
X5460664Y44366D01*
X5464539Y31866D01*
G01X5463144Y36241D02*
X5458184D01*
G01X5473064Y31866D02*
Y37491D01*
X5469964Y44366D01*
G01X5476164D02*
X5473064Y37491D01*
G01X5488564Y31866D02*
X5482364D01*
Y44366D01*
X5488564D01*
G01X5486084Y38324D02*
X5482364D01*
G01X5494764Y31866D02*
Y44366D01*
X5498639D01*
X5499879Y43741D01*
X5500654Y42908D01*
X5500964Y41241D01*
X5500654Y39574D01*
X5499724Y38533D01*
X5498639Y37908D01*
X5494764D01*
G01X5498639D02*
X5500964Y31866D01*
G01X5522664Y44366D02*
Y31866D01*
G01X5519099Y44366D02*
X5526229D01*
G01X5535064Y31866D02*
X5533824Y32074D01*
X5532739Y32907D01*
X5531809Y34158D01*
X5531189Y35616D01*
X5530879Y37283D01*
Y38949D01*
X5531189Y40616D01*
X5531809Y42074D01*
X5532739Y43324D01*
X5533824Y44158D01*
X5535064Y44366D01*
X5536304Y44158D01*
X5537389Y43324D01*
X5538319Y42074D01*
X5538939Y40616D01*
X5539249Y38949D01*
Y37283D01*
X5538939Y35616D01*
X5538319Y34158D01*
X5537389Y32907D01*
X5536304Y32074D01*
X5535064Y31866D01*
G01X5559864Y44366D02*
Y31866D01*
G01X5556299Y44366D02*
X5563429D01*
G01X5569009Y31866D02*
Y44366D01*
G01X5575519D02*
Y31866D01*
G01Y38116D02*
X5569009D01*
G01X5587764Y31866D02*
X5581564D01*
Y44366D01*
X5587764D01*
G01X5585284Y38324D02*
X5581564D01*
G01X5074249Y54783D02*
X5078279D01*
G01X5097034Y50616D02*
Y63116D01*
X5101064Y52699D01*
X5105094Y63116D01*
Y50616D01*
G01X5109899D02*
Y63116D01*
X5117029Y50616D01*
Y63116D01*
G01X5129274Y62074D02*
X5128344Y62699D01*
X5127259Y63116D01*
X5126019D01*
X5124624Y62491D01*
X5123539Y61449D01*
X5122764Y60199D01*
X5122144Y58116D01*
X5121989Y56241D01*
X5122299Y54366D01*
X5122764Y53116D01*
X5123694Y51866D01*
X5124779Y51033D01*
X5125864Y50616D01*
X5126949D01*
X5128034Y51033D01*
X5128964Y51657D01*
X5129739Y52491D01*
G01X5133614Y46449D02*
X5142914D01*
G01X5147564Y63116D02*
Y50616D01*
X5153764D01*
G01X5159189D02*
X5163064Y63116D01*
X5166939Y50616D01*
G01X5165544Y54991D02*
X5160584D01*
G01X5175464Y50616D02*
Y56241D01*
X5172364Y63116D01*
G01X5178564D02*
X5175464Y56241D01*
G01X5190964Y50616D02*
X5184764D01*
Y63116D01*
X5190964D01*
G01X5188484Y57074D02*
X5184764D01*
G01X5197164Y50616D02*
Y63116D01*
X5201039D01*
X5202279Y62491D01*
X5203054Y61658D01*
X5203364Y59991D01*
X5203054Y58324D01*
X5202124Y57283D01*
X5201039Y56658D01*
X5197164D01*
G01X5201039D02*
X5203364Y50616D01*
G01X5212664Y50199D02*
X5212354Y50408D01*
Y50824D01*
X5212664Y51033D01*
X5212974Y50824D01*
Y50408D01*
X5212664Y50199D01*
G01Y55824D02*
X5212354Y56033D01*
Y56449D01*
X5212664Y56658D01*
X5212974Y56449D01*
Y56033D01*
X5212664Y55824D01*
G01X5233434Y50616D02*
Y63116D01*
X5237464Y52699D01*
X5241494Y63116D01*
Y50616D01*
G01X5246454Y63116D02*
Y54158D01*
X5247074Y52282D01*
X5248314Y51033D01*
X5249864Y50616D01*
X5251414Y51033D01*
X5252654Y52282D01*
X5253274Y54158D01*
Y63116D01*
G01X5259009Y52282D02*
X5260249Y51241D01*
X5261644Y50616D01*
X5262884D01*
X5264124Y51241D01*
X5265054Y52282D01*
X5265519Y53741D01*
X5265209Y55199D01*
X5264434Y56449D01*
X5263039Y57283D01*
X5261179Y57699D01*
X5260094Y58533D01*
X5259629Y59991D01*
X5259939Y61449D01*
X5260714Y62491D01*
X5261799Y63116D01*
X5262884D01*
X5263969Y62699D01*
X5264899Y61658D01*
G01X5274664Y63116D02*
Y50616D01*
G01X5271099Y63116D02*
X5278229D01*
G01X5285049Y54783D02*
X5289079D01*
G01X5295899Y50616D02*
Y63116D01*
X5303029Y50616D01*
Y63116D01*
G01X5311864Y50616D02*
X5310624Y50824D01*
X5309539Y51657D01*
X5308609Y52908D01*
X5307989Y54366D01*
X5307679Y56033D01*
Y57699D01*
X5307989Y59366D01*
X5308609Y60824D01*
X5309539Y62074D01*
X5310624Y62908D01*
X5311864Y63116D01*
X5313104Y62908D01*
X5314189Y62074D01*
X5315119Y60824D01*
X5315739Y59366D01*
X5316049Y57699D01*
Y56033D01*
X5315739Y54366D01*
X5315119Y52908D01*
X5314189Y51657D01*
X5313104Y50824D01*
X5311864Y50616D01*
G01X5324264Y63116D02*
Y50616D01*
G01X5320699Y63116D02*
X5327829D01*
G01X5334649Y54783D02*
X5338679D01*
G01X5352474Y62074D02*
X5351544Y62699D01*
X5350459Y63116D01*
X5349219D01*
X5347824Y62491D01*
X5346739Y61449D01*
X5345964Y60199D01*
X5345344Y58116D01*
X5345189Y56241D01*
X5345499Y54366D01*
X5345964Y53116D01*
X5346894Y51866D01*
X5347979Y51033D01*
X5349064Y50616D01*
X5350149D01*
X5351234Y51033D01*
X5352164Y51657D01*
X5352939Y52491D01*
G01X5358054Y63116D02*
Y54158D01*
X5358674Y52282D01*
X5359914Y51033D01*
X5361464Y50616D01*
X5363014Y51033D01*
X5364254Y52282D01*
X5364874Y54158D01*
Y63116D01*
G01X5373864D02*
Y50616D01*
G01X5370299Y63116D02*
X5377429D01*
G01X5384249Y54783D02*
X5388279D01*
G01X5395564Y63116D02*
Y50616D01*
X5401764D01*
G01X5407189D02*
X5411064Y63116D01*
X5414939Y50616D01*
G01X5413544Y54991D02*
X5408584D01*
G01X5423464Y50616D02*
Y56241D01*
X5420364Y63116D01*
G01X5426564D02*
X5423464Y56241D01*
G01X5438964Y50616D02*
X5432764D01*
Y63116D01*
X5438964D01*
G01X5436484Y57074D02*
X5432764D01*
G01X5445164Y50616D02*
Y63116D01*
X5449039D01*
X5450279Y62491D01*
X5451054Y61658D01*
X5451364Y59991D01*
X5451054Y58324D01*
X5450124Y57283D01*
X5449039Y56658D01*
X5445164D01*
G01X5449039D02*
X5451364Y50616D01*
G01X5072699Y69366D02*
Y81866D01*
X5079829Y69366D01*
Y81866D01*
G01X5088664Y69366D02*
X5087424Y69574D01*
X5086339Y70407D01*
X5085409Y71658D01*
X5084789Y73116D01*
X5084479Y74783D01*
Y76449D01*
X5084789Y78116D01*
X5085409Y79574D01*
X5086339Y80824D01*
X5087424Y81658D01*
X5088664Y81866D01*
X5089904Y81658D01*
X5090989Y80824D01*
X5091919Y79574D01*
X5092539Y78116D01*
X5092849Y76449D01*
Y74783D01*
X5092539Y73116D01*
X5091919Y71658D01*
X5090989Y70407D01*
X5089904Y69574D01*
X5088664Y69366D01*
G01X5101064Y81866D02*
Y69366D01*
G01X5097499Y81866D02*
X5104629D01*
G01X5116564Y69366D02*
X5110364D01*
Y81866D01*
X5116564D01*
G01X5114084Y75824D02*
X5110364D01*
G01X5122609Y71032D02*
X5123849Y69991D01*
X5125244Y69366D01*
X5126484D01*
X5127724Y69991D01*
X5128654Y71032D01*
X5129119Y72491D01*
X5128809Y73949D01*
X5128034Y75199D01*
X5126639Y76033D01*
X5124779Y76449D01*
X5123694Y77283D01*
X5123229Y78741D01*
X5123539Y80199D01*
X5124314Y81241D01*
X5125399Y81866D01*
X5126484D01*
X5127569Y81449D01*
X5128499Y80408D01*
G01X5138264Y68949D02*
X5137954Y69158D01*
Y69574D01*
X5138264Y69783D01*
X5138574Y69574D01*
Y69158D01*
X5138264Y68949D01*
G01Y74574D02*
X5137954Y74783D01*
Y75199D01*
X5138264Y75408D01*
X5138574Y75199D01*
Y74783D01*
X5138264Y74574D01*
G01X5238670Y255102D02*
X5239290Y255727D01*
X5239755Y256768D01*
X5240065Y258227D01*
X5239755Y259477D01*
X5239135Y260310D01*
X5238050Y260935D01*
X5233865D01*
Y248435D01*
X5238980D01*
X5240065Y249268D01*
X5240685Y250518D01*
X5240995Y251977D01*
X5240685Y253435D01*
X5239755Y254685D01*
X5238670Y255102D01*
X5233865D01*
G01X5245955Y248435D02*
X5249830Y260935D01*
X5253705Y248435D01*
G01X5252310Y252810D02*
X5247350D01*
G01X5265640Y259893D02*
X5264710Y260518D01*
X5263625Y260935D01*
X5262385D01*
X5260990Y260310D01*
X5259905Y259268D01*
X5259130Y258018D01*
X5258510Y255935D01*
X5258355Y254060D01*
X5258665Y252185D01*
X5259130Y250935D01*
X5260060Y249685D01*
X5261145Y248852D01*
X5262230Y248435D01*
X5263315D01*
X5264400Y248852D01*
X5265330Y249476D01*
X5266105Y250310D01*
G01X5271220Y248435D02*
Y260935D01*
G01X5277110D02*
X5271220Y253226D01*
G01X5278040Y248435D02*
X5273855Y256768D01*
G01X5283620Y248435D02*
Y260935D01*
X5286720D01*
X5287960Y260310D01*
X5288890Y259477D01*
X5289665Y258227D01*
X5290285Y256768D01*
X5290440Y254685D01*
X5290285Y252602D01*
X5289665Y251143D01*
X5288890Y249893D01*
X5287960Y249060D01*
X5286720Y248435D01*
X5283620D01*
G01X5296330D02*
Y260935D01*
X5300205D01*
X5301445Y260310D01*
X5302220Y259477D01*
X5302530Y257810D01*
X5302220Y256143D01*
X5301290Y255102D01*
X5300205Y254477D01*
X5296330D01*
G01X5300205D02*
X5302530Y248435D01*
G01X5309970Y260935D02*
X5313690D01*
G01X5311830D02*
Y248435D01*
G01X5309970D02*
X5313690D01*
G01X5321130Y260935D02*
Y248435D01*
X5327330D01*
G01X5333530Y260935D02*
Y248435D01*
X5339730D01*
G01X5358175Y250101D02*
X5359415Y249060D01*
X5360810Y248435D01*
X5362050D01*
X5363290Y249060D01*
X5364220Y250101D01*
X5364685Y251560D01*
X5364375Y253018D01*
X5363600Y254268D01*
X5362205Y255102D01*
X5360345Y255518D01*
X5359260Y256352D01*
X5358795Y257810D01*
X5359105Y259268D01*
X5359880Y260310D01*
X5360965Y260935D01*
X5362050D01*
X5363135Y260518D01*
X5364065Y259477D01*
G01X5373830Y260935D02*
Y248435D01*
G01X5370265Y260935D02*
X5377395D01*
G01X5382820D02*
Y251977D01*
X5383440Y250101D01*
X5384680Y248852D01*
X5386230Y248435D01*
X5387780Y248852D01*
X5389020Y250101D01*
X5389640Y251977D01*
Y260935D01*
G01X5399870Y255102D02*
X5400490Y255727D01*
X5400955Y256768D01*
X5401265Y258227D01*
X5400955Y259477D01*
X5400335Y260310D01*
X5399250Y260935D01*
X5395065D01*
Y248435D01*
X5400180D01*
X5401265Y249268D01*
X5401885Y250518D01*
X5402195Y251977D01*
X5401885Y253435D01*
X5400955Y254685D01*
X5399870Y255102D01*
X5395065D01*
G01X5420330Y260935D02*
Y248435D01*
X5426530D01*
G01X5438930D02*
X5432730D01*
Y260935D01*
X5438930D01*
G01X5436450Y254893D02*
X5432730D01*
G01X5444665Y248435D02*
Y260935D01*
X5451795Y248435D01*
Y260935D01*
G01X5461560Y254685D02*
X5464660D01*
Y250935D01*
X5463730Y249685D01*
X5462645Y248852D01*
X5461095Y248435D01*
X5459545Y248852D01*
X5458460Y249685D01*
X5457530Y250935D01*
X5456910Y252393D01*
X5456600Y254060D01*
Y255518D01*
X5456910Y256768D01*
X5457530Y258227D01*
X5458460Y259477D01*
X5459390Y260310D01*
X5460630Y260935D01*
X5461715D01*
X5462955Y260518D01*
X5463885Y259685D01*
G01X5473030Y260935D02*
Y248435D01*
G01X5469465Y260935D02*
X5476595D01*
G01X5482175Y248435D02*
Y260935D01*
G01X5488685D02*
Y248435D01*
G01Y254685D02*
X5482175D01*
G01X5510230Y260935D02*
Y248435D01*
G01X5506665Y260935D02*
X5513795D01*
G01X5522630Y248435D02*
X5521390Y248643D01*
X5520305Y249476D01*
X5519375Y250727D01*
X5518755Y252185D01*
X5518445Y253852D01*
Y255518D01*
X5518755Y257185D01*
X5519375Y258643D01*
X5520305Y259893D01*
X5521390Y260727D01*
X5522630Y260935D01*
X5523870Y260727D01*
X5524955Y259893D01*
X5525885Y258643D01*
X5526505Y257185D01*
X5526815Y255518D01*
Y253852D01*
X5526505Y252185D01*
X5525885Y250727D01*
X5524955Y249476D01*
X5523870Y248643D01*
X5522630Y248435D01*
G01X5531930Y260935D02*
Y248435D01*
X5538130D01*
G01X5550530D02*
X5544330D01*
Y260935D01*
X5550530D01*
G01X5548050Y254893D02*
X5544330D01*
G01X5556730Y248435D02*
Y260935D01*
X5560605D01*
X5561845Y260310D01*
X5562620Y259477D01*
X5562930Y257810D01*
X5562620Y256143D01*
X5561690Y255102D01*
X5560605Y254477D01*
X5556730D01*
G01X5560605D02*
X5562930Y248435D01*
G01X5568355D02*
X5572230Y260935D01*
X5576105Y248435D01*
G01X5574710Y252810D02*
X5569750D01*
G01X5581065Y248435D02*
Y260935D01*
X5588195Y248435D01*
Y260935D01*
G01X5600440Y259893D02*
X5599510Y260518D01*
X5598425Y260935D01*
X5597185D01*
X5595790Y260310D01*
X5594705Y259268D01*
X5593930Y258018D01*
X5593310Y255935D01*
X5593155Y254060D01*
X5593465Y252185D01*
X5593930Y250935D01*
X5594860Y249685D01*
X5595945Y248852D01*
X5597030Y248435D01*
X5598115D01*
X5599200Y248852D01*
X5600130Y249476D01*
X5600905Y250310D01*
G01X5612530Y248435D02*
X5606330D01*
Y260935D01*
X5612530D01*
G01X5610050Y254893D02*
X5606330D01*
G01X5634230Y260935D02*
Y248435D01*
G01X5630665Y260935D02*
X5637795D01*
G01X5646630Y248435D02*
X5645390Y248643D01*
X5644305Y249476D01*
X5643375Y250727D01*
X5642755Y252185D01*
X5642445Y253852D01*
Y255518D01*
X5642755Y257185D01*
X5643375Y258643D01*
X5644305Y259893D01*
X5645390Y260727D01*
X5646630Y260935D01*
X5647870Y260727D01*
X5648955Y259893D01*
X5649885Y258643D01*
X5650505Y257185D01*
X5650815Y255518D01*
Y253852D01*
X5650505Y252185D01*
X5649885Y250727D01*
X5648955Y249476D01*
X5647870Y248643D01*
X5646630Y248435D01*
G01X5672670Y255102D02*
X5673290Y255727D01*
X5673755Y256768D01*
X5674065Y258227D01*
X5673755Y259477D01*
X5673135Y260310D01*
X5672050Y260935D01*
X5667865D01*
Y248435D01*
X5672980D01*
X5674065Y249268D01*
X5674685Y250518D01*
X5674995Y251977D01*
X5674685Y253435D01*
X5673755Y254685D01*
X5672670Y255102D01*
X5667865D01*
G01X5686930Y248435D02*
X5680730D01*
Y260935D01*
X5686930D01*
G01X5684450Y254893D02*
X5680730D01*
G01X5708320Y248435D02*
X5708630Y251143D01*
X5709095Y253435D01*
X5709715Y255518D01*
X5710490Y257810D01*
X5711730Y260935D01*
X5705530D01*
G01X5731725Y252602D02*
X5735445D01*
G01X5733430Y255310D02*
Y249893D01*
G01X5743040Y248018D02*
X5748620Y260935D01*
G01X5756215Y252602D02*
X5760245D01*
G01X5767220Y250310D02*
X5768150Y249268D01*
X5769235Y248643D01*
X5770630Y248435D01*
X5772025Y248852D01*
X5773110Y249685D01*
X5773885Y251143D01*
X5774040Y252810D01*
X5773730Y254477D01*
X5772955Y255518D01*
X5771870Y256352D01*
X5770785Y256560D01*
X5769700Y256352D01*
X5768305Y255518D01*
X5768770Y260935D01*
X5772955D01*
G01X5791400Y248435D02*
Y260935D01*
X5795430Y250518D01*
X5799460Y260935D01*
Y248435D01*
G01X5805970Y260935D02*
X5809690D01*
G01X5807830D02*
Y248435D01*
G01X5805970D02*
X5809690D01*
G01X5817130Y260935D02*
Y248435D01*
X5823330D01*
G01X5829375Y250101D02*
X5830615Y249060D01*
X5832010Y248435D01*
X5833250D01*
X5834490Y249060D01*
X5835420Y250101D01*
X5835885Y251560D01*
X5835575Y253018D01*
X5834800Y254268D01*
X5833405Y255102D01*
X5831545Y255518D01*
X5830460Y256352D01*
X5829995Y257810D01*
X5830305Y259268D01*
X5831080Y260310D01*
X5832165Y260935D01*
X5833250D01*
X5834335Y260518D01*
X5835265Y259477D01*
G01X5074215Y271352D02*
X5078245D01*
G01X5097000Y267185D02*
Y279685D01*
X5101030Y269268D01*
X5105060Y279685D01*
Y267185D01*
G01X5110485D02*
Y279685D01*
X5116375D01*
G01X5114205Y273643D02*
X5110485D01*
G01X5126760Y273435D02*
X5129860D01*
Y269685D01*
X5128930Y268435D01*
X5127845Y267602D01*
X5126295Y267185D01*
X5124745Y267602D01*
X5123660Y268435D01*
X5122730Y269685D01*
X5122110Y271143D01*
X5121800Y272810D01*
Y274268D01*
X5122110Y275518D01*
X5122730Y276977D01*
X5123660Y278227D01*
X5124590Y279060D01*
X5125830Y279685D01*
X5126915D01*
X5128155Y279268D01*
X5129085Y278435D01*
G01X5133580Y263018D02*
X5142880D01*
G01X5147375Y268851D02*
X5148615Y267810D01*
X5150010Y267185D01*
X5151250D01*
X5152490Y267810D01*
X5153420Y268851D01*
X5153885Y270310D01*
X5153575Y271768D01*
X5152800Y273018D01*
X5151405Y273852D01*
X5149545Y274268D01*
X5148460Y275102D01*
X5147995Y276560D01*
X5148305Y278018D01*
X5149080Y279060D01*
X5150165Y279685D01*
X5151250D01*
X5152335Y279268D01*
X5153265Y278227D01*
G01X5163030Y279685D02*
Y267185D01*
G01X5159465Y279685D02*
X5166595D01*
G01X5172020D02*
Y270727D01*
X5172640Y268851D01*
X5173880Y267602D01*
X5175430Y267185D01*
X5176980Y267602D01*
X5178220Y268851D01*
X5178840Y270727D01*
Y279685D01*
G01X5189070Y273852D02*
X5189690Y274477D01*
X5190155Y275518D01*
X5190465Y276977D01*
X5190155Y278227D01*
X5189535Y279060D01*
X5188450Y279685D01*
X5184265D01*
Y267185D01*
X5189380D01*
X5190465Y268018D01*
X5191085Y269268D01*
X5191395Y270727D01*
X5191085Y272185D01*
X5190155Y273435D01*
X5189070Y273852D01*
X5184265D01*
G01X5212630Y266768D02*
X5212320Y266977D01*
Y267393D01*
X5212630Y267602D01*
X5212940Y267393D01*
Y266977D01*
X5212630Y266768D01*
G01Y272393D02*
X5212320Y272602D01*
Y273018D01*
X5212630Y273227D01*
X5212940Y273018D01*
Y272602D01*
X5212630Y272393D01*
G01X5233400Y267185D02*
Y279685D01*
X5237430Y269268D01*
X5241460Y279685D01*
Y267185D01*
G01X5245955D02*
X5249830Y279685D01*
X5253705Y267185D01*
G01X5252310Y271560D02*
X5247350D01*
G01X5258665Y267185D02*
Y279685D01*
X5265795Y267185D01*
Y279685D01*
G01X5271220D02*
Y270727D01*
X5271840Y268851D01*
X5273080Y267602D01*
X5274630Y267185D01*
X5276180Y267602D01*
X5277420Y268851D01*
X5278040Y270727D01*
Y279685D01*
G01X5284085Y267185D02*
Y279685D01*
X5289975D01*
G01X5287805Y273643D02*
X5284085D01*
G01X5295555Y267185D02*
X5299430Y279685D01*
X5303305Y267185D01*
G01X5301910Y271560D02*
X5296950D01*
G01X5315240Y278643D02*
X5314310Y279268D01*
X5313225Y279685D01*
X5311985D01*
X5310590Y279060D01*
X5309505Y278018D01*
X5308730Y276768D01*
X5308110Y274685D01*
X5307955Y272810D01*
X5308265Y270935D01*
X5308730Y269685D01*
X5309660Y268435D01*
X5310745Y267602D01*
X5311830Y267185D01*
X5312915D01*
X5314000Y267602D01*
X5314930Y268226D01*
X5315705Y269060D01*
G01X5324230Y279685D02*
Y267185D01*
G01X5320665Y279685D02*
X5327795D01*
G01X5333220D02*
Y270727D01*
X5333840Y268851D01*
X5335080Y267602D01*
X5336630Y267185D01*
X5338180Y267602D01*
X5339420Y268851D01*
X5340040Y270727D01*
Y279685D01*
G01X5345930Y267185D02*
Y279685D01*
X5349805D01*
X5351045Y279060D01*
X5351820Y278227D01*
X5352130Y276560D01*
X5351820Y274893D01*
X5350890Y273852D01*
X5349805Y273227D01*
X5345930D01*
G01X5349805D02*
X5352130Y267185D01*
G01X5359570Y279685D02*
X5363290D01*
G01X5361430D02*
Y267185D01*
G01X5359570D02*
X5363290D01*
G01X5370265D02*
Y279685D01*
X5377395Y267185D01*
Y279685D01*
G01X5387160Y273435D02*
X5390260D01*
Y269685D01*
X5389330Y268435D01*
X5388245Y267602D01*
X5386695Y267185D01*
X5385145Y267602D01*
X5384060Y268435D01*
X5383130Y269685D01*
X5382510Y271143D01*
X5382200Y272810D01*
Y274268D01*
X5382510Y275518D01*
X5383130Y276977D01*
X5384060Y278227D01*
X5384990Y279060D01*
X5386230Y279685D01*
X5387315D01*
X5388555Y279268D01*
X5389485Y278435D01*
G01X5407775Y268851D02*
X5409015Y267810D01*
X5410410Y267185D01*
X5411650D01*
X5412890Y267810D01*
X5413820Y268851D01*
X5414285Y270310D01*
X5413975Y271768D01*
X5413200Y273018D01*
X5411805Y273852D01*
X5409945Y274268D01*
X5408860Y275102D01*
X5408395Y276560D01*
X5408705Y278018D01*
X5409480Y279060D01*
X5410565Y279685D01*
X5411650D01*
X5412735Y279268D01*
X5413665Y278227D01*
G01X5423430Y279685D02*
Y267185D01*
G01X5419865Y279685D02*
X5426995D01*
G01X5432420D02*
Y270727D01*
X5433040Y268851D01*
X5434280Y267602D01*
X5435830Y267185D01*
X5437380Y267602D01*
X5438620Y268851D01*
X5439240Y270727D01*
Y279685D01*
G01X5449470Y273852D02*
X5450090Y274477D01*
X5450555Y275518D01*
X5450865Y276977D01*
X5450555Y278227D01*
X5449935Y279060D01*
X5448850Y279685D01*
X5444665D01*
Y267185D01*
X5449780D01*
X5450865Y268018D01*
X5451485Y269268D01*
X5451795Y270727D01*
X5451485Y272185D01*
X5450555Y273435D01*
X5449470Y273852D01*
X5444665D01*
G01X5469930Y279685D02*
Y267185D01*
X5476130D01*
G01X5488530D02*
X5482330D01*
Y279685D01*
X5488530D01*
G01X5486050Y273643D02*
X5482330D01*
G01X5494265Y267185D02*
Y279685D01*
X5501395Y267185D01*
Y279685D01*
G01X5511160Y273435D02*
X5514260D01*
Y269685D01*
X5513330Y268435D01*
X5512245Y267602D01*
X5510695Y267185D01*
X5509145Y267602D01*
X5508060Y268435D01*
X5507130Y269685D01*
X5506510Y271143D01*
X5506200Y272810D01*
Y274268D01*
X5506510Y275518D01*
X5507130Y276977D01*
X5508060Y278227D01*
X5508990Y279060D01*
X5510230Y279685D01*
X5511315D01*
X5512555Y279268D01*
X5513485Y278435D01*
G01X5522630Y279685D02*
Y267185D01*
G01X5519065Y279685D02*
X5526195D01*
G01X5531775Y267185D02*
Y279685D01*
G01X5538285D02*
Y267185D01*
G01Y273435D02*
X5531775D01*
G01X5234175Y287601D02*
X5235415Y286560D01*
X5236810Y285935D01*
X5238050D01*
X5239290Y286560D01*
X5240220Y287601D01*
X5240685Y289060D01*
X5240375Y290518D01*
X5239600Y291768D01*
X5238205Y292602D01*
X5236345Y293018D01*
X5235260Y293852D01*
X5234795Y295310D01*
X5235105Y296768D01*
X5235880Y297810D01*
X5236965Y298435D01*
X5238050D01*
X5239135Y298018D01*
X5240065Y296977D01*
G01X5246420Y298435D02*
Y289477D01*
X5247040Y287601D01*
X5248280Y286352D01*
X5249830Y285935D01*
X5251380Y286352D01*
X5252620Y287601D01*
X5253240Y289477D01*
Y298435D01*
G01X5259130Y285935D02*
Y298435D01*
X5263005D01*
X5264245Y297810D01*
X5265020Y296977D01*
X5265330Y295310D01*
X5265020Y293643D01*
X5264090Y292602D01*
X5263005Y291977D01*
X5259130D01*
G01X5263005D02*
X5265330Y285935D01*
G01X5271685D02*
Y298435D01*
X5277575D01*
G01X5275405Y292393D02*
X5271685D01*
G01X5283155Y285935D02*
X5287030Y298435D01*
X5290905Y285935D01*
G01X5289510Y290310D02*
X5284550D01*
G01X5302840Y297393D02*
X5301910Y298018D01*
X5300825Y298435D01*
X5299585D01*
X5298190Y297810D01*
X5297105Y296768D01*
X5296330Y295518D01*
X5295710Y293435D01*
X5295555Y291560D01*
X5295865Y289685D01*
X5296330Y288435D01*
X5297260Y287185D01*
X5298345Y286352D01*
X5299430Y285935D01*
X5300515D01*
X5301600Y286352D01*
X5302530Y286976D01*
X5303305Y287810D01*
G01X5314930Y285935D02*
X5308730D01*
Y298435D01*
X5314930D01*
G01X5312450Y292393D02*
X5308730D01*
G01X5336630Y285935D02*
X5335390Y286143D01*
X5334305Y286976D01*
X5333375Y288227D01*
X5332755Y289685D01*
X5332445Y291352D01*
Y293018D01*
X5332755Y294685D01*
X5333375Y296143D01*
X5334305Y297393D01*
X5335390Y298227D01*
X5336630Y298435D01*
X5337870Y298227D01*
X5338955Y297393D01*
X5339885Y296143D01*
X5340505Y294685D01*
X5340815Y293018D01*
Y291352D01*
X5340505Y289685D01*
X5339885Y288227D01*
X5338955Y286976D01*
X5337870Y286143D01*
X5336630Y285935D01*
G01X5346085D02*
Y298435D01*
X5351975D01*
G01X5349805Y292393D02*
X5346085D01*
G01X5369800Y285935D02*
Y298435D01*
X5373830Y288018D01*
X5377860Y298435D01*
Y285935D01*
G01X5382820Y298435D02*
Y289477D01*
X5383440Y287601D01*
X5384680Y286352D01*
X5386230Y285935D01*
X5387780Y286352D01*
X5389020Y287601D01*
X5389640Y289477D01*
Y298435D01*
G01X5395375Y287601D02*
X5396615Y286560D01*
X5398010Y285935D01*
X5399250D01*
X5400490Y286560D01*
X5401420Y287601D01*
X5401885Y289060D01*
X5401575Y290518D01*
X5400800Y291768D01*
X5399405Y292602D01*
X5397545Y293018D01*
X5396460Y293852D01*
X5395995Y295310D01*
X5396305Y296768D01*
X5397080Y297810D01*
X5398165Y298435D01*
X5399250D01*
X5400335Y298018D01*
X5401265Y296977D01*
G01X5411030Y298435D02*
Y285935D01*
G01X5407465Y298435D02*
X5414595D01*
G01X5421415Y290102D02*
X5425445D01*
G01X5432265Y285935D02*
Y298435D01*
X5439395Y285935D01*
Y298435D01*
G01X5448230Y285935D02*
X5446990Y286143D01*
X5445905Y286976D01*
X5444975Y288227D01*
X5444355Y289685D01*
X5444045Y291352D01*
Y293018D01*
X5444355Y294685D01*
X5444975Y296143D01*
X5445905Y297393D01*
X5446990Y298227D01*
X5448230Y298435D01*
X5449470Y298227D01*
X5450555Y297393D01*
X5451485Y296143D01*
X5452105Y294685D01*
X5452415Y293018D01*
Y291352D01*
X5452105Y289685D01*
X5451485Y288227D01*
X5450555Y286976D01*
X5449470Y286143D01*
X5448230Y285935D01*
G01X5460630Y298435D02*
Y285935D01*
G01X5457065Y298435D02*
X5464195D01*
G01X5471015Y290102D02*
X5475045D01*
G01X5488840Y297393D02*
X5487910Y298018D01*
X5486825Y298435D01*
X5485585D01*
X5484190Y297810D01*
X5483105Y296768D01*
X5482330Y295518D01*
X5481710Y293435D01*
X5481555Y291560D01*
X5481865Y289685D01*
X5482330Y288435D01*
X5483260Y287185D01*
X5484345Y286352D01*
X5485430Y285935D01*
X5486515D01*
X5487600Y286352D01*
X5488530Y286976D01*
X5489305Y287810D01*
G01X5494420Y298435D02*
Y289477D01*
X5495040Y287601D01*
X5496280Y286352D01*
X5497830Y285935D01*
X5499380Y286352D01*
X5500620Y287601D01*
X5501240Y289477D01*
Y298435D01*
G01X5510230D02*
Y285935D01*
G01X5506665Y298435D02*
X5513795D01*
G01X5520615Y290102D02*
X5524645D01*
G01X5531930Y298435D02*
Y285935D01*
X5538130D01*
G01X5543555D02*
X5547430Y298435D01*
X5551305Y285935D01*
G01X5549910Y290310D02*
X5544950D01*
G01X5559830Y285935D02*
Y291560D01*
X5556730Y298435D01*
G01X5562930D02*
X5559830Y291560D01*
G01X5575330Y285935D02*
X5569130D01*
Y298435D01*
X5575330D01*
G01X5572850Y292393D02*
X5569130D01*
G01X5581530Y285935D02*
Y298435D01*
X5585405D01*
X5586645Y297810D01*
X5587420Y296977D01*
X5587730Y295310D01*
X5587420Y293643D01*
X5586490Y292602D01*
X5585405Y291977D01*
X5581530D01*
G01X5585405D02*
X5587730Y285935D01*
G01X5074215Y308852D02*
X5078245D01*
G01X5097000Y304685D02*
Y317185D01*
X5101030Y306768D01*
X5105060Y317185D01*
Y304685D01*
G01X5109555D02*
X5113430Y317185D01*
X5117305Y304685D01*
G01X5115910Y309060D02*
X5110950D01*
G01X5122575Y304685D02*
X5129085Y317185D01*
G01X5122575D02*
X5129085Y304685D01*
G01X5133580Y300518D02*
X5142880D01*
G01X5147220Y304685D02*
Y317185D01*
X5150320D01*
X5151560Y316560D01*
X5152490Y315727D01*
X5153265Y314477D01*
X5153885Y313018D01*
X5154040Y310935D01*
X5153885Y308852D01*
X5153265Y307393D01*
X5152490Y306143D01*
X5151560Y305310D01*
X5150320Y304685D01*
X5147220D01*
G01X5166130D02*
X5159930D01*
Y317185D01*
X5166130D01*
G01X5163650Y311143D02*
X5159930D01*
G01X5172330Y304685D02*
Y317185D01*
X5176050D01*
X5177290Y316560D01*
X5178220Y315102D01*
X5178530Y313435D01*
X5178220Y311768D01*
X5177445Y310518D01*
X5176050Y309893D01*
X5172330D01*
G01X5187830Y317185D02*
Y304685D01*
G01X5184265Y317185D02*
X5191395D01*
G01X5196975Y304685D02*
Y317185D01*
G01X5203485D02*
Y304685D01*
G01Y310935D02*
X5196975D01*
G01X5212630Y304268D02*
X5212320Y304477D01*
Y304893D01*
X5212630Y305102D01*
X5212940Y304893D01*
Y304477D01*
X5212630Y304268D01*
G01Y309893D02*
X5212320Y310102D01*
Y310518D01*
X5212630Y310727D01*
X5212940Y310518D01*
Y310102D01*
X5212630Y309893D01*
G01X5234020Y304685D02*
Y317185D01*
X5237120D01*
X5238360Y316560D01*
X5239290Y315727D01*
X5240065Y314477D01*
X5240685Y313018D01*
X5240840Y310935D01*
X5240685Y308852D01*
X5240065Y307393D01*
X5239290Y306143D01*
X5238360Y305310D01*
X5237120Y304685D01*
X5234020D01*
G01X5252930D02*
X5246730D01*
Y317185D01*
X5252930D01*
G01X5250450Y311143D02*
X5246730D01*
G01X5259130Y304685D02*
Y317185D01*
X5262850D01*
X5264090Y316560D01*
X5265020Y315102D01*
X5265330Y313435D01*
X5265020Y311768D01*
X5264245Y310518D01*
X5262850Y309893D01*
X5259130D01*
G01X5274630Y317185D02*
Y304685D01*
G01X5271065Y317185D02*
X5278195D01*
G01X5283775Y304685D02*
Y317185D01*
G01X5290285D02*
Y304685D01*
G01Y310935D02*
X5283775D01*
G01X5308885Y304685D02*
Y317185D01*
X5314775D01*
G01X5312605Y311143D02*
X5308885D01*
G01X5321130Y304685D02*
Y317185D01*
X5325005D01*
X5326245Y316560D01*
X5327020Y315727D01*
X5327330Y314060D01*
X5327020Y312393D01*
X5326090Y311352D01*
X5325005Y310727D01*
X5321130D01*
G01X5325005D02*
X5327330Y304685D01*
G01X5336630D02*
X5335390Y304893D01*
X5334305Y305726D01*
X5333375Y306977D01*
X5332755Y308435D01*
X5332445Y310102D01*
Y311768D01*
X5332755Y313435D01*
X5333375Y314893D01*
X5334305Y316143D01*
X5335390Y316977D01*
X5336630Y317185D01*
X5337870Y316977D01*
X5338955Y316143D01*
X5339885Y314893D01*
X5340505Y313435D01*
X5340815Y311768D01*
Y310102D01*
X5340505Y308435D01*
X5339885Y306977D01*
X5338955Y305726D01*
X5337870Y304893D01*
X5336630Y304685D01*
G01X5345000D02*
Y317185D01*
X5349030Y306768D01*
X5353060Y317185D01*
Y304685D01*
G01X5370575Y306351D02*
X5371815Y305310D01*
X5373210Y304685D01*
X5374450D01*
X5375690Y305310D01*
X5376620Y306351D01*
X5377085Y307810D01*
X5376775Y309268D01*
X5376000Y310518D01*
X5374605Y311352D01*
X5372745Y311768D01*
X5371660Y312602D01*
X5371195Y314060D01*
X5371505Y315518D01*
X5372280Y316560D01*
X5373365Y317185D01*
X5374450D01*
X5375535Y316768D01*
X5376465Y315727D01*
G01X5386230Y317185D02*
Y304685D01*
G01X5382665Y317185D02*
X5389795D01*
G01X5394755Y304685D02*
X5398630Y317185D01*
X5402505Y304685D01*
G01X5401110Y309060D02*
X5396150D01*
G01X5407930Y304685D02*
Y317185D01*
X5411805D01*
X5413045Y316560D01*
X5413820Y315727D01*
X5414130Y314060D01*
X5413820Y312393D01*
X5412890Y311352D01*
X5411805Y310727D01*
X5407930D01*
G01X5411805D02*
X5414130Y304685D01*
G01X5423430Y317185D02*
Y304685D01*
G01X5419865Y317185D02*
X5426995D01*
G01X5445130D02*
Y304685D01*
X5451330D01*
G01X5456755D02*
X5460630Y317185D01*
X5464505Y304685D01*
G01X5463110Y309060D02*
X5458150D01*
G01X5473030Y304685D02*
Y310310D01*
X5469930Y317185D01*
G01X5476130D02*
X5473030Y310310D01*
G01X5488530Y304685D02*
X5482330D01*
Y317185D01*
X5488530D01*
G01X5486050Y311143D02*
X5482330D01*
G01X5494730Y304685D02*
Y317185D01*
X5498605D01*
X5499845Y316560D01*
X5500620Y315727D01*
X5500930Y314060D01*
X5500620Y312393D01*
X5499690Y311352D01*
X5498605Y310727D01*
X5494730D01*
G01X5498605D02*
X5500930Y304685D01*
G01X5522630Y317185D02*
Y304685D01*
G01X5519065Y317185D02*
X5526195D01*
G01X5535030Y304685D02*
X5533790Y304893D01*
X5532705Y305726D01*
X5531775Y306977D01*
X5531155Y308435D01*
X5530845Y310102D01*
Y311768D01*
X5531155Y313435D01*
X5531775Y314893D01*
X5532705Y316143D01*
X5533790Y316977D01*
X5535030Y317185D01*
X5536270Y316977D01*
X5537355Y316143D01*
X5538285Y314893D01*
X5538905Y313435D01*
X5539215Y311768D01*
Y310102D01*
X5538905Y308435D01*
X5538285Y306977D01*
X5537355Y305726D01*
X5536270Y304893D01*
X5535030Y304685D01*
G01X5559830Y317185D02*
Y304685D01*
G01X5556265Y317185D02*
X5563395D01*
G01X5568975Y304685D02*
Y317185D01*
G01X5575485D02*
Y304685D01*
G01Y310935D02*
X5568975D01*
G01X5587730Y304685D02*
X5581530D01*
Y317185D01*
X5587730D01*
G01X5585250Y311143D02*
X5581530D01*
G01X5074215Y327602D02*
X5078245D01*
G01X5097000Y323435D02*
Y335935D01*
X5101030Y325518D01*
X5105060Y335935D01*
Y323435D01*
G01X5109865D02*
Y335935D01*
X5116995Y323435D01*
Y335935D01*
G01X5129240Y334893D02*
X5128310Y335518D01*
X5127225Y335935D01*
X5125985D01*
X5124590Y335310D01*
X5123505Y334268D01*
X5122730Y333018D01*
X5122110Y330935D01*
X5121955Y329060D01*
X5122265Y327185D01*
X5122730Y325935D01*
X5123660Y324685D01*
X5124745Y323852D01*
X5125830Y323435D01*
X5126915D01*
X5128000Y323852D01*
X5128930Y324476D01*
X5129705Y325310D01*
G01X5133580Y319268D02*
X5142880D01*
G01X5147530Y335935D02*
Y323435D01*
X5153730D01*
G01X5159155D02*
X5163030Y335935D01*
X5166905Y323435D01*
G01X5165510Y327810D02*
X5160550D01*
G01X5175430Y323435D02*
Y329060D01*
X5172330Y335935D01*
G01X5178530D02*
X5175430Y329060D01*
G01X5190930Y323435D02*
X5184730D01*
Y335935D01*
X5190930D01*
G01X5188450Y329893D02*
X5184730D01*
G01X5197130Y323435D02*
Y335935D01*
X5201005D01*
X5202245Y335310D01*
X5203020Y334477D01*
X5203330Y332810D01*
X5203020Y331143D01*
X5202090Y330102D01*
X5201005Y329477D01*
X5197130D01*
G01X5201005D02*
X5203330Y323435D01*
G01X5212630Y323018D02*
X5212320Y323227D01*
Y323643D01*
X5212630Y323852D01*
X5212940Y323643D01*
Y323227D01*
X5212630Y323018D01*
G01Y328643D02*
X5212320Y328852D01*
Y329268D01*
X5212630Y329477D01*
X5212940Y329268D01*
Y328852D01*
X5212630Y328643D01*
G01X5233400Y323435D02*
Y335935D01*
X5237430Y325518D01*
X5241460Y335935D01*
Y323435D01*
G01X5246420Y335935D02*
Y326977D01*
X5247040Y325101D01*
X5248280Y323852D01*
X5249830Y323435D01*
X5251380Y323852D01*
X5252620Y325101D01*
X5253240Y326977D01*
Y335935D01*
G01X5258975Y325101D02*
X5260215Y324060D01*
X5261610Y323435D01*
X5262850D01*
X5264090Y324060D01*
X5265020Y325101D01*
X5265485Y326560D01*
X5265175Y328018D01*
X5264400Y329268D01*
X5263005Y330102D01*
X5261145Y330518D01*
X5260060Y331352D01*
X5259595Y332810D01*
X5259905Y334268D01*
X5260680Y335310D01*
X5261765Y335935D01*
X5262850D01*
X5263935Y335518D01*
X5264865Y334477D01*
G01X5274630Y335935D02*
Y323435D01*
G01X5271065Y335935D02*
X5278195D01*
G01X5285015Y327602D02*
X5289045D01*
G01X5295865Y323435D02*
Y335935D01*
X5302995Y323435D01*
Y335935D01*
G01X5311830Y323435D02*
X5310590Y323643D01*
X5309505Y324476D01*
X5308575Y325727D01*
X5307955Y327185D01*
X5307645Y328852D01*
Y330518D01*
X5307955Y332185D01*
X5308575Y333643D01*
X5309505Y334893D01*
X5310590Y335727D01*
X5311830Y335935D01*
X5313070Y335727D01*
X5314155Y334893D01*
X5315085Y333643D01*
X5315705Y332185D01*
X5316015Y330518D01*
Y328852D01*
X5315705Y327185D01*
X5315085Y325727D01*
X5314155Y324476D01*
X5313070Y323643D01*
X5311830Y323435D01*
G01X5324230Y335935D02*
Y323435D01*
G01X5320665Y335935D02*
X5327795D01*
G01X5334615Y327602D02*
X5338645D01*
G01X5352440Y334893D02*
X5351510Y335518D01*
X5350425Y335935D01*
X5349185D01*
X5347790Y335310D01*
X5346705Y334268D01*
X5345930Y333018D01*
X5345310Y330935D01*
X5345155Y329060D01*
X5345465Y327185D01*
X5345930Y325935D01*
X5346860Y324685D01*
X5347945Y323852D01*
X5349030Y323435D01*
X5350115D01*
X5351200Y323852D01*
X5352130Y324476D01*
X5352905Y325310D01*
G01X5358020Y335935D02*
Y326977D01*
X5358640Y325101D01*
X5359880Y323852D01*
X5361430Y323435D01*
X5362980Y323852D01*
X5364220Y325101D01*
X5364840Y326977D01*
Y335935D01*
G01X5373830D02*
Y323435D01*
G01X5370265Y335935D02*
X5377395D01*
G01X5384215Y327602D02*
X5388245D01*
G01X5395530Y335935D02*
Y323435D01*
X5401730D01*
G01X5407155D02*
X5411030Y335935D01*
X5414905Y323435D01*
G01X5413510Y327810D02*
X5408550D01*
G01X5423430Y323435D02*
Y329060D01*
X5420330Y335935D01*
G01X5426530D02*
X5423430Y329060D01*
G01X5438930Y323435D02*
X5432730D01*
Y335935D01*
X5438930D01*
G01X5436450Y329893D02*
X5432730D01*
G01X5445130Y323435D02*
Y335935D01*
X5449005D01*
X5450245Y335310D01*
X5451020Y334477D01*
X5451330Y332810D01*
X5451020Y331143D01*
X5450090Y330102D01*
X5449005Y329477D01*
X5445130D01*
G01X5449005D02*
X5451330Y323435D01*
G01X5072665Y342185D02*
Y354685D01*
X5079795Y342185D01*
Y354685D01*
G01X5088630Y342185D02*
X5087390Y342393D01*
X5086305Y343226D01*
X5085375Y344477D01*
X5084755Y345935D01*
X5084445Y347602D01*
Y349268D01*
X5084755Y350935D01*
X5085375Y352393D01*
X5086305Y353643D01*
X5087390Y354477D01*
X5088630Y354685D01*
X5089870Y354477D01*
X5090955Y353643D01*
X5091885Y352393D01*
X5092505Y350935D01*
X5092815Y349268D01*
Y347602D01*
X5092505Y345935D01*
X5091885Y344477D01*
X5090955Y343226D01*
X5089870Y342393D01*
X5088630Y342185D01*
G01X5101030Y354685D02*
Y342185D01*
G01X5097465Y354685D02*
X5104595D01*
G01X5116530Y342185D02*
X5110330D01*
Y354685D01*
X5116530D01*
G01X5114050Y348643D02*
X5110330D01*
G01X5122575Y343851D02*
X5123815Y342810D01*
X5125210Y342185D01*
X5126450D01*
X5127690Y342810D01*
X5128620Y343851D01*
X5129085Y345310D01*
X5128775Y346768D01*
X5128000Y348018D01*
X5126605Y348852D01*
X5124745Y349268D01*
X5123660Y350102D01*
X5123195Y351560D01*
X5123505Y353018D01*
X5124280Y354060D01*
X5125365Y354685D01*
X5126450D01*
X5127535Y354268D01*
X5128465Y353227D01*
G01X5138230Y341768D02*
X5137920Y341977D01*
Y342393D01*
X5138230Y342602D01*
X5138540Y342393D01*
Y341977D01*
X5138230Y341768D01*
G01Y347393D02*
X5137920Y347602D01*
Y348018D01*
X5138230Y348227D01*
X5138540Y348018D01*
Y347602D01*
X5138230Y347393D01*
G01X5241260Y526273D02*
X5241880Y526898D01*
X5242345Y527939D01*
X5242655Y529398D01*
X5242345Y530648D01*
X5241725Y531481D01*
X5240640Y532106D01*
X5236455D01*
Y519606D01*
X5241570D01*
X5242655Y520439D01*
X5243275Y521689D01*
X5243585Y523148D01*
X5243275Y524606D01*
X5242345Y525856D01*
X5241260Y526273D01*
X5236455D01*
G01X5248545Y519606D02*
X5252420Y532106D01*
X5256295Y519606D01*
G01X5254900Y523981D02*
X5249940D01*
G01X5268230Y531064D02*
X5267300Y531689D01*
X5266215Y532106D01*
X5264975D01*
X5263580Y531481D01*
X5262495Y530439D01*
X5261720Y529189D01*
X5261100Y527106D01*
X5260945Y525231D01*
X5261255Y523356D01*
X5261720Y522106D01*
X5262650Y520856D01*
X5263735Y520023D01*
X5264820Y519606D01*
X5265905D01*
X5266990Y520023D01*
X5267920Y520647D01*
X5268695Y521481D01*
G01X5273810Y519606D02*
Y532106D01*
G01X5279700D02*
X5273810Y524397D01*
G01X5280630Y519606D02*
X5276445Y527939D01*
G01X5286210Y519606D02*
Y532106D01*
X5289310D01*
X5290550Y531481D01*
X5291480Y530648D01*
X5292255Y529398D01*
X5292875Y527939D01*
X5293030Y525856D01*
X5292875Y523773D01*
X5292255Y522314D01*
X5291480Y521064D01*
X5290550Y520231D01*
X5289310Y519606D01*
X5286210D01*
G01X5298920D02*
Y532106D01*
X5302795D01*
X5304035Y531481D01*
X5304810Y530648D01*
X5305120Y528981D01*
X5304810Y527314D01*
X5303880Y526273D01*
X5302795Y525648D01*
X5298920D01*
G01X5302795D02*
X5305120Y519606D01*
G01X5312560Y532106D02*
X5316280D01*
G01X5314420D02*
Y519606D01*
G01X5312560D02*
X5316280D01*
G01X5323720Y532106D02*
Y519606D01*
X5329920D01*
G01X5336120Y532106D02*
Y519606D01*
X5342320D01*
G01X5360765Y521272D02*
X5362005Y520231D01*
X5363400Y519606D01*
X5364640D01*
X5365880Y520231D01*
X5366810Y521272D01*
X5367275Y522731D01*
X5366965Y524189D01*
X5366190Y525439D01*
X5364795Y526273D01*
X5362935Y526689D01*
X5361850Y527523D01*
X5361385Y528981D01*
X5361695Y530439D01*
X5362470Y531481D01*
X5363555Y532106D01*
X5364640D01*
X5365725Y531689D01*
X5366655Y530648D01*
G01X5376420Y532106D02*
Y519606D01*
G01X5372855Y532106D02*
X5379985D01*
G01X5385410D02*
Y523148D01*
X5386030Y521272D01*
X5387270Y520023D01*
X5388820Y519606D01*
X5390370Y520023D01*
X5391610Y521272D01*
X5392230Y523148D01*
Y532106D01*
G01X5402460Y526273D02*
X5403080Y526898D01*
X5403545Y527939D01*
X5403855Y529398D01*
X5403545Y530648D01*
X5402925Y531481D01*
X5401840Y532106D01*
X5397655D01*
Y519606D01*
X5402770D01*
X5403855Y520439D01*
X5404475Y521689D01*
X5404785Y523148D01*
X5404475Y524606D01*
X5403545Y525856D01*
X5402460Y526273D01*
X5397655D01*
G01X5422920Y532106D02*
Y519606D01*
X5429120D01*
G01X5441520D02*
X5435320D01*
Y532106D01*
X5441520D01*
G01X5439040Y526064D02*
X5435320D01*
G01X5447255Y519606D02*
Y532106D01*
X5454385Y519606D01*
Y532106D01*
G01X5464150Y525856D02*
X5467250D01*
Y522106D01*
X5466320Y520856D01*
X5465235Y520023D01*
X5463685Y519606D01*
X5462135Y520023D01*
X5461050Y520856D01*
X5460120Y522106D01*
X5459500Y523564D01*
X5459190Y525231D01*
Y526689D01*
X5459500Y527939D01*
X5460120Y529398D01*
X5461050Y530648D01*
X5461980Y531481D01*
X5463220Y532106D01*
X5464305D01*
X5465545Y531689D01*
X5466475Y530856D01*
G01X5475620Y532106D02*
Y519606D01*
G01X5472055Y532106D02*
X5479185D01*
G01X5484765Y519606D02*
Y532106D01*
G01X5491275D02*
Y519606D01*
G01Y525856D02*
X5484765D01*
G01X5512820Y532106D02*
Y519606D01*
G01X5509255Y532106D02*
X5516385D01*
G01X5525220Y519606D02*
X5523980Y519814D01*
X5522895Y520647D01*
X5521965Y521898D01*
X5521345Y523356D01*
X5521035Y525023D01*
Y526689D01*
X5521345Y528356D01*
X5521965Y529814D01*
X5522895Y531064D01*
X5523980Y531898D01*
X5525220Y532106D01*
X5526460Y531898D01*
X5527545Y531064D01*
X5528475Y529814D01*
X5529095Y528356D01*
X5529405Y526689D01*
Y525023D01*
X5529095Y523356D01*
X5528475Y521898D01*
X5527545Y520647D01*
X5526460Y519814D01*
X5525220Y519606D01*
G01X5534520Y532106D02*
Y519606D01*
X5540720D01*
G01X5553120D02*
X5546920D01*
Y532106D01*
X5553120D01*
G01X5550640Y526064D02*
X5546920D01*
G01X5559320Y519606D02*
Y532106D01*
X5563195D01*
X5564435Y531481D01*
X5565210Y530648D01*
X5565520Y528981D01*
X5565210Y527314D01*
X5564280Y526273D01*
X5563195Y525648D01*
X5559320D01*
G01X5563195D02*
X5565520Y519606D01*
G01X5570945D02*
X5574820Y532106D01*
X5578695Y519606D01*
G01X5577300Y523981D02*
X5572340D01*
G01X5583655Y519606D02*
Y532106D01*
X5590785Y519606D01*
Y532106D01*
G01X5603030Y531064D02*
X5602100Y531689D01*
X5601015Y532106D01*
X5599775D01*
X5598380Y531481D01*
X5597295Y530439D01*
X5596520Y529189D01*
X5595900Y527106D01*
X5595745Y525231D01*
X5596055Y523356D01*
X5596520Y522106D01*
X5597450Y520856D01*
X5598535Y520023D01*
X5599620Y519606D01*
X5600705D01*
X5601790Y520023D01*
X5602720Y520647D01*
X5603495Y521481D01*
G01X5615120Y519606D02*
X5608920D01*
Y532106D01*
X5615120D01*
G01X5612640Y526064D02*
X5608920D01*
G01X5636820Y532106D02*
Y519606D01*
G01X5633255Y532106D02*
X5640385D01*
G01X5649220Y519606D02*
X5647980Y519814D01*
X5646895Y520647D01*
X5645965Y521898D01*
X5645345Y523356D01*
X5645035Y525023D01*
Y526689D01*
X5645345Y528356D01*
X5645965Y529814D01*
X5646895Y531064D01*
X5647980Y531898D01*
X5649220Y532106D01*
X5650460Y531898D01*
X5651545Y531064D01*
X5652475Y529814D01*
X5653095Y528356D01*
X5653405Y526689D01*
Y525023D01*
X5653095Y523356D01*
X5652475Y521898D01*
X5651545Y520647D01*
X5650460Y519814D01*
X5649220Y519606D01*
G01X5675260Y526273D02*
X5675880Y526898D01*
X5676345Y527939D01*
X5676655Y529398D01*
X5676345Y530648D01*
X5675725Y531481D01*
X5674640Y532106D01*
X5670455D01*
Y519606D01*
X5675570D01*
X5676655Y520439D01*
X5677275Y521689D01*
X5677585Y523148D01*
X5677275Y524606D01*
X5676345Y525856D01*
X5675260Y526273D01*
X5670455D01*
G01X5689520Y519606D02*
X5683320D01*
Y532106D01*
X5689520D01*
G01X5687040Y526064D02*
X5683320D01*
G01X5710910Y519606D02*
X5711220Y522314D01*
X5711685Y524606D01*
X5712305Y526689D01*
X5713080Y528981D01*
X5714320Y532106D01*
X5708120D01*
G01X5734315Y523773D02*
X5738035D01*
G01X5736020Y526481D02*
Y521064D01*
G01X5745630Y519189D02*
X5751210Y532106D01*
G01X5758805Y523773D02*
X5762835D01*
G01X5769810Y521481D02*
X5770740Y520439D01*
X5771825Y519814D01*
X5773220Y519606D01*
X5774615Y520023D01*
X5775700Y520856D01*
X5776475Y522314D01*
X5776630Y523981D01*
X5776320Y525648D01*
X5775545Y526689D01*
X5774460Y527523D01*
X5773375Y527731D01*
X5772290Y527523D01*
X5770895Y526689D01*
X5771360Y532106D01*
X5775545D01*
G01X5793990Y519606D02*
Y532106D01*
X5798020Y521689D01*
X5802050Y532106D01*
Y519606D01*
G01X5808560Y532106D02*
X5812280D01*
G01X5810420D02*
Y519606D01*
G01X5808560D02*
X5812280D01*
G01X5819720Y532106D02*
Y519606D01*
X5825920D01*
G01X5831965Y521272D02*
X5833205Y520231D01*
X5834600Y519606D01*
X5835840D01*
X5837080Y520231D01*
X5838010Y521272D01*
X5838475Y522731D01*
X5838165Y524189D01*
X5837390Y525439D01*
X5835995Y526273D01*
X5834135Y526689D01*
X5833050Y527523D01*
X5832585Y528981D01*
X5832895Y530439D01*
X5833670Y531481D01*
X5834755Y532106D01*
X5835840D01*
X5836925Y531689D01*
X5837855Y530648D01*
G01X5076805Y542523D02*
X5080835D01*
G01X5099590Y538356D02*
Y550856D01*
X5103620Y540439D01*
X5107650Y550856D01*
Y538356D01*
G01X5113075D02*
Y550856D01*
X5118965D01*
G01X5116795Y544814D02*
X5113075D01*
G01X5129350Y544606D02*
X5132450D01*
Y540856D01*
X5131520Y539606D01*
X5130435Y538773D01*
X5128885Y538356D01*
X5127335Y538773D01*
X5126250Y539606D01*
X5125320Y540856D01*
X5124700Y542314D01*
X5124390Y543981D01*
Y545439D01*
X5124700Y546689D01*
X5125320Y548148D01*
X5126250Y549398D01*
X5127180Y550231D01*
X5128420Y550856D01*
X5129505D01*
X5130745Y550439D01*
X5131675Y549606D01*
G01X5136170Y534189D02*
X5145470D01*
G01X5149965Y540022D02*
X5151205Y538981D01*
X5152600Y538356D01*
X5153840D01*
X5155080Y538981D01*
X5156010Y540022D01*
X5156475Y541481D01*
X5156165Y542939D01*
X5155390Y544189D01*
X5153995Y545023D01*
X5152135Y545439D01*
X5151050Y546273D01*
X5150585Y547731D01*
X5150895Y549189D01*
X5151670Y550231D01*
X5152755Y550856D01*
X5153840D01*
X5154925Y550439D01*
X5155855Y549398D01*
G01X5165620Y550856D02*
Y538356D01*
G01X5162055Y550856D02*
X5169185D01*
G01X5174610D02*
Y541898D01*
X5175230Y540022D01*
X5176470Y538773D01*
X5178020Y538356D01*
X5179570Y538773D01*
X5180810Y540022D01*
X5181430Y541898D01*
Y550856D01*
G01X5191660Y545023D02*
X5192280Y545648D01*
X5192745Y546689D01*
X5193055Y548148D01*
X5192745Y549398D01*
X5192125Y550231D01*
X5191040Y550856D01*
X5186855D01*
Y538356D01*
X5191970D01*
X5193055Y539189D01*
X5193675Y540439D01*
X5193985Y541898D01*
X5193675Y543356D01*
X5192745Y544606D01*
X5191660Y545023D01*
X5186855D01*
G01X5215220Y537939D02*
X5214910Y538148D01*
Y538564D01*
X5215220Y538773D01*
X5215530Y538564D01*
Y538148D01*
X5215220Y537939D01*
G01Y543564D02*
X5214910Y543773D01*
Y544189D01*
X5215220Y544398D01*
X5215530Y544189D01*
Y543773D01*
X5215220Y543564D01*
G01X5235990Y538356D02*
Y550856D01*
X5240020Y540439D01*
X5244050Y550856D01*
Y538356D01*
G01X5248545D02*
X5252420Y550856D01*
X5256295Y538356D01*
G01X5254900Y542731D02*
X5249940D01*
G01X5261255Y538356D02*
Y550856D01*
X5268385Y538356D01*
Y550856D01*
G01X5273810D02*
Y541898D01*
X5274430Y540022D01*
X5275670Y538773D01*
X5277220Y538356D01*
X5278770Y538773D01*
X5280010Y540022D01*
X5280630Y541898D01*
Y550856D01*
G01X5286675Y538356D02*
Y550856D01*
X5292565D01*
G01X5290395Y544814D02*
X5286675D01*
G01X5298145Y538356D02*
X5302020Y550856D01*
X5305895Y538356D01*
G01X5304500Y542731D02*
X5299540D01*
G01X5317830Y549814D02*
X5316900Y550439D01*
X5315815Y550856D01*
X5314575D01*
X5313180Y550231D01*
X5312095Y549189D01*
X5311320Y547939D01*
X5310700Y545856D01*
X5310545Y543981D01*
X5310855Y542106D01*
X5311320Y540856D01*
X5312250Y539606D01*
X5313335Y538773D01*
X5314420Y538356D01*
X5315505D01*
X5316590Y538773D01*
X5317520Y539397D01*
X5318295Y540231D01*
G01X5326820Y550856D02*
Y538356D01*
G01X5323255Y550856D02*
X5330385D01*
G01X5335810D02*
Y541898D01*
X5336430Y540022D01*
X5337670Y538773D01*
X5339220Y538356D01*
X5340770Y538773D01*
X5342010Y540022D01*
X5342630Y541898D01*
Y550856D01*
G01X5348520Y538356D02*
Y550856D01*
X5352395D01*
X5353635Y550231D01*
X5354410Y549398D01*
X5354720Y547731D01*
X5354410Y546064D01*
X5353480Y545023D01*
X5352395Y544398D01*
X5348520D01*
G01X5352395D02*
X5354720Y538356D01*
G01X5362160Y550856D02*
X5365880D01*
G01X5364020D02*
Y538356D01*
G01X5362160D02*
X5365880D01*
G01X5372855D02*
Y550856D01*
X5379985Y538356D01*
Y550856D01*
G01X5389750Y544606D02*
X5392850D01*
Y540856D01*
X5391920Y539606D01*
X5390835Y538773D01*
X5389285Y538356D01*
X5387735Y538773D01*
X5386650Y539606D01*
X5385720Y540856D01*
X5385100Y542314D01*
X5384790Y543981D01*
Y545439D01*
X5385100Y546689D01*
X5385720Y548148D01*
X5386650Y549398D01*
X5387580Y550231D01*
X5388820Y550856D01*
X5389905D01*
X5391145Y550439D01*
X5392075Y549606D01*
G01X5410365Y540022D02*
X5411605Y538981D01*
X5413000Y538356D01*
X5414240D01*
X5415480Y538981D01*
X5416410Y540022D01*
X5416875Y541481D01*
X5416565Y542939D01*
X5415790Y544189D01*
X5414395Y545023D01*
X5412535Y545439D01*
X5411450Y546273D01*
X5410985Y547731D01*
X5411295Y549189D01*
X5412070Y550231D01*
X5413155Y550856D01*
X5414240D01*
X5415325Y550439D01*
X5416255Y549398D01*
G01X5426020Y550856D02*
Y538356D01*
G01X5422455Y550856D02*
X5429585D01*
G01X5435010D02*
Y541898D01*
X5435630Y540022D01*
X5436870Y538773D01*
X5438420Y538356D01*
X5439970Y538773D01*
X5441210Y540022D01*
X5441830Y541898D01*
Y550856D01*
G01X5452060Y545023D02*
X5452680Y545648D01*
X5453145Y546689D01*
X5453455Y548148D01*
X5453145Y549398D01*
X5452525Y550231D01*
X5451440Y550856D01*
X5447255D01*
Y538356D01*
X5452370D01*
X5453455Y539189D01*
X5454075Y540439D01*
X5454385Y541898D01*
X5454075Y543356D01*
X5453145Y544606D01*
X5452060Y545023D01*
X5447255D01*
G01X5472520Y550856D02*
Y538356D01*
X5478720D01*
G01X5491120D02*
X5484920D01*
Y550856D01*
X5491120D01*
G01X5488640Y544814D02*
X5484920D01*
G01X5496855Y538356D02*
Y550856D01*
X5503985Y538356D01*
Y550856D01*
G01X5513750Y544606D02*
X5516850D01*
Y540856D01*
X5515920Y539606D01*
X5514835Y538773D01*
X5513285Y538356D01*
X5511735Y538773D01*
X5510650Y539606D01*
X5509720Y540856D01*
X5509100Y542314D01*
X5508790Y543981D01*
Y545439D01*
X5509100Y546689D01*
X5509720Y548148D01*
X5510650Y549398D01*
X5511580Y550231D01*
X5512820Y550856D01*
X5513905D01*
X5515145Y550439D01*
X5516075Y549606D01*
G01X5525220Y550856D02*
Y538356D01*
G01X5521655Y550856D02*
X5528785D01*
G01X5534365Y538356D02*
Y550856D01*
G01X5540875D02*
Y538356D01*
G01Y544606D02*
X5534365D01*
G01X5236765Y558772D02*
X5238005Y557731D01*
X5239400Y557106D01*
X5240640D01*
X5241880Y557731D01*
X5242810Y558772D01*
X5243275Y560231D01*
X5242965Y561689D01*
X5242190Y562939D01*
X5240795Y563773D01*
X5238935Y564189D01*
X5237850Y565023D01*
X5237385Y566481D01*
X5237695Y567939D01*
X5238470Y568981D01*
X5239555Y569606D01*
X5240640D01*
X5241725Y569189D01*
X5242655Y568148D01*
G01X5249010Y569606D02*
Y560648D01*
X5249630Y558772D01*
X5250870Y557523D01*
X5252420Y557106D01*
X5253970Y557523D01*
X5255210Y558772D01*
X5255830Y560648D01*
Y569606D01*
G01X5261720Y557106D02*
Y569606D01*
X5265595D01*
X5266835Y568981D01*
X5267610Y568148D01*
X5267920Y566481D01*
X5267610Y564814D01*
X5266680Y563773D01*
X5265595Y563148D01*
X5261720D01*
G01X5265595D02*
X5267920Y557106D01*
G01X5274275D02*
Y569606D01*
X5280165D01*
G01X5277995Y563564D02*
X5274275D01*
G01X5285745Y557106D02*
X5289620Y569606D01*
X5293495Y557106D01*
G01X5292100Y561481D02*
X5287140D01*
G01X5305430Y568564D02*
X5304500Y569189D01*
X5303415Y569606D01*
X5302175D01*
X5300780Y568981D01*
X5299695Y567939D01*
X5298920Y566689D01*
X5298300Y564606D01*
X5298145Y562731D01*
X5298455Y560856D01*
X5298920Y559606D01*
X5299850Y558356D01*
X5300935Y557523D01*
X5302020Y557106D01*
X5303105D01*
X5304190Y557523D01*
X5305120Y558147D01*
X5305895Y558981D01*
G01X5317520Y557106D02*
X5311320D01*
Y569606D01*
X5317520D01*
G01X5315040Y563564D02*
X5311320D01*
G01X5339220Y557106D02*
X5337980Y557314D01*
X5336895Y558147D01*
X5335965Y559398D01*
X5335345Y560856D01*
X5335035Y562523D01*
Y564189D01*
X5335345Y565856D01*
X5335965Y567314D01*
X5336895Y568564D01*
X5337980Y569398D01*
X5339220Y569606D01*
X5340460Y569398D01*
X5341545Y568564D01*
X5342475Y567314D01*
X5343095Y565856D01*
X5343405Y564189D01*
Y562523D01*
X5343095Y560856D01*
X5342475Y559398D01*
X5341545Y558147D01*
X5340460Y557314D01*
X5339220Y557106D01*
G01X5348675D02*
Y569606D01*
X5354565D01*
G01X5352395Y563564D02*
X5348675D01*
G01X5372390Y557106D02*
Y569606D01*
X5376420Y559189D01*
X5380450Y569606D01*
Y557106D01*
G01X5385410Y569606D02*
Y560648D01*
X5386030Y558772D01*
X5387270Y557523D01*
X5388820Y557106D01*
X5390370Y557523D01*
X5391610Y558772D01*
X5392230Y560648D01*
Y569606D01*
G01X5397965Y558772D02*
X5399205Y557731D01*
X5400600Y557106D01*
X5401840D01*
X5403080Y557731D01*
X5404010Y558772D01*
X5404475Y560231D01*
X5404165Y561689D01*
X5403390Y562939D01*
X5401995Y563773D01*
X5400135Y564189D01*
X5399050Y565023D01*
X5398585Y566481D01*
X5398895Y567939D01*
X5399670Y568981D01*
X5400755Y569606D01*
X5401840D01*
X5402925Y569189D01*
X5403855Y568148D01*
G01X5413620Y569606D02*
Y557106D01*
G01X5410055Y569606D02*
X5417185D01*
G01X5424005Y561273D02*
X5428035D01*
G01X5434855Y557106D02*
Y569606D01*
X5441985Y557106D01*
Y569606D01*
G01X5450820Y557106D02*
X5449580Y557314D01*
X5448495Y558147D01*
X5447565Y559398D01*
X5446945Y560856D01*
X5446635Y562523D01*
Y564189D01*
X5446945Y565856D01*
X5447565Y567314D01*
X5448495Y568564D01*
X5449580Y569398D01*
X5450820Y569606D01*
X5452060Y569398D01*
X5453145Y568564D01*
X5454075Y567314D01*
X5454695Y565856D01*
X5455005Y564189D01*
Y562523D01*
X5454695Y560856D01*
X5454075Y559398D01*
X5453145Y558147D01*
X5452060Y557314D01*
X5450820Y557106D01*
G01X5463220Y569606D02*
Y557106D01*
G01X5459655Y569606D02*
X5466785D01*
G01X5473605Y561273D02*
X5477635D01*
G01X5491430Y568564D02*
X5490500Y569189D01*
X5489415Y569606D01*
X5488175D01*
X5486780Y568981D01*
X5485695Y567939D01*
X5484920Y566689D01*
X5484300Y564606D01*
X5484145Y562731D01*
X5484455Y560856D01*
X5484920Y559606D01*
X5485850Y558356D01*
X5486935Y557523D01*
X5488020Y557106D01*
X5489105D01*
X5490190Y557523D01*
X5491120Y558147D01*
X5491895Y558981D01*
G01X5497010Y569606D02*
Y560648D01*
X5497630Y558772D01*
X5498870Y557523D01*
X5500420Y557106D01*
X5501970Y557523D01*
X5503210Y558772D01*
X5503830Y560648D01*
Y569606D01*
G01X5512820D02*
Y557106D01*
G01X5509255Y569606D02*
X5516385D01*
G01X5523205Y561273D02*
X5527235D01*
G01X5534520Y569606D02*
Y557106D01*
X5540720D01*
G01X5546145D02*
X5550020Y569606D01*
X5553895Y557106D01*
G01X5552500Y561481D02*
X5547540D01*
G01X5562420Y557106D02*
Y562731D01*
X5559320Y569606D01*
G01X5565520D02*
X5562420Y562731D01*
G01X5577920Y557106D02*
X5571720D01*
Y569606D01*
X5577920D01*
G01X5575440Y563564D02*
X5571720D01*
G01X5584120Y557106D02*
Y569606D01*
X5587995D01*
X5589235Y568981D01*
X5590010Y568148D01*
X5590320Y566481D01*
X5590010Y564814D01*
X5589080Y563773D01*
X5587995Y563148D01*
X5584120D01*
G01X5587995D02*
X5590320Y557106D01*
G01X5076805Y580023D02*
X5080835D01*
G01X5099590Y575856D02*
Y588356D01*
X5103620Y577939D01*
X5107650Y588356D01*
Y575856D01*
G01X5112145D02*
X5116020Y588356D01*
X5119895Y575856D01*
G01X5118500Y580231D02*
X5113540D01*
G01X5125165Y575856D02*
X5131675Y588356D01*
G01X5125165D02*
X5131675Y575856D01*
G01X5136170Y571689D02*
X5145470D01*
G01X5149810Y575856D02*
Y588356D01*
X5152910D01*
X5154150Y587731D01*
X5155080Y586898D01*
X5155855Y585648D01*
X5156475Y584189D01*
X5156630Y582106D01*
X5156475Y580023D01*
X5155855Y578564D01*
X5155080Y577314D01*
X5154150Y576481D01*
X5152910Y575856D01*
X5149810D01*
G01X5168720D02*
X5162520D01*
Y588356D01*
X5168720D01*
G01X5166240Y582314D02*
X5162520D01*
G01X5174920Y575856D02*
Y588356D01*
X5178640D01*
X5179880Y587731D01*
X5180810Y586273D01*
X5181120Y584606D01*
X5180810Y582939D01*
X5180035Y581689D01*
X5178640Y581064D01*
X5174920D01*
G01X5190420Y588356D02*
Y575856D01*
G01X5186855Y588356D02*
X5193985D01*
G01X5199565Y575856D02*
Y588356D01*
G01X5206075D02*
Y575856D01*
G01Y582106D02*
X5199565D01*
G01X5215220Y575439D02*
X5214910Y575648D01*
Y576064D01*
X5215220Y576273D01*
X5215530Y576064D01*
Y575648D01*
X5215220Y575439D01*
G01Y581064D02*
X5214910Y581273D01*
Y581689D01*
X5215220Y581898D01*
X5215530Y581689D01*
Y581273D01*
X5215220Y581064D01*
G01X5236610Y575856D02*
Y588356D01*
X5239710D01*
X5240950Y587731D01*
X5241880Y586898D01*
X5242655Y585648D01*
X5243275Y584189D01*
X5243430Y582106D01*
X5243275Y580023D01*
X5242655Y578564D01*
X5241880Y577314D01*
X5240950Y576481D01*
X5239710Y575856D01*
X5236610D01*
G01X5255520D02*
X5249320D01*
Y588356D01*
X5255520D01*
G01X5253040Y582314D02*
X5249320D01*
G01X5261720Y575856D02*
Y588356D01*
X5265440D01*
X5266680Y587731D01*
X5267610Y586273D01*
X5267920Y584606D01*
X5267610Y582939D01*
X5266835Y581689D01*
X5265440Y581064D01*
X5261720D01*
G01X5277220Y588356D02*
Y575856D01*
G01X5273655Y588356D02*
X5280785D01*
G01X5286365Y575856D02*
Y588356D01*
G01X5292875D02*
Y575856D01*
G01Y582106D02*
X5286365D01*
G01X5311475Y575856D02*
Y588356D01*
X5317365D01*
G01X5315195Y582314D02*
X5311475D01*
G01X5323720Y575856D02*
Y588356D01*
X5327595D01*
X5328835Y587731D01*
X5329610Y586898D01*
X5329920Y585231D01*
X5329610Y583564D01*
X5328680Y582523D01*
X5327595Y581898D01*
X5323720D01*
G01X5327595D02*
X5329920Y575856D01*
G01X5339220D02*
X5337980Y576064D01*
X5336895Y576897D01*
X5335965Y578148D01*
X5335345Y579606D01*
X5335035Y581273D01*
Y582939D01*
X5335345Y584606D01*
X5335965Y586064D01*
X5336895Y587314D01*
X5337980Y588148D01*
X5339220Y588356D01*
X5340460Y588148D01*
X5341545Y587314D01*
X5342475Y586064D01*
X5343095Y584606D01*
X5343405Y582939D01*
Y581273D01*
X5343095Y579606D01*
X5342475Y578148D01*
X5341545Y576897D01*
X5340460Y576064D01*
X5339220Y575856D01*
G01X5347590D02*
Y588356D01*
X5351620Y577939D01*
X5355650Y588356D01*
Y575856D01*
G01X5373165Y577522D02*
X5374405Y576481D01*
X5375800Y575856D01*
X5377040D01*
X5378280Y576481D01*
X5379210Y577522D01*
X5379675Y578981D01*
X5379365Y580439D01*
X5378590Y581689D01*
X5377195Y582523D01*
X5375335Y582939D01*
X5374250Y583773D01*
X5373785Y585231D01*
X5374095Y586689D01*
X5374870Y587731D01*
X5375955Y588356D01*
X5377040D01*
X5378125Y587939D01*
X5379055Y586898D01*
G01X5388820Y588356D02*
Y575856D01*
G01X5385255Y588356D02*
X5392385D01*
G01X5397345Y575856D02*
X5401220Y588356D01*
X5405095Y575856D01*
G01X5403700Y580231D02*
X5398740D01*
G01X5410520Y575856D02*
Y588356D01*
X5414395D01*
X5415635Y587731D01*
X5416410Y586898D01*
X5416720Y585231D01*
X5416410Y583564D01*
X5415480Y582523D01*
X5414395Y581898D01*
X5410520D01*
G01X5414395D02*
X5416720Y575856D01*
G01X5426020Y588356D02*
Y575856D01*
G01X5422455Y588356D02*
X5429585D01*
G01X5447720D02*
Y575856D01*
X5453920D01*
G01X5459345D02*
X5463220Y588356D01*
X5467095Y575856D01*
G01X5465700Y580231D02*
X5460740D01*
G01X5475620Y575856D02*
Y581481D01*
X5472520Y588356D01*
G01X5478720D02*
X5475620Y581481D01*
G01X5491120Y575856D02*
X5484920D01*
Y588356D01*
X5491120D01*
G01X5488640Y582314D02*
X5484920D01*
G01X5497320Y575856D02*
Y588356D01*
X5501195D01*
X5502435Y587731D01*
X5503210Y586898D01*
X5503520Y585231D01*
X5503210Y583564D01*
X5502280Y582523D01*
X5501195Y581898D01*
X5497320D01*
G01X5501195D02*
X5503520Y575856D01*
G01X5525220Y588356D02*
Y575856D01*
G01X5521655Y588356D02*
X5528785D01*
G01X5537620Y575856D02*
X5536380Y576064D01*
X5535295Y576897D01*
X5534365Y578148D01*
X5533745Y579606D01*
X5533435Y581273D01*
Y582939D01*
X5533745Y584606D01*
X5534365Y586064D01*
X5535295Y587314D01*
X5536380Y588148D01*
X5537620Y588356D01*
X5538860Y588148D01*
X5539945Y587314D01*
X5540875Y586064D01*
X5541495Y584606D01*
X5541805Y582939D01*
Y581273D01*
X5541495Y579606D01*
X5540875Y578148D01*
X5539945Y576897D01*
X5538860Y576064D01*
X5537620Y575856D01*
G01X5562420Y588356D02*
Y575856D01*
G01X5558855Y588356D02*
X5565985D01*
G01X5571565Y575856D02*
Y588356D01*
G01X5578075D02*
Y575856D01*
G01Y582106D02*
X5571565D01*
G01X5590320Y575856D02*
X5584120D01*
Y588356D01*
X5590320D01*
G01X5587840Y582314D02*
X5584120D01*
G01X5076805Y598773D02*
X5080835D01*
G01X5099590Y594606D02*
Y607106D01*
X5103620Y596689D01*
X5107650Y607106D01*
Y594606D01*
G01X5112455D02*
Y607106D01*
X5119585Y594606D01*
Y607106D01*
G01X5131830Y606064D02*
X5130900Y606689D01*
X5129815Y607106D01*
X5128575D01*
X5127180Y606481D01*
X5126095Y605439D01*
X5125320Y604189D01*
X5124700Y602106D01*
X5124545Y600231D01*
X5124855Y598356D01*
X5125320Y597106D01*
X5126250Y595856D01*
X5127335Y595023D01*
X5128420Y594606D01*
X5129505D01*
X5130590Y595023D01*
X5131520Y595647D01*
X5132295Y596481D01*
G01X5136170Y590439D02*
X5145470D01*
G01X5150120Y607106D02*
Y594606D01*
X5156320D01*
G01X5161745D02*
X5165620Y607106D01*
X5169495Y594606D01*
G01X5168100Y598981D02*
X5163140D01*
G01X5178020Y594606D02*
Y600231D01*
X5174920Y607106D01*
G01X5181120D02*
X5178020Y600231D01*
G01X5193520Y594606D02*
X5187320D01*
Y607106D01*
X5193520D01*
G01X5191040Y601064D02*
X5187320D01*
G01X5199720Y594606D02*
Y607106D01*
X5203595D01*
X5204835Y606481D01*
X5205610Y605648D01*
X5205920Y603981D01*
X5205610Y602314D01*
X5204680Y601273D01*
X5203595Y600648D01*
X5199720D01*
G01X5203595D02*
X5205920Y594606D01*
G01X5215220Y594189D02*
X5214910Y594398D01*
Y594814D01*
X5215220Y595023D01*
X5215530Y594814D01*
Y594398D01*
X5215220Y594189D01*
G01Y599814D02*
X5214910Y600023D01*
Y600439D01*
X5215220Y600648D01*
X5215530Y600439D01*
Y600023D01*
X5215220Y599814D01*
G01X5235990Y594606D02*
Y607106D01*
X5240020Y596689D01*
X5244050Y607106D01*
Y594606D01*
G01X5249010Y607106D02*
Y598148D01*
X5249630Y596272D01*
X5250870Y595023D01*
X5252420Y594606D01*
X5253970Y595023D01*
X5255210Y596272D01*
X5255830Y598148D01*
Y607106D01*
G01X5261565Y596272D02*
X5262805Y595231D01*
X5264200Y594606D01*
X5265440D01*
X5266680Y595231D01*
X5267610Y596272D01*
X5268075Y597731D01*
X5267765Y599189D01*
X5266990Y600439D01*
X5265595Y601273D01*
X5263735Y601689D01*
X5262650Y602523D01*
X5262185Y603981D01*
X5262495Y605439D01*
X5263270Y606481D01*
X5264355Y607106D01*
X5265440D01*
X5266525Y606689D01*
X5267455Y605648D01*
G01X5277220Y607106D02*
Y594606D01*
G01X5273655Y607106D02*
X5280785D01*
G01X5287605Y598773D02*
X5291635D01*
G01X5298455Y594606D02*
Y607106D01*
X5305585Y594606D01*
Y607106D01*
G01X5314420Y594606D02*
X5313180Y594814D01*
X5312095Y595647D01*
X5311165Y596898D01*
X5310545Y598356D01*
X5310235Y600023D01*
Y601689D01*
X5310545Y603356D01*
X5311165Y604814D01*
X5312095Y606064D01*
X5313180Y606898D01*
X5314420Y607106D01*
X5315660Y606898D01*
X5316745Y606064D01*
X5317675Y604814D01*
X5318295Y603356D01*
X5318605Y601689D01*
Y600023D01*
X5318295Y598356D01*
X5317675Y596898D01*
X5316745Y595647D01*
X5315660Y594814D01*
X5314420Y594606D01*
G01X5326820Y607106D02*
Y594606D01*
G01X5323255Y607106D02*
X5330385D01*
G01X5337205Y598773D02*
X5341235D01*
G01X5355030Y606064D02*
X5354100Y606689D01*
X5353015Y607106D01*
X5351775D01*
X5350380Y606481D01*
X5349295Y605439D01*
X5348520Y604189D01*
X5347900Y602106D01*
X5347745Y600231D01*
X5348055Y598356D01*
X5348520Y597106D01*
X5349450Y595856D01*
X5350535Y595023D01*
X5351620Y594606D01*
X5352705D01*
X5353790Y595023D01*
X5354720Y595647D01*
X5355495Y596481D01*
G01X5360610Y607106D02*
Y598148D01*
X5361230Y596272D01*
X5362470Y595023D01*
X5364020Y594606D01*
X5365570Y595023D01*
X5366810Y596272D01*
X5367430Y598148D01*
Y607106D01*
G01X5376420D02*
Y594606D01*
G01X5372855Y607106D02*
X5379985D01*
G01X5386805Y598773D02*
X5390835D01*
G01X5398120Y607106D02*
Y594606D01*
X5404320D01*
G01X5409745D02*
X5413620Y607106D01*
X5417495Y594606D01*
G01X5416100Y598981D02*
X5411140D01*
G01X5426020Y594606D02*
Y600231D01*
X5422920Y607106D01*
G01X5429120D02*
X5426020Y600231D01*
G01X5441520Y594606D02*
X5435320D01*
Y607106D01*
X5441520D01*
G01X5439040Y601064D02*
X5435320D01*
G01X5447720Y594606D02*
Y607106D01*
X5451595D01*
X5452835Y606481D01*
X5453610Y605648D01*
X5453920Y603981D01*
X5453610Y602314D01*
X5452680Y601273D01*
X5451595Y600648D01*
X5447720D01*
G01X5451595D02*
X5453920Y594606D01*
G01X5075255Y613356D02*
Y625856D01*
X5082385Y613356D01*
Y625856D01*
G01X5091220Y613356D02*
X5089980Y613564D01*
X5088895Y614397D01*
X5087965Y615648D01*
X5087345Y617106D01*
X5087035Y618773D01*
Y620439D01*
X5087345Y622106D01*
X5087965Y623564D01*
X5088895Y624814D01*
X5089980Y625648D01*
X5091220Y625856D01*
X5092460Y625648D01*
X5093545Y624814D01*
X5094475Y623564D01*
X5095095Y622106D01*
X5095405Y620439D01*
Y618773D01*
X5095095Y617106D01*
X5094475Y615648D01*
X5093545Y614397D01*
X5092460Y613564D01*
X5091220Y613356D01*
G01X5103620Y625856D02*
Y613356D01*
G01X5100055Y625856D02*
X5107185D01*
G01X5119120Y613356D02*
X5112920D01*
Y625856D01*
X5119120D01*
G01X5116640Y619814D02*
X5112920D01*
G01X5125165Y615022D02*
X5126405Y613981D01*
X5127800Y613356D01*
X5129040D01*
X5130280Y613981D01*
X5131210Y615022D01*
X5131675Y616481D01*
X5131365Y617939D01*
X5130590Y619189D01*
X5129195Y620023D01*
X5127335Y620439D01*
X5126250Y621273D01*
X5125785Y622731D01*
X5126095Y624189D01*
X5126870Y625231D01*
X5127955Y625856D01*
X5129040D01*
X5130125Y625439D01*
X5131055Y624398D01*
G01X5140820Y612939D02*
X5140510Y613148D01*
Y613564D01*
X5140820Y613773D01*
X5141130Y613564D01*
Y613148D01*
X5140820Y612939D01*
G01Y618564D02*
X5140510Y618773D01*
Y619189D01*
X5140820Y619398D01*
X5141130Y619189D01*
Y618773D01*
X5140820Y618564D01*
G01X5242260Y1097773D02*
X5242880Y1098398D01*
X5243345Y1099439D01*
X5243655Y1100898D01*
X5243345Y1102148D01*
X5242725Y1102981D01*
X5241640Y1103606D01*
X5237455D01*
Y1091106D01*
X5242570D01*
X5243655Y1091939D01*
X5244275Y1093189D01*
X5244585Y1094648D01*
X5244275Y1096106D01*
X5243345Y1097356D01*
X5242260Y1097773D01*
X5237455D01*
G01X5249545Y1091106D02*
X5253420Y1103606D01*
X5257295Y1091106D01*
G01X5255900Y1095481D02*
X5250940D01*
G01X5269230Y1102564D02*
X5268300Y1103189D01*
X5267215Y1103606D01*
X5265975D01*
X5264580Y1102981D01*
X5263495Y1101939D01*
X5262720Y1100689D01*
X5262100Y1098606D01*
X5261945Y1096731D01*
X5262255Y1094856D01*
X5262720Y1093606D01*
X5263650Y1092356D01*
X5264735Y1091523D01*
X5265820Y1091106D01*
X5266905D01*
X5267990Y1091523D01*
X5268920Y1092147D01*
X5269695Y1092981D01*
G01X5274810Y1091106D02*
Y1103606D01*
G01X5280700D02*
X5274810Y1095897D01*
G01X5281630Y1091106D02*
X5277445Y1099439D01*
G01X5287210Y1091106D02*
Y1103606D01*
X5290310D01*
X5291550Y1102981D01*
X5292480Y1102148D01*
X5293255Y1100898D01*
X5293875Y1099439D01*
X5294030Y1097356D01*
X5293875Y1095273D01*
X5293255Y1093814D01*
X5292480Y1092564D01*
X5291550Y1091731D01*
X5290310Y1091106D01*
X5287210D01*
G01X5299920D02*
Y1103606D01*
X5303795D01*
X5305035Y1102981D01*
X5305810Y1102148D01*
X5306120Y1100481D01*
X5305810Y1098814D01*
X5304880Y1097773D01*
X5303795Y1097148D01*
X5299920D01*
G01X5303795D02*
X5306120Y1091106D01*
G01X5313560Y1103606D02*
X5317280D01*
G01X5315420D02*
Y1091106D01*
G01X5313560D02*
X5317280D01*
G01X5324720Y1103606D02*
Y1091106D01*
X5330920D01*
G01X5337120Y1103606D02*
Y1091106D01*
X5343320D01*
G01X5361765Y1092772D02*
X5363005Y1091731D01*
X5364400Y1091106D01*
X5365640D01*
X5366880Y1091731D01*
X5367810Y1092772D01*
X5368275Y1094231D01*
X5367965Y1095689D01*
X5367190Y1096939D01*
X5365795Y1097773D01*
X5363935Y1098189D01*
X5362850Y1099023D01*
X5362385Y1100481D01*
X5362695Y1101939D01*
X5363470Y1102981D01*
X5364555Y1103606D01*
X5365640D01*
X5366725Y1103189D01*
X5367655Y1102148D01*
G01X5377420Y1103606D02*
Y1091106D01*
G01X5373855Y1103606D02*
X5380985D01*
G01X5386410D02*
Y1094648D01*
X5387030Y1092772D01*
X5388270Y1091523D01*
X5389820Y1091106D01*
X5391370Y1091523D01*
X5392610Y1092772D01*
X5393230Y1094648D01*
Y1103606D01*
G01X5403460Y1097773D02*
X5404080Y1098398D01*
X5404545Y1099439D01*
X5404855Y1100898D01*
X5404545Y1102148D01*
X5403925Y1102981D01*
X5402840Y1103606D01*
X5398655D01*
Y1091106D01*
X5403770D01*
X5404855Y1091939D01*
X5405475Y1093189D01*
X5405785Y1094648D01*
X5405475Y1096106D01*
X5404545Y1097356D01*
X5403460Y1097773D01*
X5398655D01*
G01X5423920Y1103606D02*
Y1091106D01*
X5430120D01*
G01X5442520D02*
X5436320D01*
Y1103606D01*
X5442520D01*
G01X5440040Y1097564D02*
X5436320D01*
G01X5448255Y1091106D02*
Y1103606D01*
X5455385Y1091106D01*
Y1103606D01*
G01X5465150Y1097356D02*
X5468250D01*
Y1093606D01*
X5467320Y1092356D01*
X5466235Y1091523D01*
X5464685Y1091106D01*
X5463135Y1091523D01*
X5462050Y1092356D01*
X5461120Y1093606D01*
X5460500Y1095064D01*
X5460190Y1096731D01*
Y1098189D01*
X5460500Y1099439D01*
X5461120Y1100898D01*
X5462050Y1102148D01*
X5462980Y1102981D01*
X5464220Y1103606D01*
X5465305D01*
X5466545Y1103189D01*
X5467475Y1102356D01*
G01X5476620Y1103606D02*
Y1091106D01*
G01X5473055Y1103606D02*
X5480185D01*
G01X5485765Y1091106D02*
Y1103606D01*
G01X5492275D02*
Y1091106D01*
G01Y1097356D02*
X5485765D01*
G01X5513820Y1103606D02*
Y1091106D01*
G01X5510255Y1103606D02*
X5517385D01*
G01X5526220Y1091106D02*
X5524980Y1091314D01*
X5523895Y1092147D01*
X5522965Y1093398D01*
X5522345Y1094856D01*
X5522035Y1096523D01*
Y1098189D01*
X5522345Y1099856D01*
X5522965Y1101314D01*
X5523895Y1102564D01*
X5524980Y1103398D01*
X5526220Y1103606D01*
X5527460Y1103398D01*
X5528545Y1102564D01*
X5529475Y1101314D01*
X5530095Y1099856D01*
X5530405Y1098189D01*
Y1096523D01*
X5530095Y1094856D01*
X5529475Y1093398D01*
X5528545Y1092147D01*
X5527460Y1091314D01*
X5526220Y1091106D01*
G01X5535520Y1103606D02*
Y1091106D01*
X5541720D01*
G01X5554120D02*
X5547920D01*
Y1103606D01*
X5554120D01*
G01X5551640Y1097564D02*
X5547920D01*
G01X5560320Y1091106D02*
Y1103606D01*
X5564195D01*
X5565435Y1102981D01*
X5566210Y1102148D01*
X5566520Y1100481D01*
X5566210Y1098814D01*
X5565280Y1097773D01*
X5564195Y1097148D01*
X5560320D01*
G01X5564195D02*
X5566520Y1091106D01*
G01X5571945D02*
X5575820Y1103606D01*
X5579695Y1091106D01*
G01X5578300Y1095481D02*
X5573340D01*
G01X5584655Y1091106D02*
Y1103606D01*
X5591785Y1091106D01*
Y1103606D01*
G01X5604030Y1102564D02*
X5603100Y1103189D01*
X5602015Y1103606D01*
X5600775D01*
X5599380Y1102981D01*
X5598295Y1101939D01*
X5597520Y1100689D01*
X5596900Y1098606D01*
X5596745Y1096731D01*
X5597055Y1094856D01*
X5597520Y1093606D01*
X5598450Y1092356D01*
X5599535Y1091523D01*
X5600620Y1091106D01*
X5601705D01*
X5602790Y1091523D01*
X5603720Y1092147D01*
X5604495Y1092981D01*
G01X5616120Y1091106D02*
X5609920D01*
Y1103606D01*
X5616120D01*
G01X5613640Y1097564D02*
X5609920D01*
G01X5637820Y1103606D02*
Y1091106D01*
G01X5634255Y1103606D02*
X5641385D01*
G01X5650220Y1091106D02*
X5648980Y1091314D01*
X5647895Y1092147D01*
X5646965Y1093398D01*
X5646345Y1094856D01*
X5646035Y1096523D01*
Y1098189D01*
X5646345Y1099856D01*
X5646965Y1101314D01*
X5647895Y1102564D01*
X5648980Y1103398D01*
X5650220Y1103606D01*
X5651460Y1103398D01*
X5652545Y1102564D01*
X5653475Y1101314D01*
X5654095Y1099856D01*
X5654405Y1098189D01*
Y1096523D01*
X5654095Y1094856D01*
X5653475Y1093398D01*
X5652545Y1092147D01*
X5651460Y1091314D01*
X5650220Y1091106D01*
G01X5676260Y1097773D02*
X5676880Y1098398D01*
X5677345Y1099439D01*
X5677655Y1100898D01*
X5677345Y1102148D01*
X5676725Y1102981D01*
X5675640Y1103606D01*
X5671455D01*
Y1091106D01*
X5676570D01*
X5677655Y1091939D01*
X5678275Y1093189D01*
X5678585Y1094648D01*
X5678275Y1096106D01*
X5677345Y1097356D01*
X5676260Y1097773D01*
X5671455D01*
G01X5690520Y1091106D02*
X5684320D01*
Y1103606D01*
X5690520D01*
G01X5688040Y1097564D02*
X5684320D01*
G01X5711910Y1091106D02*
X5712220Y1093814D01*
X5712685Y1096106D01*
X5713305Y1098189D01*
X5714080Y1100481D01*
X5715320Y1103606D01*
X5709120D01*
G01X5735315Y1095273D02*
X5739035D01*
G01X5737020Y1097981D02*
Y1092564D01*
G01X5746630Y1090689D02*
X5752210Y1103606D01*
G01X5759805Y1095273D02*
X5763835D01*
G01X5770810Y1092981D02*
X5771740Y1091939D01*
X5772825Y1091314D01*
X5774220Y1091106D01*
X5775615Y1091523D01*
X5776700Y1092356D01*
X5777475Y1093814D01*
X5777630Y1095481D01*
X5777320Y1097148D01*
X5776545Y1098189D01*
X5775460Y1099023D01*
X5774375Y1099231D01*
X5773290Y1099023D01*
X5771895Y1098189D01*
X5772360Y1103606D01*
X5776545D01*
G01X5794990Y1091106D02*
Y1103606D01*
X5799020Y1093189D01*
X5803050Y1103606D01*
Y1091106D01*
G01X5809560Y1103606D02*
X5813280D01*
G01X5811420D02*
Y1091106D01*
G01X5809560D02*
X5813280D01*
G01X5820720Y1103606D02*
Y1091106D01*
X5826920D01*
G01X5832965Y1092772D02*
X5834205Y1091731D01*
X5835600Y1091106D01*
X5836840D01*
X5838080Y1091731D01*
X5839010Y1092772D01*
X5839475Y1094231D01*
X5839165Y1095689D01*
X5838390Y1096939D01*
X5836995Y1097773D01*
X5835135Y1098189D01*
X5834050Y1099023D01*
X5833585Y1100481D01*
X5833895Y1101939D01*
X5834670Y1102981D01*
X5835755Y1103606D01*
X5836840D01*
X5837925Y1103189D01*
X5838855Y1102148D01*
G01X5077805Y1114023D02*
X5081835D01*
G01X5100590Y1109856D02*
Y1122356D01*
X5104620Y1111939D01*
X5108650Y1122356D01*
Y1109856D01*
G01X5114075D02*
Y1122356D01*
X5119965D01*
G01X5117795Y1116314D02*
X5114075D01*
G01X5130350Y1116106D02*
X5133450D01*
Y1112356D01*
X5132520Y1111106D01*
X5131435Y1110273D01*
X5129885Y1109856D01*
X5128335Y1110273D01*
X5127250Y1111106D01*
X5126320Y1112356D01*
X5125700Y1113814D01*
X5125390Y1115481D01*
Y1116939D01*
X5125700Y1118189D01*
X5126320Y1119648D01*
X5127250Y1120898D01*
X5128180Y1121731D01*
X5129420Y1122356D01*
X5130505D01*
X5131745Y1121939D01*
X5132675Y1121106D01*
G01X5137170Y1105689D02*
X5146470D01*
G01X5150965Y1111522D02*
X5152205Y1110481D01*
X5153600Y1109856D01*
X5154840D01*
X5156080Y1110481D01*
X5157010Y1111522D01*
X5157475Y1112981D01*
X5157165Y1114439D01*
X5156390Y1115689D01*
X5154995Y1116523D01*
X5153135Y1116939D01*
X5152050Y1117773D01*
X5151585Y1119231D01*
X5151895Y1120689D01*
X5152670Y1121731D01*
X5153755Y1122356D01*
X5154840D01*
X5155925Y1121939D01*
X5156855Y1120898D01*
G01X5166620Y1122356D02*
Y1109856D01*
G01X5163055Y1122356D02*
X5170185D01*
G01X5175610D02*
Y1113398D01*
X5176230Y1111522D01*
X5177470Y1110273D01*
X5179020Y1109856D01*
X5180570Y1110273D01*
X5181810Y1111522D01*
X5182430Y1113398D01*
Y1122356D01*
G01X5192660Y1116523D02*
X5193280Y1117148D01*
X5193745Y1118189D01*
X5194055Y1119648D01*
X5193745Y1120898D01*
X5193125Y1121731D01*
X5192040Y1122356D01*
X5187855D01*
Y1109856D01*
X5192970D01*
X5194055Y1110689D01*
X5194675Y1111939D01*
X5194985Y1113398D01*
X5194675Y1114856D01*
X5193745Y1116106D01*
X5192660Y1116523D01*
X5187855D01*
G01X5216220Y1109439D02*
X5215910Y1109648D01*
Y1110064D01*
X5216220Y1110273D01*
X5216530Y1110064D01*
Y1109648D01*
X5216220Y1109439D01*
G01Y1115064D02*
X5215910Y1115273D01*
Y1115689D01*
X5216220Y1115898D01*
X5216530Y1115689D01*
Y1115273D01*
X5216220Y1115064D01*
G01X5236990Y1109856D02*
Y1122356D01*
X5241020Y1111939D01*
X5245050Y1122356D01*
Y1109856D01*
G01X5249545D02*
X5253420Y1122356D01*
X5257295Y1109856D01*
G01X5255900Y1114231D02*
X5250940D01*
G01X5262255Y1109856D02*
Y1122356D01*
X5269385Y1109856D01*
Y1122356D01*
G01X5274810D02*
Y1113398D01*
X5275430Y1111522D01*
X5276670Y1110273D01*
X5278220Y1109856D01*
X5279770Y1110273D01*
X5281010Y1111522D01*
X5281630Y1113398D01*
Y1122356D01*
G01X5287675Y1109856D02*
Y1122356D01*
X5293565D01*
G01X5291395Y1116314D02*
X5287675D01*
G01X5299145Y1109856D02*
X5303020Y1122356D01*
X5306895Y1109856D01*
G01X5305500Y1114231D02*
X5300540D01*
G01X5318830Y1121314D02*
X5317900Y1121939D01*
X5316815Y1122356D01*
X5315575D01*
X5314180Y1121731D01*
X5313095Y1120689D01*
X5312320Y1119439D01*
X5311700Y1117356D01*
X5311545Y1115481D01*
X5311855Y1113606D01*
X5312320Y1112356D01*
X5313250Y1111106D01*
X5314335Y1110273D01*
X5315420Y1109856D01*
X5316505D01*
X5317590Y1110273D01*
X5318520Y1110897D01*
X5319295Y1111731D01*
G01X5327820Y1122356D02*
Y1109856D01*
G01X5324255Y1122356D02*
X5331385D01*
G01X5336810D02*
Y1113398D01*
X5337430Y1111522D01*
X5338670Y1110273D01*
X5340220Y1109856D01*
X5341770Y1110273D01*
X5343010Y1111522D01*
X5343630Y1113398D01*
Y1122356D01*
G01X5349520Y1109856D02*
Y1122356D01*
X5353395D01*
X5354635Y1121731D01*
X5355410Y1120898D01*
X5355720Y1119231D01*
X5355410Y1117564D01*
X5354480Y1116523D01*
X5353395Y1115898D01*
X5349520D01*
G01X5353395D02*
X5355720Y1109856D01*
G01X5363160Y1122356D02*
X5366880D01*
G01X5365020D02*
Y1109856D01*
G01X5363160D02*
X5366880D01*
G01X5373855D02*
Y1122356D01*
X5380985Y1109856D01*
Y1122356D01*
G01X5390750Y1116106D02*
X5393850D01*
Y1112356D01*
X5392920Y1111106D01*
X5391835Y1110273D01*
X5390285Y1109856D01*
X5388735Y1110273D01*
X5387650Y1111106D01*
X5386720Y1112356D01*
X5386100Y1113814D01*
X5385790Y1115481D01*
Y1116939D01*
X5386100Y1118189D01*
X5386720Y1119648D01*
X5387650Y1120898D01*
X5388580Y1121731D01*
X5389820Y1122356D01*
X5390905D01*
X5392145Y1121939D01*
X5393075Y1121106D01*
G01X5411365Y1111522D02*
X5412605Y1110481D01*
X5414000Y1109856D01*
X5415240D01*
X5416480Y1110481D01*
X5417410Y1111522D01*
X5417875Y1112981D01*
X5417565Y1114439D01*
X5416790Y1115689D01*
X5415395Y1116523D01*
X5413535Y1116939D01*
X5412450Y1117773D01*
X5411985Y1119231D01*
X5412295Y1120689D01*
X5413070Y1121731D01*
X5414155Y1122356D01*
X5415240D01*
X5416325Y1121939D01*
X5417255Y1120898D01*
G01X5427020Y1122356D02*
Y1109856D01*
G01X5423455Y1122356D02*
X5430585D01*
G01X5436010D02*
Y1113398D01*
X5436630Y1111522D01*
X5437870Y1110273D01*
X5439420Y1109856D01*
X5440970Y1110273D01*
X5442210Y1111522D01*
X5442830Y1113398D01*
Y1122356D01*
G01X5453060Y1116523D02*
X5453680Y1117148D01*
X5454145Y1118189D01*
X5454455Y1119648D01*
X5454145Y1120898D01*
X5453525Y1121731D01*
X5452440Y1122356D01*
X5448255D01*
Y1109856D01*
X5453370D01*
X5454455Y1110689D01*
X5455075Y1111939D01*
X5455385Y1113398D01*
X5455075Y1114856D01*
X5454145Y1116106D01*
X5453060Y1116523D01*
X5448255D01*
G01X5473520Y1122356D02*
Y1109856D01*
X5479720D01*
G01X5492120D02*
X5485920D01*
Y1122356D01*
X5492120D01*
G01X5489640Y1116314D02*
X5485920D01*
G01X5497855Y1109856D02*
Y1122356D01*
X5504985Y1109856D01*
Y1122356D01*
G01X5514750Y1116106D02*
X5517850D01*
Y1112356D01*
X5516920Y1111106D01*
X5515835Y1110273D01*
X5514285Y1109856D01*
X5512735Y1110273D01*
X5511650Y1111106D01*
X5510720Y1112356D01*
X5510100Y1113814D01*
X5509790Y1115481D01*
Y1116939D01*
X5510100Y1118189D01*
X5510720Y1119648D01*
X5511650Y1120898D01*
X5512580Y1121731D01*
X5513820Y1122356D01*
X5514905D01*
X5516145Y1121939D01*
X5517075Y1121106D01*
G01X5526220Y1122356D02*
Y1109856D01*
G01X5522655Y1122356D02*
X5529785D01*
G01X5535365Y1109856D02*
Y1122356D01*
G01X5541875D02*
Y1109856D01*
G01Y1116106D02*
X5535365D01*
G01X5237765Y1130272D02*
X5239005Y1129231D01*
X5240400Y1128606D01*
X5241640D01*
X5242880Y1129231D01*
X5243810Y1130272D01*
X5244275Y1131731D01*
X5243965Y1133189D01*
X5243190Y1134439D01*
X5241795Y1135273D01*
X5239935Y1135689D01*
X5238850Y1136523D01*
X5238385Y1137981D01*
X5238695Y1139439D01*
X5239470Y1140481D01*
X5240555Y1141106D01*
X5241640D01*
X5242725Y1140689D01*
X5243655Y1139648D01*
G01X5250010Y1141106D02*
Y1132148D01*
X5250630Y1130272D01*
X5251870Y1129023D01*
X5253420Y1128606D01*
X5254970Y1129023D01*
X5256210Y1130272D01*
X5256830Y1132148D01*
Y1141106D01*
G01X5262720Y1128606D02*
Y1141106D01*
X5266595D01*
X5267835Y1140481D01*
X5268610Y1139648D01*
X5268920Y1137981D01*
X5268610Y1136314D01*
X5267680Y1135273D01*
X5266595Y1134648D01*
X5262720D01*
G01X5266595D02*
X5268920Y1128606D01*
G01X5275275D02*
Y1141106D01*
X5281165D01*
G01X5278995Y1135064D02*
X5275275D01*
G01X5286745Y1128606D02*
X5290620Y1141106D01*
X5294495Y1128606D01*
G01X5293100Y1132981D02*
X5288140D01*
G01X5306430Y1140064D02*
X5305500Y1140689D01*
X5304415Y1141106D01*
X5303175D01*
X5301780Y1140481D01*
X5300695Y1139439D01*
X5299920Y1138189D01*
X5299300Y1136106D01*
X5299145Y1134231D01*
X5299455Y1132356D01*
X5299920Y1131106D01*
X5300850Y1129856D01*
X5301935Y1129023D01*
X5303020Y1128606D01*
X5304105D01*
X5305190Y1129023D01*
X5306120Y1129647D01*
X5306895Y1130481D01*
G01X5318520Y1128606D02*
X5312320D01*
Y1141106D01*
X5318520D01*
G01X5316040Y1135064D02*
X5312320D01*
G01X5340220Y1128606D02*
X5338980Y1128814D01*
X5337895Y1129647D01*
X5336965Y1130898D01*
X5336345Y1132356D01*
X5336035Y1134023D01*
Y1135689D01*
X5336345Y1137356D01*
X5336965Y1138814D01*
X5337895Y1140064D01*
X5338980Y1140898D01*
X5340220Y1141106D01*
X5341460Y1140898D01*
X5342545Y1140064D01*
X5343475Y1138814D01*
X5344095Y1137356D01*
X5344405Y1135689D01*
Y1134023D01*
X5344095Y1132356D01*
X5343475Y1130898D01*
X5342545Y1129647D01*
X5341460Y1128814D01*
X5340220Y1128606D01*
G01X5349675D02*
Y1141106D01*
X5355565D01*
G01X5353395Y1135064D02*
X5349675D01*
G01X5373390Y1128606D02*
Y1141106D01*
X5377420Y1130689D01*
X5381450Y1141106D01*
Y1128606D01*
G01X5386410Y1141106D02*
Y1132148D01*
X5387030Y1130272D01*
X5388270Y1129023D01*
X5389820Y1128606D01*
X5391370Y1129023D01*
X5392610Y1130272D01*
X5393230Y1132148D01*
Y1141106D01*
G01X5398965Y1130272D02*
X5400205Y1129231D01*
X5401600Y1128606D01*
X5402840D01*
X5404080Y1129231D01*
X5405010Y1130272D01*
X5405475Y1131731D01*
X5405165Y1133189D01*
X5404390Y1134439D01*
X5402995Y1135273D01*
X5401135Y1135689D01*
X5400050Y1136523D01*
X5399585Y1137981D01*
X5399895Y1139439D01*
X5400670Y1140481D01*
X5401755Y1141106D01*
X5402840D01*
X5403925Y1140689D01*
X5404855Y1139648D01*
G01X5414620Y1141106D02*
Y1128606D01*
G01X5411055Y1141106D02*
X5418185D01*
G01X5425005Y1132773D02*
X5429035D01*
G01X5435855Y1128606D02*
Y1141106D01*
X5442985Y1128606D01*
Y1141106D01*
G01X5451820Y1128606D02*
X5450580Y1128814D01*
X5449495Y1129647D01*
X5448565Y1130898D01*
X5447945Y1132356D01*
X5447635Y1134023D01*
Y1135689D01*
X5447945Y1137356D01*
X5448565Y1138814D01*
X5449495Y1140064D01*
X5450580Y1140898D01*
X5451820Y1141106D01*
X5453060Y1140898D01*
X5454145Y1140064D01*
X5455075Y1138814D01*
X5455695Y1137356D01*
X5456005Y1135689D01*
Y1134023D01*
X5455695Y1132356D01*
X5455075Y1130898D01*
X5454145Y1129647D01*
X5453060Y1128814D01*
X5451820Y1128606D01*
G01X5464220Y1141106D02*
Y1128606D01*
G01X5460655Y1141106D02*
X5467785D01*
G01X5474605Y1132773D02*
X5478635D01*
G01X5492430Y1140064D02*
X5491500Y1140689D01*
X5490415Y1141106D01*
X5489175D01*
X5487780Y1140481D01*
X5486695Y1139439D01*
X5485920Y1138189D01*
X5485300Y1136106D01*
X5485145Y1134231D01*
X5485455Y1132356D01*
X5485920Y1131106D01*
X5486850Y1129856D01*
X5487935Y1129023D01*
X5489020Y1128606D01*
X5490105D01*
X5491190Y1129023D01*
X5492120Y1129647D01*
X5492895Y1130481D01*
G01X5498010Y1141106D02*
Y1132148D01*
X5498630Y1130272D01*
X5499870Y1129023D01*
X5501420Y1128606D01*
X5502970Y1129023D01*
X5504210Y1130272D01*
X5504830Y1132148D01*
Y1141106D01*
G01X5513820D02*
Y1128606D01*
G01X5510255Y1141106D02*
X5517385D01*
G01X5524205Y1132773D02*
X5528235D01*
G01X5535520Y1141106D02*
Y1128606D01*
X5541720D01*
G01X5547145D02*
X5551020Y1141106D01*
X5554895Y1128606D01*
G01X5553500Y1132981D02*
X5548540D01*
G01X5563420Y1128606D02*
Y1134231D01*
X5560320Y1141106D01*
G01X5566520D02*
X5563420Y1134231D01*
G01X5578920Y1128606D02*
X5572720D01*
Y1141106D01*
X5578920D01*
G01X5576440Y1135064D02*
X5572720D01*
G01X5585120Y1128606D02*
Y1141106D01*
X5588995D01*
X5590235Y1140481D01*
X5591010Y1139648D01*
X5591320Y1137981D01*
X5591010Y1136314D01*
X5590080Y1135273D01*
X5588995Y1134648D01*
X5585120D01*
G01X5588995D02*
X5591320Y1128606D01*
G01X5077805Y1151523D02*
X5081835D01*
G01X5100590Y1147356D02*
Y1159856D01*
X5104620Y1149439D01*
X5108650Y1159856D01*
Y1147356D01*
G01X5113145D02*
X5117020Y1159856D01*
X5120895Y1147356D01*
G01X5119500Y1151731D02*
X5114540D01*
G01X5126165Y1147356D02*
X5132675Y1159856D01*
G01X5126165D02*
X5132675Y1147356D01*
G01X5137170Y1143189D02*
X5146470D01*
G01X5150810Y1147356D02*
Y1159856D01*
X5153910D01*
X5155150Y1159231D01*
X5156080Y1158398D01*
X5156855Y1157148D01*
X5157475Y1155689D01*
X5157630Y1153606D01*
X5157475Y1151523D01*
X5156855Y1150064D01*
X5156080Y1148814D01*
X5155150Y1147981D01*
X5153910Y1147356D01*
X5150810D01*
G01X5169720D02*
X5163520D01*
Y1159856D01*
X5169720D01*
G01X5167240Y1153814D02*
X5163520D01*
G01X5175920Y1147356D02*
Y1159856D01*
X5179640D01*
X5180880Y1159231D01*
X5181810Y1157773D01*
X5182120Y1156106D01*
X5181810Y1154439D01*
X5181035Y1153189D01*
X5179640Y1152564D01*
X5175920D01*
G01X5191420Y1159856D02*
Y1147356D01*
G01X5187855Y1159856D02*
X5194985D01*
G01X5200565Y1147356D02*
Y1159856D01*
G01X5207075D02*
Y1147356D01*
G01Y1153606D02*
X5200565D01*
G01X5216220Y1146939D02*
X5215910Y1147148D01*
Y1147564D01*
X5216220Y1147773D01*
X5216530Y1147564D01*
Y1147148D01*
X5216220Y1146939D01*
G01Y1152564D02*
X5215910Y1152773D01*
Y1153189D01*
X5216220Y1153398D01*
X5216530Y1153189D01*
Y1152773D01*
X5216220Y1152564D01*
G01X5237610Y1147356D02*
Y1159856D01*
X5240710D01*
X5241950Y1159231D01*
X5242880Y1158398D01*
X5243655Y1157148D01*
X5244275Y1155689D01*
X5244430Y1153606D01*
X5244275Y1151523D01*
X5243655Y1150064D01*
X5242880Y1148814D01*
X5241950Y1147981D01*
X5240710Y1147356D01*
X5237610D01*
G01X5256520D02*
X5250320D01*
Y1159856D01*
X5256520D01*
G01X5254040Y1153814D02*
X5250320D01*
G01X5262720Y1147356D02*
Y1159856D01*
X5266440D01*
X5267680Y1159231D01*
X5268610Y1157773D01*
X5268920Y1156106D01*
X5268610Y1154439D01*
X5267835Y1153189D01*
X5266440Y1152564D01*
X5262720D01*
G01X5278220Y1159856D02*
Y1147356D01*
G01X5274655Y1159856D02*
X5281785D01*
G01X5287365Y1147356D02*
Y1159856D01*
G01X5293875D02*
Y1147356D01*
G01Y1153606D02*
X5287365D01*
G01X5312475Y1147356D02*
Y1159856D01*
X5318365D01*
G01X5316195Y1153814D02*
X5312475D01*
G01X5324720Y1147356D02*
Y1159856D01*
X5328595D01*
X5329835Y1159231D01*
X5330610Y1158398D01*
X5330920Y1156731D01*
X5330610Y1155064D01*
X5329680Y1154023D01*
X5328595Y1153398D01*
X5324720D01*
G01X5328595D02*
X5330920Y1147356D01*
G01X5340220D02*
X5338980Y1147564D01*
X5337895Y1148397D01*
X5336965Y1149648D01*
X5336345Y1151106D01*
X5336035Y1152773D01*
Y1154439D01*
X5336345Y1156106D01*
X5336965Y1157564D01*
X5337895Y1158814D01*
X5338980Y1159648D01*
X5340220Y1159856D01*
X5341460Y1159648D01*
X5342545Y1158814D01*
X5343475Y1157564D01*
X5344095Y1156106D01*
X5344405Y1154439D01*
Y1152773D01*
X5344095Y1151106D01*
X5343475Y1149648D01*
X5342545Y1148397D01*
X5341460Y1147564D01*
X5340220Y1147356D01*
G01X5348590D02*
Y1159856D01*
X5352620Y1149439D01*
X5356650Y1159856D01*
Y1147356D01*
G01X5374165Y1149022D02*
X5375405Y1147981D01*
X5376800Y1147356D01*
X5378040D01*
X5379280Y1147981D01*
X5380210Y1149022D01*
X5380675Y1150481D01*
X5380365Y1151939D01*
X5379590Y1153189D01*
X5378195Y1154023D01*
X5376335Y1154439D01*
X5375250Y1155273D01*
X5374785Y1156731D01*
X5375095Y1158189D01*
X5375870Y1159231D01*
X5376955Y1159856D01*
X5378040D01*
X5379125Y1159439D01*
X5380055Y1158398D01*
G01X5389820Y1159856D02*
Y1147356D01*
G01X5386255Y1159856D02*
X5393385D01*
G01X5398345Y1147356D02*
X5402220Y1159856D01*
X5406095Y1147356D01*
G01X5404700Y1151731D02*
X5399740D01*
G01X5411520Y1147356D02*
Y1159856D01*
X5415395D01*
X5416635Y1159231D01*
X5417410Y1158398D01*
X5417720Y1156731D01*
X5417410Y1155064D01*
X5416480Y1154023D01*
X5415395Y1153398D01*
X5411520D01*
G01X5415395D02*
X5417720Y1147356D01*
G01X5427020Y1159856D02*
Y1147356D01*
G01X5423455Y1159856D02*
X5430585D01*
G01X5448720D02*
Y1147356D01*
X5454920D01*
G01X5460345D02*
X5464220Y1159856D01*
X5468095Y1147356D01*
G01X5466700Y1151731D02*
X5461740D01*
G01X5476620Y1147356D02*
Y1152981D01*
X5473520Y1159856D01*
G01X5479720D02*
X5476620Y1152981D01*
G01X5492120Y1147356D02*
X5485920D01*
Y1159856D01*
X5492120D01*
G01X5489640Y1153814D02*
X5485920D01*
G01X5498320Y1147356D02*
Y1159856D01*
X5502195D01*
X5503435Y1159231D01*
X5504210Y1158398D01*
X5504520Y1156731D01*
X5504210Y1155064D01*
X5503280Y1154023D01*
X5502195Y1153398D01*
X5498320D01*
G01X5502195D02*
X5504520Y1147356D01*
G01X5526220Y1159856D02*
Y1147356D01*
G01X5522655Y1159856D02*
X5529785D01*
G01X5538620Y1147356D02*
X5537380Y1147564D01*
X5536295Y1148397D01*
X5535365Y1149648D01*
X5534745Y1151106D01*
X5534435Y1152773D01*
Y1154439D01*
X5534745Y1156106D01*
X5535365Y1157564D01*
X5536295Y1158814D01*
X5537380Y1159648D01*
X5538620Y1159856D01*
X5539860Y1159648D01*
X5540945Y1158814D01*
X5541875Y1157564D01*
X5542495Y1156106D01*
X5542805Y1154439D01*
Y1152773D01*
X5542495Y1151106D01*
X5541875Y1149648D01*
X5540945Y1148397D01*
X5539860Y1147564D01*
X5538620Y1147356D01*
G01X5563420Y1159856D02*
Y1147356D01*
G01X5559855Y1159856D02*
X5566985D01*
G01X5572565Y1147356D02*
Y1159856D01*
G01X5579075D02*
Y1147356D01*
G01Y1153606D02*
X5572565D01*
G01X5591320Y1147356D02*
X5585120D01*
Y1159856D01*
X5591320D01*
G01X5588840Y1153814D02*
X5585120D01*
G01X5077805Y1170273D02*
X5081835D01*
G01X5100590Y1166106D02*
Y1178606D01*
X5104620Y1168189D01*
X5108650Y1178606D01*
Y1166106D01*
G01X5113455D02*
Y1178606D01*
X5120585Y1166106D01*
Y1178606D01*
G01X5132830Y1177564D02*
X5131900Y1178189D01*
X5130815Y1178606D01*
X5129575D01*
X5128180Y1177981D01*
X5127095Y1176939D01*
X5126320Y1175689D01*
X5125700Y1173606D01*
X5125545Y1171731D01*
X5125855Y1169856D01*
X5126320Y1168606D01*
X5127250Y1167356D01*
X5128335Y1166523D01*
X5129420Y1166106D01*
X5130505D01*
X5131590Y1166523D01*
X5132520Y1167147D01*
X5133295Y1167981D01*
G01X5137170Y1161939D02*
X5146470D01*
G01X5151120Y1178606D02*
Y1166106D01*
X5157320D01*
G01X5162745D02*
X5166620Y1178606D01*
X5170495Y1166106D01*
G01X5169100Y1170481D02*
X5164140D01*
G01X5179020Y1166106D02*
Y1171731D01*
X5175920Y1178606D01*
G01X5182120D02*
X5179020Y1171731D01*
G01X5194520Y1166106D02*
X5188320D01*
Y1178606D01*
X5194520D01*
G01X5192040Y1172564D02*
X5188320D01*
G01X5200720Y1166106D02*
Y1178606D01*
X5204595D01*
X5205835Y1177981D01*
X5206610Y1177148D01*
X5206920Y1175481D01*
X5206610Y1173814D01*
X5205680Y1172773D01*
X5204595Y1172148D01*
X5200720D01*
G01X5204595D02*
X5206920Y1166106D01*
G01X5216220Y1165689D02*
X5215910Y1165898D01*
Y1166314D01*
X5216220Y1166523D01*
X5216530Y1166314D01*
Y1165898D01*
X5216220Y1165689D01*
G01Y1171314D02*
X5215910Y1171523D01*
Y1171939D01*
X5216220Y1172148D01*
X5216530Y1171939D01*
Y1171523D01*
X5216220Y1171314D01*
G01X5236990Y1166106D02*
Y1178606D01*
X5241020Y1168189D01*
X5245050Y1178606D01*
Y1166106D01*
G01X5250010Y1178606D02*
Y1169648D01*
X5250630Y1167772D01*
X5251870Y1166523D01*
X5253420Y1166106D01*
X5254970Y1166523D01*
X5256210Y1167772D01*
X5256830Y1169648D01*
Y1178606D01*
G01X5262565Y1167772D02*
X5263805Y1166731D01*
X5265200Y1166106D01*
X5266440D01*
X5267680Y1166731D01*
X5268610Y1167772D01*
X5269075Y1169231D01*
X5268765Y1170689D01*
X5267990Y1171939D01*
X5266595Y1172773D01*
X5264735Y1173189D01*
X5263650Y1174023D01*
X5263185Y1175481D01*
X5263495Y1176939D01*
X5264270Y1177981D01*
X5265355Y1178606D01*
X5266440D01*
X5267525Y1178189D01*
X5268455Y1177148D01*
G01X5278220Y1178606D02*
Y1166106D01*
G01X5274655Y1178606D02*
X5281785D01*
G01X5288605Y1170273D02*
X5292635D01*
G01X5299455Y1166106D02*
Y1178606D01*
X5306585Y1166106D01*
Y1178606D01*
G01X5315420Y1166106D02*
X5314180Y1166314D01*
X5313095Y1167147D01*
X5312165Y1168398D01*
X5311545Y1169856D01*
X5311235Y1171523D01*
Y1173189D01*
X5311545Y1174856D01*
X5312165Y1176314D01*
X5313095Y1177564D01*
X5314180Y1178398D01*
X5315420Y1178606D01*
X5316660Y1178398D01*
X5317745Y1177564D01*
X5318675Y1176314D01*
X5319295Y1174856D01*
X5319605Y1173189D01*
Y1171523D01*
X5319295Y1169856D01*
X5318675Y1168398D01*
X5317745Y1167147D01*
X5316660Y1166314D01*
X5315420Y1166106D01*
G01X5327820Y1178606D02*
Y1166106D01*
G01X5324255Y1178606D02*
X5331385D01*
G01X5338205Y1170273D02*
X5342235D01*
G01X5356030Y1177564D02*
X5355100Y1178189D01*
X5354015Y1178606D01*
X5352775D01*
X5351380Y1177981D01*
X5350295Y1176939D01*
X5349520Y1175689D01*
X5348900Y1173606D01*
X5348745Y1171731D01*
X5349055Y1169856D01*
X5349520Y1168606D01*
X5350450Y1167356D01*
X5351535Y1166523D01*
X5352620Y1166106D01*
X5353705D01*
X5354790Y1166523D01*
X5355720Y1167147D01*
X5356495Y1167981D01*
G01X5361610Y1178606D02*
Y1169648D01*
X5362230Y1167772D01*
X5363470Y1166523D01*
X5365020Y1166106D01*
X5366570Y1166523D01*
X5367810Y1167772D01*
X5368430Y1169648D01*
Y1178606D01*
G01X5377420D02*
Y1166106D01*
G01X5373855Y1178606D02*
X5380985D01*
G01X5387805Y1170273D02*
X5391835D01*
G01X5399120Y1178606D02*
Y1166106D01*
X5405320D01*
G01X5410745D02*
X5414620Y1178606D01*
X5418495Y1166106D01*
G01X5417100Y1170481D02*
X5412140D01*
G01X5427020Y1166106D02*
Y1171731D01*
X5423920Y1178606D01*
G01X5430120D02*
X5427020Y1171731D01*
G01X5442520Y1166106D02*
X5436320D01*
Y1178606D01*
X5442520D01*
G01X5440040Y1172564D02*
X5436320D01*
G01X5448720Y1166106D02*
Y1178606D01*
X5452595D01*
X5453835Y1177981D01*
X5454610Y1177148D01*
X5454920Y1175481D01*
X5454610Y1173814D01*
X5453680Y1172773D01*
X5452595Y1172148D01*
X5448720D01*
G01X5452595D02*
X5454920Y1166106D01*
G01X5076255Y1184856D02*
Y1197356D01*
X5083385Y1184856D01*
Y1197356D01*
G01X5092220Y1184856D02*
X5090980Y1185064D01*
X5089895Y1185897D01*
X5088965Y1187148D01*
X5088345Y1188606D01*
X5088035Y1190273D01*
Y1191939D01*
X5088345Y1193606D01*
X5088965Y1195064D01*
X5089895Y1196314D01*
X5090980Y1197148D01*
X5092220Y1197356D01*
X5093460Y1197148D01*
X5094545Y1196314D01*
X5095475Y1195064D01*
X5096095Y1193606D01*
X5096405Y1191939D01*
Y1190273D01*
X5096095Y1188606D01*
X5095475Y1187148D01*
X5094545Y1185897D01*
X5093460Y1185064D01*
X5092220Y1184856D01*
G01X5104620Y1197356D02*
Y1184856D01*
G01X5101055Y1197356D02*
X5108185D01*
G01X5120120Y1184856D02*
X5113920D01*
Y1197356D01*
X5120120D01*
G01X5117640Y1191314D02*
X5113920D01*
G01X5126165Y1186522D02*
X5127405Y1185481D01*
X5128800Y1184856D01*
X5130040D01*
X5131280Y1185481D01*
X5132210Y1186522D01*
X5132675Y1187981D01*
X5132365Y1189439D01*
X5131590Y1190689D01*
X5130195Y1191523D01*
X5128335Y1191939D01*
X5127250Y1192773D01*
X5126785Y1194231D01*
X5127095Y1195689D01*
X5127870Y1196731D01*
X5128955Y1197356D01*
X5130040D01*
X5131125Y1196939D01*
X5132055Y1195898D01*
G01X5141820Y1184439D02*
X5141510Y1184648D01*
Y1185064D01*
X5141820Y1185273D01*
X5142130Y1185064D01*
Y1184648D01*
X5141820Y1184439D01*
G01Y1190064D02*
X5141510Y1190273D01*
Y1190689D01*
X5141820Y1190898D01*
X5142130Y1190689D01*
Y1190273D01*
X5141820Y1190064D01*
G01X5242260Y1413273D02*
X5242880Y1413898D01*
X5243345Y1414939D01*
X5243655Y1416398D01*
X5243345Y1417648D01*
X5242725Y1418481D01*
X5241640Y1419106D01*
X5237455D01*
Y1406606D01*
X5242570D01*
X5243655Y1407439D01*
X5244275Y1408689D01*
X5244585Y1410148D01*
X5244275Y1411606D01*
X5243345Y1412856D01*
X5242260Y1413273D01*
X5237455D01*
G01X5249545Y1406606D02*
X5253420Y1419106D01*
X5257295Y1406606D01*
G01X5255900Y1410981D02*
X5250940D01*
G01X5269230Y1418064D02*
X5268300Y1418689D01*
X5267215Y1419106D01*
X5265975D01*
X5264580Y1418481D01*
X5263495Y1417439D01*
X5262720Y1416189D01*
X5262100Y1414106D01*
X5261945Y1412231D01*
X5262255Y1410356D01*
X5262720Y1409106D01*
X5263650Y1407856D01*
X5264735Y1407023D01*
X5265820Y1406606D01*
X5266905D01*
X5267990Y1407023D01*
X5268920Y1407647D01*
X5269695Y1408481D01*
G01X5274810Y1406606D02*
Y1419106D01*
G01X5280700D02*
X5274810Y1411397D01*
G01X5281630Y1406606D02*
X5277445Y1414939D01*
G01X5287210Y1406606D02*
Y1419106D01*
X5290310D01*
X5291550Y1418481D01*
X5292480Y1417648D01*
X5293255Y1416398D01*
X5293875Y1414939D01*
X5294030Y1412856D01*
X5293875Y1410773D01*
X5293255Y1409314D01*
X5292480Y1408064D01*
X5291550Y1407231D01*
X5290310Y1406606D01*
X5287210D01*
G01X5299920D02*
Y1419106D01*
X5303795D01*
X5305035Y1418481D01*
X5305810Y1417648D01*
X5306120Y1415981D01*
X5305810Y1414314D01*
X5304880Y1413273D01*
X5303795Y1412648D01*
X5299920D01*
G01X5303795D02*
X5306120Y1406606D01*
G01X5313560Y1419106D02*
X5317280D01*
G01X5315420D02*
Y1406606D01*
G01X5313560D02*
X5317280D01*
G01X5324720Y1419106D02*
Y1406606D01*
X5330920D01*
G01X5337120Y1419106D02*
Y1406606D01*
X5343320D01*
G01X5361765Y1408272D02*
X5363005Y1407231D01*
X5364400Y1406606D01*
X5365640D01*
X5366880Y1407231D01*
X5367810Y1408272D01*
X5368275Y1409731D01*
X5367965Y1411189D01*
X5367190Y1412439D01*
X5365795Y1413273D01*
X5363935Y1413689D01*
X5362850Y1414523D01*
X5362385Y1415981D01*
X5362695Y1417439D01*
X5363470Y1418481D01*
X5364555Y1419106D01*
X5365640D01*
X5366725Y1418689D01*
X5367655Y1417648D01*
G01X5377420Y1419106D02*
Y1406606D01*
G01X5373855Y1419106D02*
X5380985D01*
G01X5386410D02*
Y1410148D01*
X5387030Y1408272D01*
X5388270Y1407023D01*
X5389820Y1406606D01*
X5391370Y1407023D01*
X5392610Y1408272D01*
X5393230Y1410148D01*
Y1419106D01*
G01X5403460Y1413273D02*
X5404080Y1413898D01*
X5404545Y1414939D01*
X5404855Y1416398D01*
X5404545Y1417648D01*
X5403925Y1418481D01*
X5402840Y1419106D01*
X5398655D01*
Y1406606D01*
X5403770D01*
X5404855Y1407439D01*
X5405475Y1408689D01*
X5405785Y1410148D01*
X5405475Y1411606D01*
X5404545Y1412856D01*
X5403460Y1413273D01*
X5398655D01*
G01X5423920Y1419106D02*
Y1406606D01*
X5430120D01*
G01X5442520D02*
X5436320D01*
Y1419106D01*
X5442520D01*
G01X5440040Y1413064D02*
X5436320D01*
G01X5448255Y1406606D02*
Y1419106D01*
X5455385Y1406606D01*
Y1419106D01*
G01X5465150Y1412856D02*
X5468250D01*
Y1409106D01*
X5467320Y1407856D01*
X5466235Y1407023D01*
X5464685Y1406606D01*
X5463135Y1407023D01*
X5462050Y1407856D01*
X5461120Y1409106D01*
X5460500Y1410564D01*
X5460190Y1412231D01*
Y1413689D01*
X5460500Y1414939D01*
X5461120Y1416398D01*
X5462050Y1417648D01*
X5462980Y1418481D01*
X5464220Y1419106D01*
X5465305D01*
X5466545Y1418689D01*
X5467475Y1417856D01*
G01X5476620Y1419106D02*
Y1406606D01*
G01X5473055Y1419106D02*
X5480185D01*
G01X5485765Y1406606D02*
Y1419106D01*
G01X5492275D02*
Y1406606D01*
G01Y1412856D02*
X5485765D01*
G01X5513820Y1419106D02*
Y1406606D01*
G01X5510255Y1419106D02*
X5517385D01*
G01X5526220Y1406606D02*
X5524980Y1406814D01*
X5523895Y1407647D01*
X5522965Y1408898D01*
X5522345Y1410356D01*
X5522035Y1412023D01*
Y1413689D01*
X5522345Y1415356D01*
X5522965Y1416814D01*
X5523895Y1418064D01*
X5524980Y1418898D01*
X5526220Y1419106D01*
X5527460Y1418898D01*
X5528545Y1418064D01*
X5529475Y1416814D01*
X5530095Y1415356D01*
X5530405Y1413689D01*
Y1412023D01*
X5530095Y1410356D01*
X5529475Y1408898D01*
X5528545Y1407647D01*
X5527460Y1406814D01*
X5526220Y1406606D01*
G01X5535520Y1419106D02*
Y1406606D01*
X5541720D01*
G01X5554120D02*
X5547920D01*
Y1419106D01*
X5554120D01*
G01X5551640Y1413064D02*
X5547920D01*
G01X5560320Y1406606D02*
Y1419106D01*
X5564195D01*
X5565435Y1418481D01*
X5566210Y1417648D01*
X5566520Y1415981D01*
X5566210Y1414314D01*
X5565280Y1413273D01*
X5564195Y1412648D01*
X5560320D01*
G01X5564195D02*
X5566520Y1406606D01*
G01X5571945D02*
X5575820Y1419106D01*
X5579695Y1406606D01*
G01X5578300Y1410981D02*
X5573340D01*
G01X5584655Y1406606D02*
Y1419106D01*
X5591785Y1406606D01*
Y1419106D01*
G01X5604030Y1418064D02*
X5603100Y1418689D01*
X5602015Y1419106D01*
X5600775D01*
X5599380Y1418481D01*
X5598295Y1417439D01*
X5597520Y1416189D01*
X5596900Y1414106D01*
X5596745Y1412231D01*
X5597055Y1410356D01*
X5597520Y1409106D01*
X5598450Y1407856D01*
X5599535Y1407023D01*
X5600620Y1406606D01*
X5601705D01*
X5602790Y1407023D01*
X5603720Y1407647D01*
X5604495Y1408481D01*
G01X5616120Y1406606D02*
X5609920D01*
Y1419106D01*
X5616120D01*
G01X5613640Y1413064D02*
X5609920D01*
G01X5637820Y1419106D02*
Y1406606D01*
G01X5634255Y1419106D02*
X5641385D01*
G01X5650220Y1406606D02*
X5648980Y1406814D01*
X5647895Y1407647D01*
X5646965Y1408898D01*
X5646345Y1410356D01*
X5646035Y1412023D01*
Y1413689D01*
X5646345Y1415356D01*
X5646965Y1416814D01*
X5647895Y1418064D01*
X5648980Y1418898D01*
X5650220Y1419106D01*
X5651460Y1418898D01*
X5652545Y1418064D01*
X5653475Y1416814D01*
X5654095Y1415356D01*
X5654405Y1413689D01*
Y1412023D01*
X5654095Y1410356D01*
X5653475Y1408898D01*
X5652545Y1407647D01*
X5651460Y1406814D01*
X5650220Y1406606D01*
G01X5676260Y1413273D02*
X5676880Y1413898D01*
X5677345Y1414939D01*
X5677655Y1416398D01*
X5677345Y1417648D01*
X5676725Y1418481D01*
X5675640Y1419106D01*
X5671455D01*
Y1406606D01*
X5676570D01*
X5677655Y1407439D01*
X5678275Y1408689D01*
X5678585Y1410148D01*
X5678275Y1411606D01*
X5677345Y1412856D01*
X5676260Y1413273D01*
X5671455D01*
G01X5690520Y1406606D02*
X5684320D01*
Y1419106D01*
X5690520D01*
G01X5688040Y1413064D02*
X5684320D01*
G01X5711910Y1406606D02*
X5712220Y1409314D01*
X5712685Y1411606D01*
X5713305Y1413689D01*
X5714080Y1415981D01*
X5715320Y1419106D01*
X5709120D01*
G01X5735315Y1410773D02*
X5739035D01*
G01X5737020Y1413481D02*
Y1408064D01*
G01X5746630Y1406189D02*
X5752210Y1419106D01*
G01X5759805Y1410773D02*
X5763835D01*
G01X5770810Y1408481D02*
X5771740Y1407439D01*
X5772825Y1406814D01*
X5774220Y1406606D01*
X5775615Y1407023D01*
X5776700Y1407856D01*
X5777475Y1409314D01*
X5777630Y1410981D01*
X5777320Y1412648D01*
X5776545Y1413689D01*
X5775460Y1414523D01*
X5774375Y1414731D01*
X5773290Y1414523D01*
X5771895Y1413689D01*
X5772360Y1419106D01*
X5776545D01*
G01X5794990Y1406606D02*
Y1419106D01*
X5799020Y1408689D01*
X5803050Y1419106D01*
Y1406606D01*
G01X5809560Y1419106D02*
X5813280D01*
G01X5811420D02*
Y1406606D01*
G01X5809560D02*
X5813280D01*
G01X5820720Y1419106D02*
Y1406606D01*
X5826920D01*
G01X5832965Y1408272D02*
X5834205Y1407231D01*
X5835600Y1406606D01*
X5836840D01*
X5838080Y1407231D01*
X5839010Y1408272D01*
X5839475Y1409731D01*
X5839165Y1411189D01*
X5838390Y1412439D01*
X5836995Y1413273D01*
X5835135Y1413689D01*
X5834050Y1414523D01*
X5833585Y1415981D01*
X5833895Y1417439D01*
X5834670Y1418481D01*
X5835755Y1419106D01*
X5836840D01*
X5837925Y1418689D01*
X5838855Y1417648D01*
G01X5077805Y1429523D02*
X5081835D01*
G01X5100590Y1425356D02*
Y1437856D01*
X5104620Y1427439D01*
X5108650Y1437856D01*
Y1425356D01*
G01X5114075D02*
Y1437856D01*
X5119965D01*
G01X5117795Y1431814D02*
X5114075D01*
G01X5130350Y1431606D02*
X5133450D01*
Y1427856D01*
X5132520Y1426606D01*
X5131435Y1425773D01*
X5129885Y1425356D01*
X5128335Y1425773D01*
X5127250Y1426606D01*
X5126320Y1427856D01*
X5125700Y1429314D01*
X5125390Y1430981D01*
Y1432439D01*
X5125700Y1433689D01*
X5126320Y1435148D01*
X5127250Y1436398D01*
X5128180Y1437231D01*
X5129420Y1437856D01*
X5130505D01*
X5131745Y1437439D01*
X5132675Y1436606D01*
G01X5137170Y1421189D02*
X5146470D01*
G01X5150965Y1427022D02*
X5152205Y1425981D01*
X5153600Y1425356D01*
X5154840D01*
X5156080Y1425981D01*
X5157010Y1427022D01*
X5157475Y1428481D01*
X5157165Y1429939D01*
X5156390Y1431189D01*
X5154995Y1432023D01*
X5153135Y1432439D01*
X5152050Y1433273D01*
X5151585Y1434731D01*
X5151895Y1436189D01*
X5152670Y1437231D01*
X5153755Y1437856D01*
X5154840D01*
X5155925Y1437439D01*
X5156855Y1436398D01*
G01X5166620Y1437856D02*
Y1425356D01*
G01X5163055Y1437856D02*
X5170185D01*
G01X5175610D02*
Y1428898D01*
X5176230Y1427022D01*
X5177470Y1425773D01*
X5179020Y1425356D01*
X5180570Y1425773D01*
X5181810Y1427022D01*
X5182430Y1428898D01*
Y1437856D01*
G01X5192660Y1432023D02*
X5193280Y1432648D01*
X5193745Y1433689D01*
X5194055Y1435148D01*
X5193745Y1436398D01*
X5193125Y1437231D01*
X5192040Y1437856D01*
X5187855D01*
Y1425356D01*
X5192970D01*
X5194055Y1426189D01*
X5194675Y1427439D01*
X5194985Y1428898D01*
X5194675Y1430356D01*
X5193745Y1431606D01*
X5192660Y1432023D01*
X5187855D01*
G01X5216220Y1424939D02*
X5215910Y1425148D01*
Y1425564D01*
X5216220Y1425773D01*
X5216530Y1425564D01*
Y1425148D01*
X5216220Y1424939D01*
G01Y1430564D02*
X5215910Y1430773D01*
Y1431189D01*
X5216220Y1431398D01*
X5216530Y1431189D01*
Y1430773D01*
X5216220Y1430564D01*
G01X5236990Y1425356D02*
Y1437856D01*
X5241020Y1427439D01*
X5245050Y1437856D01*
Y1425356D01*
G01X5249545D02*
X5253420Y1437856D01*
X5257295Y1425356D01*
G01X5255900Y1429731D02*
X5250940D01*
G01X5262255Y1425356D02*
Y1437856D01*
X5269385Y1425356D01*
Y1437856D01*
G01X5274810D02*
Y1428898D01*
X5275430Y1427022D01*
X5276670Y1425773D01*
X5278220Y1425356D01*
X5279770Y1425773D01*
X5281010Y1427022D01*
X5281630Y1428898D01*
Y1437856D01*
G01X5287675Y1425356D02*
Y1437856D01*
X5293565D01*
G01X5291395Y1431814D02*
X5287675D01*
G01X5299145Y1425356D02*
X5303020Y1437856D01*
X5306895Y1425356D01*
G01X5305500Y1429731D02*
X5300540D01*
G01X5318830Y1436814D02*
X5317900Y1437439D01*
X5316815Y1437856D01*
X5315575D01*
X5314180Y1437231D01*
X5313095Y1436189D01*
X5312320Y1434939D01*
X5311700Y1432856D01*
X5311545Y1430981D01*
X5311855Y1429106D01*
X5312320Y1427856D01*
X5313250Y1426606D01*
X5314335Y1425773D01*
X5315420Y1425356D01*
X5316505D01*
X5317590Y1425773D01*
X5318520Y1426397D01*
X5319295Y1427231D01*
G01X5327820Y1437856D02*
Y1425356D01*
G01X5324255Y1437856D02*
X5331385D01*
G01X5336810D02*
Y1428898D01*
X5337430Y1427022D01*
X5338670Y1425773D01*
X5340220Y1425356D01*
X5341770Y1425773D01*
X5343010Y1427022D01*
X5343630Y1428898D01*
Y1437856D01*
G01X5349520Y1425356D02*
Y1437856D01*
X5353395D01*
X5354635Y1437231D01*
X5355410Y1436398D01*
X5355720Y1434731D01*
X5355410Y1433064D01*
X5354480Y1432023D01*
X5353395Y1431398D01*
X5349520D01*
G01X5353395D02*
X5355720Y1425356D01*
G01X5363160Y1437856D02*
X5366880D01*
G01X5365020D02*
Y1425356D01*
G01X5363160D02*
X5366880D01*
G01X5373855D02*
Y1437856D01*
X5380985Y1425356D01*
Y1437856D01*
G01X5390750Y1431606D02*
X5393850D01*
Y1427856D01*
X5392920Y1426606D01*
X5391835Y1425773D01*
X5390285Y1425356D01*
X5388735Y1425773D01*
X5387650Y1426606D01*
X5386720Y1427856D01*
X5386100Y1429314D01*
X5385790Y1430981D01*
Y1432439D01*
X5386100Y1433689D01*
X5386720Y1435148D01*
X5387650Y1436398D01*
X5388580Y1437231D01*
X5389820Y1437856D01*
X5390905D01*
X5392145Y1437439D01*
X5393075Y1436606D01*
G01X5411365Y1427022D02*
X5412605Y1425981D01*
X5414000Y1425356D01*
X5415240D01*
X5416480Y1425981D01*
X5417410Y1427022D01*
X5417875Y1428481D01*
X5417565Y1429939D01*
X5416790Y1431189D01*
X5415395Y1432023D01*
X5413535Y1432439D01*
X5412450Y1433273D01*
X5411985Y1434731D01*
X5412295Y1436189D01*
X5413070Y1437231D01*
X5414155Y1437856D01*
X5415240D01*
X5416325Y1437439D01*
X5417255Y1436398D01*
G01X5427020Y1437856D02*
Y1425356D01*
G01X5423455Y1437856D02*
X5430585D01*
G01X5436010D02*
Y1428898D01*
X5436630Y1427022D01*
X5437870Y1425773D01*
X5439420Y1425356D01*
X5440970Y1425773D01*
X5442210Y1427022D01*
X5442830Y1428898D01*
Y1437856D01*
G01X5453060Y1432023D02*
X5453680Y1432648D01*
X5454145Y1433689D01*
X5454455Y1435148D01*
X5454145Y1436398D01*
X5453525Y1437231D01*
X5452440Y1437856D01*
X5448255D01*
Y1425356D01*
X5453370D01*
X5454455Y1426189D01*
X5455075Y1427439D01*
X5455385Y1428898D01*
X5455075Y1430356D01*
X5454145Y1431606D01*
X5453060Y1432023D01*
X5448255D01*
G01X5473520Y1437856D02*
Y1425356D01*
X5479720D01*
G01X5492120D02*
X5485920D01*
Y1437856D01*
X5492120D01*
G01X5489640Y1431814D02*
X5485920D01*
G01X5497855Y1425356D02*
Y1437856D01*
X5504985Y1425356D01*
Y1437856D01*
G01X5514750Y1431606D02*
X5517850D01*
Y1427856D01*
X5516920Y1426606D01*
X5515835Y1425773D01*
X5514285Y1425356D01*
X5512735Y1425773D01*
X5511650Y1426606D01*
X5510720Y1427856D01*
X5510100Y1429314D01*
X5509790Y1430981D01*
Y1432439D01*
X5510100Y1433689D01*
X5510720Y1435148D01*
X5511650Y1436398D01*
X5512580Y1437231D01*
X5513820Y1437856D01*
X5514905D01*
X5516145Y1437439D01*
X5517075Y1436606D01*
G01X5526220Y1437856D02*
Y1425356D01*
G01X5522655Y1437856D02*
X5529785D01*
G01X5535365Y1425356D02*
Y1437856D01*
G01X5541875D02*
Y1425356D01*
G01Y1431606D02*
X5535365D01*
G01X5237765Y1445772D02*
X5239005Y1444731D01*
X5240400Y1444106D01*
X5241640D01*
X5242880Y1444731D01*
X5243810Y1445772D01*
X5244275Y1447231D01*
X5243965Y1448689D01*
X5243190Y1449939D01*
X5241795Y1450773D01*
X5239935Y1451189D01*
X5238850Y1452023D01*
X5238385Y1453481D01*
X5238695Y1454939D01*
X5239470Y1455981D01*
X5240555Y1456606D01*
X5241640D01*
X5242725Y1456189D01*
X5243655Y1455148D01*
G01X5250010Y1456606D02*
Y1447648D01*
X5250630Y1445772D01*
X5251870Y1444523D01*
X5253420Y1444106D01*
X5254970Y1444523D01*
X5256210Y1445772D01*
X5256830Y1447648D01*
Y1456606D01*
G01X5262720Y1444106D02*
Y1456606D01*
X5266595D01*
X5267835Y1455981D01*
X5268610Y1455148D01*
X5268920Y1453481D01*
X5268610Y1451814D01*
X5267680Y1450773D01*
X5266595Y1450148D01*
X5262720D01*
G01X5266595D02*
X5268920Y1444106D01*
G01X5275275D02*
Y1456606D01*
X5281165D01*
G01X5278995Y1450564D02*
X5275275D01*
G01X5286745Y1444106D02*
X5290620Y1456606D01*
X5294495Y1444106D01*
G01X5293100Y1448481D02*
X5288140D01*
G01X5306430Y1455564D02*
X5305500Y1456189D01*
X5304415Y1456606D01*
X5303175D01*
X5301780Y1455981D01*
X5300695Y1454939D01*
X5299920Y1453689D01*
X5299300Y1451606D01*
X5299145Y1449731D01*
X5299455Y1447856D01*
X5299920Y1446606D01*
X5300850Y1445356D01*
X5301935Y1444523D01*
X5303020Y1444106D01*
X5304105D01*
X5305190Y1444523D01*
X5306120Y1445147D01*
X5306895Y1445981D01*
G01X5318520Y1444106D02*
X5312320D01*
Y1456606D01*
X5318520D01*
G01X5316040Y1450564D02*
X5312320D01*
G01X5340220Y1444106D02*
X5338980Y1444314D01*
X5337895Y1445147D01*
X5336965Y1446398D01*
X5336345Y1447856D01*
X5336035Y1449523D01*
Y1451189D01*
X5336345Y1452856D01*
X5336965Y1454314D01*
X5337895Y1455564D01*
X5338980Y1456398D01*
X5340220Y1456606D01*
X5341460Y1456398D01*
X5342545Y1455564D01*
X5343475Y1454314D01*
X5344095Y1452856D01*
X5344405Y1451189D01*
Y1449523D01*
X5344095Y1447856D01*
X5343475Y1446398D01*
X5342545Y1445147D01*
X5341460Y1444314D01*
X5340220Y1444106D01*
G01X5349675D02*
Y1456606D01*
X5355565D01*
G01X5353395Y1450564D02*
X5349675D01*
G01X5373390Y1444106D02*
Y1456606D01*
X5377420Y1446189D01*
X5381450Y1456606D01*
Y1444106D01*
G01X5386410Y1456606D02*
Y1447648D01*
X5387030Y1445772D01*
X5388270Y1444523D01*
X5389820Y1444106D01*
X5391370Y1444523D01*
X5392610Y1445772D01*
X5393230Y1447648D01*
Y1456606D01*
G01X5398965Y1445772D02*
X5400205Y1444731D01*
X5401600Y1444106D01*
X5402840D01*
X5404080Y1444731D01*
X5405010Y1445772D01*
X5405475Y1447231D01*
X5405165Y1448689D01*
X5404390Y1449939D01*
X5402995Y1450773D01*
X5401135Y1451189D01*
X5400050Y1452023D01*
X5399585Y1453481D01*
X5399895Y1454939D01*
X5400670Y1455981D01*
X5401755Y1456606D01*
X5402840D01*
X5403925Y1456189D01*
X5404855Y1455148D01*
G01X5414620Y1456606D02*
Y1444106D01*
G01X5411055Y1456606D02*
X5418185D01*
G01X5425005Y1448273D02*
X5429035D01*
G01X5435855Y1444106D02*
Y1456606D01*
X5442985Y1444106D01*
Y1456606D01*
G01X5451820Y1444106D02*
X5450580Y1444314D01*
X5449495Y1445147D01*
X5448565Y1446398D01*
X5447945Y1447856D01*
X5447635Y1449523D01*
Y1451189D01*
X5447945Y1452856D01*
X5448565Y1454314D01*
X5449495Y1455564D01*
X5450580Y1456398D01*
X5451820Y1456606D01*
X5453060Y1456398D01*
X5454145Y1455564D01*
X5455075Y1454314D01*
X5455695Y1452856D01*
X5456005Y1451189D01*
Y1449523D01*
X5455695Y1447856D01*
X5455075Y1446398D01*
X5454145Y1445147D01*
X5453060Y1444314D01*
X5451820Y1444106D01*
G01X5464220Y1456606D02*
Y1444106D01*
G01X5460655Y1456606D02*
X5467785D01*
G01X5474605Y1448273D02*
X5478635D01*
G01X5492430Y1455564D02*
X5491500Y1456189D01*
X5490415Y1456606D01*
X5489175D01*
X5487780Y1455981D01*
X5486695Y1454939D01*
X5485920Y1453689D01*
X5485300Y1451606D01*
X5485145Y1449731D01*
X5485455Y1447856D01*
X5485920Y1446606D01*
X5486850Y1445356D01*
X5487935Y1444523D01*
X5489020Y1444106D01*
X5490105D01*
X5491190Y1444523D01*
X5492120Y1445147D01*
X5492895Y1445981D01*
G01X5498010Y1456606D02*
Y1447648D01*
X5498630Y1445772D01*
X5499870Y1444523D01*
X5501420Y1444106D01*
X5502970Y1444523D01*
X5504210Y1445772D01*
X5504830Y1447648D01*
Y1456606D01*
G01X5513820D02*
Y1444106D01*
G01X5510255Y1456606D02*
X5517385D01*
G01X5524205Y1448273D02*
X5528235D01*
G01X5535520Y1456606D02*
Y1444106D01*
X5541720D01*
G01X5547145D02*
X5551020Y1456606D01*
X5554895Y1444106D01*
G01X5553500Y1448481D02*
X5548540D01*
G01X5563420Y1444106D02*
Y1449731D01*
X5560320Y1456606D01*
G01X5566520D02*
X5563420Y1449731D01*
G01X5578920Y1444106D02*
X5572720D01*
Y1456606D01*
X5578920D01*
G01X5576440Y1450564D02*
X5572720D01*
G01X5585120Y1444106D02*
Y1456606D01*
X5588995D01*
X5590235Y1455981D01*
X5591010Y1455148D01*
X5591320Y1453481D01*
X5591010Y1451814D01*
X5590080Y1450773D01*
X5588995Y1450148D01*
X5585120D01*
G01X5588995D02*
X5591320Y1444106D01*
G01X5077805Y1467023D02*
X5081835D01*
G01X5100590Y1462856D02*
Y1475356D01*
X5104620Y1464939D01*
X5108650Y1475356D01*
Y1462856D01*
G01X5113145D02*
X5117020Y1475356D01*
X5120895Y1462856D01*
G01X5119500Y1467231D02*
X5114540D01*
G01X5126165Y1462856D02*
X5132675Y1475356D01*
G01X5126165D02*
X5132675Y1462856D01*
G01X5137170Y1458689D02*
X5146470D01*
G01X5150810Y1462856D02*
Y1475356D01*
X5153910D01*
X5155150Y1474731D01*
X5156080Y1473898D01*
X5156855Y1472648D01*
X5157475Y1471189D01*
X5157630Y1469106D01*
X5157475Y1467023D01*
X5156855Y1465564D01*
X5156080Y1464314D01*
X5155150Y1463481D01*
X5153910Y1462856D01*
X5150810D01*
G01X5169720D02*
X5163520D01*
Y1475356D01*
X5169720D01*
G01X5167240Y1469314D02*
X5163520D01*
G01X5175920Y1462856D02*
Y1475356D01*
X5179640D01*
X5180880Y1474731D01*
X5181810Y1473273D01*
X5182120Y1471606D01*
X5181810Y1469939D01*
X5181035Y1468689D01*
X5179640Y1468064D01*
X5175920D01*
G01X5191420Y1475356D02*
Y1462856D01*
G01X5187855Y1475356D02*
X5194985D01*
G01X5200565Y1462856D02*
Y1475356D01*
G01X5207075D02*
Y1462856D01*
G01Y1469106D02*
X5200565D01*
G01X5216220Y1462439D02*
X5215910Y1462648D01*
Y1463064D01*
X5216220Y1463273D01*
X5216530Y1463064D01*
Y1462648D01*
X5216220Y1462439D01*
G01Y1468064D02*
X5215910Y1468273D01*
Y1468689D01*
X5216220Y1468898D01*
X5216530Y1468689D01*
Y1468273D01*
X5216220Y1468064D01*
G01X5237610Y1462856D02*
Y1475356D01*
X5240710D01*
X5241950Y1474731D01*
X5242880Y1473898D01*
X5243655Y1472648D01*
X5244275Y1471189D01*
X5244430Y1469106D01*
X5244275Y1467023D01*
X5243655Y1465564D01*
X5242880Y1464314D01*
X5241950Y1463481D01*
X5240710Y1462856D01*
X5237610D01*
G01X5256520D02*
X5250320D01*
Y1475356D01*
X5256520D01*
G01X5254040Y1469314D02*
X5250320D01*
G01X5262720Y1462856D02*
Y1475356D01*
X5266440D01*
X5267680Y1474731D01*
X5268610Y1473273D01*
X5268920Y1471606D01*
X5268610Y1469939D01*
X5267835Y1468689D01*
X5266440Y1468064D01*
X5262720D01*
G01X5278220Y1475356D02*
Y1462856D01*
G01X5274655Y1475356D02*
X5281785D01*
G01X5287365Y1462856D02*
Y1475356D01*
G01X5293875D02*
Y1462856D01*
G01Y1469106D02*
X5287365D01*
G01X5312475Y1462856D02*
Y1475356D01*
X5318365D01*
G01X5316195Y1469314D02*
X5312475D01*
G01X5324720Y1462856D02*
Y1475356D01*
X5328595D01*
X5329835Y1474731D01*
X5330610Y1473898D01*
X5330920Y1472231D01*
X5330610Y1470564D01*
X5329680Y1469523D01*
X5328595Y1468898D01*
X5324720D01*
G01X5328595D02*
X5330920Y1462856D01*
G01X5340220D02*
X5338980Y1463064D01*
X5337895Y1463897D01*
X5336965Y1465148D01*
X5336345Y1466606D01*
X5336035Y1468273D01*
Y1469939D01*
X5336345Y1471606D01*
X5336965Y1473064D01*
X5337895Y1474314D01*
X5338980Y1475148D01*
X5340220Y1475356D01*
X5341460Y1475148D01*
X5342545Y1474314D01*
X5343475Y1473064D01*
X5344095Y1471606D01*
X5344405Y1469939D01*
Y1468273D01*
X5344095Y1466606D01*
X5343475Y1465148D01*
X5342545Y1463897D01*
X5341460Y1463064D01*
X5340220Y1462856D01*
G01X5348590D02*
Y1475356D01*
X5352620Y1464939D01*
X5356650Y1475356D01*
Y1462856D01*
G01X5374165Y1464522D02*
X5375405Y1463481D01*
X5376800Y1462856D01*
X5378040D01*
X5379280Y1463481D01*
X5380210Y1464522D01*
X5380675Y1465981D01*
X5380365Y1467439D01*
X5379590Y1468689D01*
X5378195Y1469523D01*
X5376335Y1469939D01*
X5375250Y1470773D01*
X5374785Y1472231D01*
X5375095Y1473689D01*
X5375870Y1474731D01*
X5376955Y1475356D01*
X5378040D01*
X5379125Y1474939D01*
X5380055Y1473898D01*
G01X5389820Y1475356D02*
Y1462856D01*
G01X5386255Y1475356D02*
X5393385D01*
G01X5398345Y1462856D02*
X5402220Y1475356D01*
X5406095Y1462856D01*
G01X5404700Y1467231D02*
X5399740D01*
G01X5411520Y1462856D02*
Y1475356D01*
X5415395D01*
X5416635Y1474731D01*
X5417410Y1473898D01*
X5417720Y1472231D01*
X5417410Y1470564D01*
X5416480Y1469523D01*
X5415395Y1468898D01*
X5411520D01*
G01X5415395D02*
X5417720Y1462856D01*
G01X5427020Y1475356D02*
Y1462856D01*
G01X5423455Y1475356D02*
X5430585D01*
G01X5448720D02*
Y1462856D01*
X5454920D01*
G01X5460345D02*
X5464220Y1475356D01*
X5468095Y1462856D01*
G01X5466700Y1467231D02*
X5461740D01*
G01X5476620Y1462856D02*
Y1468481D01*
X5473520Y1475356D01*
G01X5479720D02*
X5476620Y1468481D01*
G01X5492120Y1462856D02*
X5485920D01*
Y1475356D01*
X5492120D01*
G01X5489640Y1469314D02*
X5485920D01*
G01X5498320Y1462856D02*
Y1475356D01*
X5502195D01*
X5503435Y1474731D01*
X5504210Y1473898D01*
X5504520Y1472231D01*
X5504210Y1470564D01*
X5503280Y1469523D01*
X5502195Y1468898D01*
X5498320D01*
G01X5502195D02*
X5504520Y1462856D01*
G01X5526220Y1475356D02*
Y1462856D01*
G01X5522655Y1475356D02*
X5529785D01*
G01X5538620Y1462856D02*
X5537380Y1463064D01*
X5536295Y1463897D01*
X5535365Y1465148D01*
X5534745Y1466606D01*
X5534435Y1468273D01*
Y1469939D01*
X5534745Y1471606D01*
X5535365Y1473064D01*
X5536295Y1474314D01*
X5537380Y1475148D01*
X5538620Y1475356D01*
X5539860Y1475148D01*
X5540945Y1474314D01*
X5541875Y1473064D01*
X5542495Y1471606D01*
X5542805Y1469939D01*
Y1468273D01*
X5542495Y1466606D01*
X5541875Y1465148D01*
X5540945Y1463897D01*
X5539860Y1463064D01*
X5538620Y1462856D01*
G01X5563420Y1475356D02*
Y1462856D01*
G01X5559855Y1475356D02*
X5566985D01*
G01X5572565Y1462856D02*
Y1475356D01*
G01X5579075D02*
Y1462856D01*
G01Y1469106D02*
X5572565D01*
G01X5591320Y1462856D02*
X5585120D01*
Y1475356D01*
X5591320D01*
G01X5588840Y1469314D02*
X5585120D01*
G01X5077805Y1485773D02*
X5081835D01*
G01X5100590Y1481606D02*
Y1494106D01*
X5104620Y1483689D01*
X5108650Y1494106D01*
Y1481606D01*
G01X5113455D02*
Y1494106D01*
X5120585Y1481606D01*
Y1494106D01*
G01X5132830Y1493064D02*
X5131900Y1493689D01*
X5130815Y1494106D01*
X5129575D01*
X5128180Y1493481D01*
X5127095Y1492439D01*
X5126320Y1491189D01*
X5125700Y1489106D01*
X5125545Y1487231D01*
X5125855Y1485356D01*
X5126320Y1484106D01*
X5127250Y1482856D01*
X5128335Y1482023D01*
X5129420Y1481606D01*
X5130505D01*
X5131590Y1482023D01*
X5132520Y1482647D01*
X5133295Y1483481D01*
G01X5137170Y1477439D02*
X5146470D01*
G01X5151120Y1494106D02*
Y1481606D01*
X5157320D01*
G01X5162745D02*
X5166620Y1494106D01*
X5170495Y1481606D01*
G01X5169100Y1485981D02*
X5164140D01*
G01X5179020Y1481606D02*
Y1487231D01*
X5175920Y1494106D01*
G01X5182120D02*
X5179020Y1487231D01*
G01X5194520Y1481606D02*
X5188320D01*
Y1494106D01*
X5194520D01*
G01X5192040Y1488064D02*
X5188320D01*
G01X5200720Y1481606D02*
Y1494106D01*
X5204595D01*
X5205835Y1493481D01*
X5206610Y1492648D01*
X5206920Y1490981D01*
X5206610Y1489314D01*
X5205680Y1488273D01*
X5204595Y1487648D01*
X5200720D01*
G01X5204595D02*
X5206920Y1481606D01*
G01X5216220Y1481189D02*
X5215910Y1481398D01*
Y1481814D01*
X5216220Y1482023D01*
X5216530Y1481814D01*
Y1481398D01*
X5216220Y1481189D01*
G01Y1486814D02*
X5215910Y1487023D01*
Y1487439D01*
X5216220Y1487648D01*
X5216530Y1487439D01*
Y1487023D01*
X5216220Y1486814D01*
G01X5236990Y1481606D02*
Y1494106D01*
X5241020Y1483689D01*
X5245050Y1494106D01*
Y1481606D01*
G01X5250010Y1494106D02*
Y1485148D01*
X5250630Y1483272D01*
X5251870Y1482023D01*
X5253420Y1481606D01*
X5254970Y1482023D01*
X5256210Y1483272D01*
X5256830Y1485148D01*
Y1494106D01*
G01X5262565Y1483272D02*
X5263805Y1482231D01*
X5265200Y1481606D01*
X5266440D01*
X5267680Y1482231D01*
X5268610Y1483272D01*
X5269075Y1484731D01*
X5268765Y1486189D01*
X5267990Y1487439D01*
X5266595Y1488273D01*
X5264735Y1488689D01*
X5263650Y1489523D01*
X5263185Y1490981D01*
X5263495Y1492439D01*
X5264270Y1493481D01*
X5265355Y1494106D01*
X5266440D01*
X5267525Y1493689D01*
X5268455Y1492648D01*
G01X5278220Y1494106D02*
Y1481606D01*
G01X5274655Y1494106D02*
X5281785D01*
G01X5288605Y1485773D02*
X5292635D01*
G01X5299455Y1481606D02*
Y1494106D01*
X5306585Y1481606D01*
Y1494106D01*
G01X5315420Y1481606D02*
X5314180Y1481814D01*
X5313095Y1482647D01*
X5312165Y1483898D01*
X5311545Y1485356D01*
X5311235Y1487023D01*
Y1488689D01*
X5311545Y1490356D01*
X5312165Y1491814D01*
X5313095Y1493064D01*
X5314180Y1493898D01*
X5315420Y1494106D01*
X5316660Y1493898D01*
X5317745Y1493064D01*
X5318675Y1491814D01*
X5319295Y1490356D01*
X5319605Y1488689D01*
Y1487023D01*
X5319295Y1485356D01*
X5318675Y1483898D01*
X5317745Y1482647D01*
X5316660Y1481814D01*
X5315420Y1481606D01*
G01X5327820Y1494106D02*
Y1481606D01*
G01X5324255Y1494106D02*
X5331385D01*
G01X5338205Y1485773D02*
X5342235D01*
G01X5356030Y1493064D02*
X5355100Y1493689D01*
X5354015Y1494106D01*
X5352775D01*
X5351380Y1493481D01*
X5350295Y1492439D01*
X5349520Y1491189D01*
X5348900Y1489106D01*
X5348745Y1487231D01*
X5349055Y1485356D01*
X5349520Y1484106D01*
X5350450Y1482856D01*
X5351535Y1482023D01*
X5352620Y1481606D01*
X5353705D01*
X5354790Y1482023D01*
X5355720Y1482647D01*
X5356495Y1483481D01*
G01X5361610Y1494106D02*
Y1485148D01*
X5362230Y1483272D01*
X5363470Y1482023D01*
X5365020Y1481606D01*
X5366570Y1482023D01*
X5367810Y1483272D01*
X5368430Y1485148D01*
Y1494106D01*
G01X5377420D02*
Y1481606D01*
G01X5373855Y1494106D02*
X5380985D01*
G01X5387805Y1485773D02*
X5391835D01*
G01X5399120Y1494106D02*
Y1481606D01*
X5405320D01*
G01X5410745D02*
X5414620Y1494106D01*
X5418495Y1481606D01*
G01X5417100Y1485981D02*
X5412140D01*
G01X5427020Y1481606D02*
Y1487231D01*
X5423920Y1494106D01*
G01X5430120D02*
X5427020Y1487231D01*
G01X5442520Y1481606D02*
X5436320D01*
Y1494106D01*
X5442520D01*
G01X5440040Y1488064D02*
X5436320D01*
G01X5448720Y1481606D02*
Y1494106D01*
X5452595D01*
X5453835Y1493481D01*
X5454610Y1492648D01*
X5454920Y1490981D01*
X5454610Y1489314D01*
X5453680Y1488273D01*
X5452595Y1487648D01*
X5448720D01*
G01X5452595D02*
X5454920Y1481606D01*
G01X5076255Y1500356D02*
Y1512856D01*
X5083385Y1500356D01*
Y1512856D01*
G01X5092220Y1500356D02*
X5090980Y1500564D01*
X5089895Y1501397D01*
X5088965Y1502648D01*
X5088345Y1504106D01*
X5088035Y1505773D01*
Y1507439D01*
X5088345Y1509106D01*
X5088965Y1510564D01*
X5089895Y1511814D01*
X5090980Y1512648D01*
X5092220Y1512856D01*
X5093460Y1512648D01*
X5094545Y1511814D01*
X5095475Y1510564D01*
X5096095Y1509106D01*
X5096405Y1507439D01*
Y1505773D01*
X5096095Y1504106D01*
X5095475Y1502648D01*
X5094545Y1501397D01*
X5093460Y1500564D01*
X5092220Y1500356D01*
G01X5104620Y1512856D02*
Y1500356D01*
G01X5101055Y1512856D02*
X5108185D01*
G01X5120120Y1500356D02*
X5113920D01*
Y1512856D01*
X5120120D01*
G01X5117640Y1506814D02*
X5113920D01*
G01X5126165Y1502022D02*
X5127405Y1500981D01*
X5128800Y1500356D01*
X5130040D01*
X5131280Y1500981D01*
X5132210Y1502022D01*
X5132675Y1503481D01*
X5132365Y1504939D01*
X5131590Y1506189D01*
X5130195Y1507023D01*
X5128335Y1507439D01*
X5127250Y1508273D01*
X5126785Y1509731D01*
X5127095Y1511189D01*
X5127870Y1512231D01*
X5128955Y1512856D01*
X5130040D01*
X5131125Y1512439D01*
X5132055Y1511398D01*
G01X5141820Y1499939D02*
X5141510Y1500148D01*
Y1500564D01*
X5141820Y1500773D01*
X5142130Y1500564D01*
Y1500148D01*
X5141820Y1499939D01*
G01Y1505564D02*
X5141510Y1505773D01*
Y1506189D01*
X5141820Y1506398D01*
X5142130Y1506189D01*
Y1505773D01*
X5141820Y1505564D01*
G01X5082619Y163116D02*
Y175616D01*
X5088509D01*
G01X5086339Y169574D02*
X5082619D01*
G01X5096104Y175616D02*
X5099824D01*
G01X5097964D02*
Y163116D01*
G01X5096104D02*
X5099824D01*
G01X5111294Y169366D02*
X5114394D01*
Y165616D01*
X5113464Y164366D01*
X5112379Y163533D01*
X5110829Y163116D01*
X5109279Y163533D01*
X5108194Y164366D01*
X5107264Y165616D01*
X5106644Y167074D01*
X5106334Y168741D01*
Y170199D01*
X5106644Y171449D01*
X5107264Y172908D01*
X5108194Y174158D01*
X5109124Y174991D01*
X5110364Y175616D01*
X5111449D01*
X5112689Y175199D01*
X5113619Y174366D01*
G01X5119354Y175616D02*
Y166658D01*
X5119974Y164782D01*
X5121214Y163533D01*
X5122764Y163116D01*
X5124314Y163533D01*
X5125554Y164782D01*
X5126174Y166658D01*
Y175616D01*
G01X5132064Y163116D02*
Y175616D01*
X5135939D01*
X5137179Y174991D01*
X5137954Y174158D01*
X5138264Y172491D01*
X5137954Y170824D01*
X5137024Y169783D01*
X5135939Y169158D01*
X5132064D01*
G01X5135939D02*
X5138264Y163116D01*
G01X5150664D02*
X5144464D01*
Y175616D01*
X5150664D01*
G01X5148184Y169574D02*
X5144464D01*
G01X5082585Y435935D02*
Y448435D01*
X5088475D01*
G01X5086305Y442393D02*
X5082585D01*
G01X5096070Y448435D02*
X5099790D01*
G01X5097930D02*
Y435935D01*
G01X5096070D02*
X5099790D01*
G01X5111260Y442185D02*
X5114360D01*
Y438435D01*
X5113430Y437185D01*
X5112345Y436352D01*
X5110795Y435935D01*
X5109245Y436352D01*
X5108160Y437185D01*
X5107230Y438435D01*
X5106610Y439893D01*
X5106300Y441560D01*
Y443018D01*
X5106610Y444268D01*
X5107230Y445727D01*
X5108160Y446977D01*
X5109090Y447810D01*
X5110330Y448435D01*
X5111415D01*
X5112655Y448018D01*
X5113585Y447185D01*
G01X5119320Y448435D02*
Y439477D01*
X5119940Y437601D01*
X5121180Y436352D01*
X5122730Y435935D01*
X5124280Y436352D01*
X5125520Y437601D01*
X5126140Y439477D01*
Y448435D01*
G01X5132030Y435935D02*
Y448435D01*
X5135905D01*
X5137145Y447810D01*
X5137920Y446977D01*
X5138230Y445310D01*
X5137920Y443643D01*
X5136990Y442602D01*
X5135905Y441977D01*
X5132030D01*
G01X5135905D02*
X5138230Y435935D01*
G01X5150630D02*
X5144430D01*
Y448435D01*
X5150630D01*
G01X5148150Y442393D02*
X5144430D01*
G01X5085175Y707106D02*
Y719606D01*
X5091065D01*
G01X5088895Y713564D02*
X5085175D01*
G01X5098660Y719606D02*
X5102380D01*
G01X5100520D02*
Y707106D01*
G01X5098660D02*
X5102380D01*
G01X5113850Y713356D02*
X5116950D01*
Y709606D01*
X5116020Y708356D01*
X5114935Y707523D01*
X5113385Y707106D01*
X5111835Y707523D01*
X5110750Y708356D01*
X5109820Y709606D01*
X5109200Y711064D01*
X5108890Y712731D01*
Y714189D01*
X5109200Y715439D01*
X5109820Y716898D01*
X5110750Y718148D01*
X5111680Y718981D01*
X5112920Y719606D01*
X5114005D01*
X5115245Y719189D01*
X5116175Y718356D01*
G01X5121910Y719606D02*
Y710648D01*
X5122530Y708772D01*
X5123770Y707523D01*
X5125320Y707106D01*
X5126870Y707523D01*
X5128110Y708772D01*
X5128730Y710648D01*
Y719606D01*
G01X5134620Y707106D02*
Y719606D01*
X5138495D01*
X5139735Y718981D01*
X5140510Y718148D01*
X5140820Y716481D01*
X5140510Y714814D01*
X5139580Y713773D01*
X5138495Y713148D01*
X5134620D01*
G01X5138495D02*
X5140820Y707106D01*
G01X5153220D02*
X5147020D01*
Y719606D01*
X5153220D01*
G01X5150740Y713564D02*
X5147020D01*
G01X5243260Y783773D02*
X5243880Y784398D01*
X5244345Y785439D01*
X5244655Y786898D01*
X5244345Y788148D01*
X5243725Y788981D01*
X5242640Y789606D01*
X5238455D01*
Y777106D01*
X5243570D01*
X5244655Y777939D01*
X5245275Y779189D01*
X5245585Y780648D01*
X5245275Y782106D01*
X5244345Y783356D01*
X5243260Y783773D01*
X5238455D01*
G01X5250545Y777106D02*
X5254420Y789606D01*
X5258295Y777106D01*
G01X5256900Y781481D02*
X5251940D01*
G01X5270230Y788564D02*
X5269300Y789189D01*
X5268215Y789606D01*
X5266975D01*
X5265580Y788981D01*
X5264495Y787939D01*
X5263720Y786689D01*
X5263100Y784606D01*
X5262945Y782731D01*
X5263255Y780856D01*
X5263720Y779606D01*
X5264650Y778356D01*
X5265735Y777523D01*
X5266820Y777106D01*
X5267905D01*
X5268990Y777523D01*
X5269920Y778147D01*
X5270695Y778981D01*
G01X5275810Y777106D02*
Y789606D01*
G01X5281700D02*
X5275810Y781897D01*
G01X5282630Y777106D02*
X5278445Y785439D01*
G01X5288210Y777106D02*
Y789606D01*
X5291310D01*
X5292550Y788981D01*
X5293480Y788148D01*
X5294255Y786898D01*
X5294875Y785439D01*
X5295030Y783356D01*
X5294875Y781273D01*
X5294255Y779814D01*
X5293480Y778564D01*
X5292550Y777731D01*
X5291310Y777106D01*
X5288210D01*
G01X5300920D02*
Y789606D01*
X5304795D01*
X5306035Y788981D01*
X5306810Y788148D01*
X5307120Y786481D01*
X5306810Y784814D01*
X5305880Y783773D01*
X5304795Y783148D01*
X5300920D01*
G01X5304795D02*
X5307120Y777106D01*
G01X5314560Y789606D02*
X5318280D01*
G01X5316420D02*
Y777106D01*
G01X5314560D02*
X5318280D01*
G01X5325720Y789606D02*
Y777106D01*
X5331920D01*
G01X5338120Y789606D02*
Y777106D01*
X5344320D01*
G01X5362765Y778772D02*
X5364005Y777731D01*
X5365400Y777106D01*
X5366640D01*
X5367880Y777731D01*
X5368810Y778772D01*
X5369275Y780231D01*
X5368965Y781689D01*
X5368190Y782939D01*
X5366795Y783773D01*
X5364935Y784189D01*
X5363850Y785023D01*
X5363385Y786481D01*
X5363695Y787939D01*
X5364470Y788981D01*
X5365555Y789606D01*
X5366640D01*
X5367725Y789189D01*
X5368655Y788148D01*
G01X5378420Y789606D02*
Y777106D01*
G01X5374855Y789606D02*
X5381985D01*
G01X5387410D02*
Y780648D01*
X5388030Y778772D01*
X5389270Y777523D01*
X5390820Y777106D01*
X5392370Y777523D01*
X5393610Y778772D01*
X5394230Y780648D01*
Y789606D01*
G01X5404460Y783773D02*
X5405080Y784398D01*
X5405545Y785439D01*
X5405855Y786898D01*
X5405545Y788148D01*
X5404925Y788981D01*
X5403840Y789606D01*
X5399655D01*
Y777106D01*
X5404770D01*
X5405855Y777939D01*
X5406475Y779189D01*
X5406785Y780648D01*
X5406475Y782106D01*
X5405545Y783356D01*
X5404460Y783773D01*
X5399655D01*
G01X5424920Y789606D02*
Y777106D01*
X5431120D01*
G01X5443520D02*
X5437320D01*
Y789606D01*
X5443520D01*
G01X5441040Y783564D02*
X5437320D01*
G01X5449255Y777106D02*
Y789606D01*
X5456385Y777106D01*
Y789606D01*
G01X5466150Y783356D02*
X5469250D01*
Y779606D01*
X5468320Y778356D01*
X5467235Y777523D01*
X5465685Y777106D01*
X5464135Y777523D01*
X5463050Y778356D01*
X5462120Y779606D01*
X5461500Y781064D01*
X5461190Y782731D01*
Y784189D01*
X5461500Y785439D01*
X5462120Y786898D01*
X5463050Y788148D01*
X5463980Y788981D01*
X5465220Y789606D01*
X5466305D01*
X5467545Y789189D01*
X5468475Y788356D01*
G01X5477620Y789606D02*
Y777106D01*
G01X5474055Y789606D02*
X5481185D01*
G01X5486765Y777106D02*
Y789606D01*
G01X5493275D02*
Y777106D01*
G01Y783356D02*
X5486765D01*
G01X5514820Y789606D02*
Y777106D01*
G01X5511255Y789606D02*
X5518385D01*
G01X5527220Y777106D02*
X5525980Y777314D01*
X5524895Y778147D01*
X5523965Y779398D01*
X5523345Y780856D01*
X5523035Y782523D01*
Y784189D01*
X5523345Y785856D01*
X5523965Y787314D01*
X5524895Y788564D01*
X5525980Y789398D01*
X5527220Y789606D01*
X5528460Y789398D01*
X5529545Y788564D01*
X5530475Y787314D01*
X5531095Y785856D01*
X5531405Y784189D01*
Y782523D01*
X5531095Y780856D01*
X5530475Y779398D01*
X5529545Y778147D01*
X5528460Y777314D01*
X5527220Y777106D01*
G01X5536520Y789606D02*
Y777106D01*
X5542720D01*
G01X5555120D02*
X5548920D01*
Y789606D01*
X5555120D01*
G01X5552640Y783564D02*
X5548920D01*
G01X5561320Y777106D02*
Y789606D01*
X5565195D01*
X5566435Y788981D01*
X5567210Y788148D01*
X5567520Y786481D01*
X5567210Y784814D01*
X5566280Y783773D01*
X5565195Y783148D01*
X5561320D01*
G01X5565195D02*
X5567520Y777106D01*
G01X5572945D02*
X5576820Y789606D01*
X5580695Y777106D01*
G01X5579300Y781481D02*
X5574340D01*
G01X5585655Y777106D02*
Y789606D01*
X5592785Y777106D01*
Y789606D01*
G01X5605030Y788564D02*
X5604100Y789189D01*
X5603015Y789606D01*
X5601775D01*
X5600380Y788981D01*
X5599295Y787939D01*
X5598520Y786689D01*
X5597900Y784606D01*
X5597745Y782731D01*
X5598055Y780856D01*
X5598520Y779606D01*
X5599450Y778356D01*
X5600535Y777523D01*
X5601620Y777106D01*
X5602705D01*
X5603790Y777523D01*
X5604720Y778147D01*
X5605495Y778981D01*
G01X5617120Y777106D02*
X5610920D01*
Y789606D01*
X5617120D01*
G01X5614640Y783564D02*
X5610920D01*
G01X5638820Y789606D02*
Y777106D01*
G01X5635255Y789606D02*
X5642385D01*
G01X5651220Y777106D02*
X5649980Y777314D01*
X5648895Y778147D01*
X5647965Y779398D01*
X5647345Y780856D01*
X5647035Y782523D01*
Y784189D01*
X5647345Y785856D01*
X5647965Y787314D01*
X5648895Y788564D01*
X5649980Y789398D01*
X5651220Y789606D01*
X5652460Y789398D01*
X5653545Y788564D01*
X5654475Y787314D01*
X5655095Y785856D01*
X5655405Y784189D01*
Y782523D01*
X5655095Y780856D01*
X5654475Y779398D01*
X5653545Y778147D01*
X5652460Y777314D01*
X5651220Y777106D01*
G01X5677260Y783773D02*
X5677880Y784398D01*
X5678345Y785439D01*
X5678655Y786898D01*
X5678345Y788148D01*
X5677725Y788981D01*
X5676640Y789606D01*
X5672455D01*
Y777106D01*
X5677570D01*
X5678655Y777939D01*
X5679275Y779189D01*
X5679585Y780648D01*
X5679275Y782106D01*
X5678345Y783356D01*
X5677260Y783773D01*
X5672455D01*
G01X5691520Y777106D02*
X5685320D01*
Y789606D01*
X5691520D01*
G01X5689040Y783564D02*
X5685320D01*
G01X5712910Y777106D02*
X5713220Y779814D01*
X5713685Y782106D01*
X5714305Y784189D01*
X5715080Y786481D01*
X5716320Y789606D01*
X5710120D01*
G01X5736315Y781273D02*
X5740035D01*
G01X5738020Y783981D02*
Y778564D01*
G01X5747630Y776689D02*
X5753210Y789606D01*
G01X5760805Y781273D02*
X5764835D01*
G01X5771810Y778981D02*
X5772740Y777939D01*
X5773825Y777314D01*
X5775220Y777106D01*
X5776615Y777523D01*
X5777700Y778356D01*
X5778475Y779814D01*
X5778630Y781481D01*
X5778320Y783148D01*
X5777545Y784189D01*
X5776460Y785023D01*
X5775375Y785231D01*
X5774290Y785023D01*
X5772895Y784189D01*
X5773360Y789606D01*
X5777545D01*
G01X5795990Y777106D02*
Y789606D01*
X5800020Y779189D01*
X5804050Y789606D01*
Y777106D01*
G01X5810560Y789606D02*
X5814280D01*
G01X5812420D02*
Y777106D01*
G01X5810560D02*
X5814280D01*
G01X5821720Y789606D02*
Y777106D01*
X5827920D01*
G01X5833965Y778772D02*
X5835205Y777731D01*
X5836600Y777106D01*
X5837840D01*
X5839080Y777731D01*
X5840010Y778772D01*
X5840475Y780231D01*
X5840165Y781689D01*
X5839390Y782939D01*
X5837995Y783773D01*
X5836135Y784189D01*
X5835050Y785023D01*
X5834585Y786481D01*
X5834895Y787939D01*
X5835670Y788981D01*
X5836755Y789606D01*
X5837840D01*
X5838925Y789189D01*
X5839855Y788148D01*
G01X5078805Y800023D02*
X5082835D01*
G01X5101590Y795856D02*
Y808356D01*
X5105620Y797939D01*
X5109650Y808356D01*
Y795856D01*
G01X5115075D02*
Y808356D01*
X5120965D01*
G01X5118795Y802314D02*
X5115075D01*
G01X5131350Y802106D02*
X5134450D01*
Y798356D01*
X5133520Y797106D01*
X5132435Y796273D01*
X5130885Y795856D01*
X5129335Y796273D01*
X5128250Y797106D01*
X5127320Y798356D01*
X5126700Y799814D01*
X5126390Y801481D01*
Y802939D01*
X5126700Y804189D01*
X5127320Y805648D01*
X5128250Y806898D01*
X5129180Y807731D01*
X5130420Y808356D01*
X5131505D01*
X5132745Y807939D01*
X5133675Y807106D01*
G01X5138170Y791689D02*
X5147470D01*
G01X5151965Y797522D02*
X5153205Y796481D01*
X5154600Y795856D01*
X5155840D01*
X5157080Y796481D01*
X5158010Y797522D01*
X5158475Y798981D01*
X5158165Y800439D01*
X5157390Y801689D01*
X5155995Y802523D01*
X5154135Y802939D01*
X5153050Y803773D01*
X5152585Y805231D01*
X5152895Y806689D01*
X5153670Y807731D01*
X5154755Y808356D01*
X5155840D01*
X5156925Y807939D01*
X5157855Y806898D01*
G01X5167620Y808356D02*
Y795856D01*
G01X5164055Y808356D02*
X5171185D01*
G01X5176610D02*
Y799398D01*
X5177230Y797522D01*
X5178470Y796273D01*
X5180020Y795856D01*
X5181570Y796273D01*
X5182810Y797522D01*
X5183430Y799398D01*
Y808356D01*
G01X5193660Y802523D02*
X5194280Y803148D01*
X5194745Y804189D01*
X5195055Y805648D01*
X5194745Y806898D01*
X5194125Y807731D01*
X5193040Y808356D01*
X5188855D01*
Y795856D01*
X5193970D01*
X5195055Y796689D01*
X5195675Y797939D01*
X5195985Y799398D01*
X5195675Y800856D01*
X5194745Y802106D01*
X5193660Y802523D01*
X5188855D01*
G01X5217220Y795439D02*
X5216910Y795648D01*
Y796064D01*
X5217220Y796273D01*
X5217530Y796064D01*
Y795648D01*
X5217220Y795439D01*
G01Y801064D02*
X5216910Y801273D01*
Y801689D01*
X5217220Y801898D01*
X5217530Y801689D01*
Y801273D01*
X5217220Y801064D01*
G01X5237990Y795856D02*
Y808356D01*
X5242020Y797939D01*
X5246050Y808356D01*
Y795856D01*
G01X5250545D02*
X5254420Y808356D01*
X5258295Y795856D01*
G01X5256900Y800231D02*
X5251940D01*
G01X5263255Y795856D02*
Y808356D01*
X5270385Y795856D01*
Y808356D01*
G01X5275810D02*
Y799398D01*
X5276430Y797522D01*
X5277670Y796273D01*
X5279220Y795856D01*
X5280770Y796273D01*
X5282010Y797522D01*
X5282630Y799398D01*
Y808356D01*
G01X5288675Y795856D02*
Y808356D01*
X5294565D01*
G01X5292395Y802314D02*
X5288675D01*
G01X5300145Y795856D02*
X5304020Y808356D01*
X5307895Y795856D01*
G01X5306500Y800231D02*
X5301540D01*
G01X5319830Y807314D02*
X5318900Y807939D01*
X5317815Y808356D01*
X5316575D01*
X5315180Y807731D01*
X5314095Y806689D01*
X5313320Y805439D01*
X5312700Y803356D01*
X5312545Y801481D01*
X5312855Y799606D01*
X5313320Y798356D01*
X5314250Y797106D01*
X5315335Y796273D01*
X5316420Y795856D01*
X5317505D01*
X5318590Y796273D01*
X5319520Y796897D01*
X5320295Y797731D01*
G01X5328820Y808356D02*
Y795856D01*
G01X5325255Y808356D02*
X5332385D01*
G01X5337810D02*
Y799398D01*
X5338430Y797522D01*
X5339670Y796273D01*
X5341220Y795856D01*
X5342770Y796273D01*
X5344010Y797522D01*
X5344630Y799398D01*
Y808356D01*
G01X5350520Y795856D02*
Y808356D01*
X5354395D01*
X5355635Y807731D01*
X5356410Y806898D01*
X5356720Y805231D01*
X5356410Y803564D01*
X5355480Y802523D01*
X5354395Y801898D01*
X5350520D01*
G01X5354395D02*
X5356720Y795856D01*
G01X5364160Y808356D02*
X5367880D01*
G01X5366020D02*
Y795856D01*
G01X5364160D02*
X5367880D01*
G01X5374855D02*
Y808356D01*
X5381985Y795856D01*
Y808356D01*
G01X5391750Y802106D02*
X5394850D01*
Y798356D01*
X5393920Y797106D01*
X5392835Y796273D01*
X5391285Y795856D01*
X5389735Y796273D01*
X5388650Y797106D01*
X5387720Y798356D01*
X5387100Y799814D01*
X5386790Y801481D01*
Y802939D01*
X5387100Y804189D01*
X5387720Y805648D01*
X5388650Y806898D01*
X5389580Y807731D01*
X5390820Y808356D01*
X5391905D01*
X5393145Y807939D01*
X5394075Y807106D01*
G01X5412365Y797522D02*
X5413605Y796481D01*
X5415000Y795856D01*
X5416240D01*
X5417480Y796481D01*
X5418410Y797522D01*
X5418875Y798981D01*
X5418565Y800439D01*
X5417790Y801689D01*
X5416395Y802523D01*
X5414535Y802939D01*
X5413450Y803773D01*
X5412985Y805231D01*
X5413295Y806689D01*
X5414070Y807731D01*
X5415155Y808356D01*
X5416240D01*
X5417325Y807939D01*
X5418255Y806898D01*
G01X5428020Y808356D02*
Y795856D01*
G01X5424455Y808356D02*
X5431585D01*
G01X5437010D02*
Y799398D01*
X5437630Y797522D01*
X5438870Y796273D01*
X5440420Y795856D01*
X5441970Y796273D01*
X5443210Y797522D01*
X5443830Y799398D01*
Y808356D01*
G01X5454060Y802523D02*
X5454680Y803148D01*
X5455145Y804189D01*
X5455455Y805648D01*
X5455145Y806898D01*
X5454525Y807731D01*
X5453440Y808356D01*
X5449255D01*
Y795856D01*
X5454370D01*
X5455455Y796689D01*
X5456075Y797939D01*
X5456385Y799398D01*
X5456075Y800856D01*
X5455145Y802106D01*
X5454060Y802523D01*
X5449255D01*
G01X5474520Y808356D02*
Y795856D01*
X5480720D01*
G01X5493120D02*
X5486920D01*
Y808356D01*
X5493120D01*
G01X5490640Y802314D02*
X5486920D01*
G01X5498855Y795856D02*
Y808356D01*
X5505985Y795856D01*
Y808356D01*
G01X5515750Y802106D02*
X5518850D01*
Y798356D01*
X5517920Y797106D01*
X5516835Y796273D01*
X5515285Y795856D01*
X5513735Y796273D01*
X5512650Y797106D01*
X5511720Y798356D01*
X5511100Y799814D01*
X5510790Y801481D01*
Y802939D01*
X5511100Y804189D01*
X5511720Y805648D01*
X5512650Y806898D01*
X5513580Y807731D01*
X5514820Y808356D01*
X5515905D01*
X5517145Y807939D01*
X5518075Y807106D01*
G01X5527220Y808356D02*
Y795856D01*
G01X5523655Y808356D02*
X5530785D01*
G01X5536365Y795856D02*
Y808356D01*
G01X5542875D02*
Y795856D01*
G01Y802106D02*
X5536365D01*
G01X5238765Y816272D02*
X5240005Y815231D01*
X5241400Y814606D01*
X5242640D01*
X5243880Y815231D01*
X5244810Y816272D01*
X5245275Y817731D01*
X5244965Y819189D01*
X5244190Y820439D01*
X5242795Y821273D01*
X5240935Y821689D01*
X5239850Y822523D01*
X5239385Y823981D01*
X5239695Y825439D01*
X5240470Y826481D01*
X5241555Y827106D01*
X5242640D01*
X5243725Y826689D01*
X5244655Y825648D01*
G01X5251010Y827106D02*
Y818148D01*
X5251630Y816272D01*
X5252870Y815023D01*
X5254420Y814606D01*
X5255970Y815023D01*
X5257210Y816272D01*
X5257830Y818148D01*
Y827106D01*
G01X5263720Y814606D02*
Y827106D01*
X5267595D01*
X5268835Y826481D01*
X5269610Y825648D01*
X5269920Y823981D01*
X5269610Y822314D01*
X5268680Y821273D01*
X5267595Y820648D01*
X5263720D01*
G01X5267595D02*
X5269920Y814606D01*
G01X5276275D02*
Y827106D01*
X5282165D01*
G01X5279995Y821064D02*
X5276275D01*
G01X5287745Y814606D02*
X5291620Y827106D01*
X5295495Y814606D01*
G01X5294100Y818981D02*
X5289140D01*
G01X5307430Y826064D02*
X5306500Y826689D01*
X5305415Y827106D01*
X5304175D01*
X5302780Y826481D01*
X5301695Y825439D01*
X5300920Y824189D01*
X5300300Y822106D01*
X5300145Y820231D01*
X5300455Y818356D01*
X5300920Y817106D01*
X5301850Y815856D01*
X5302935Y815023D01*
X5304020Y814606D01*
X5305105D01*
X5306190Y815023D01*
X5307120Y815647D01*
X5307895Y816481D01*
G01X5319520Y814606D02*
X5313320D01*
Y827106D01*
X5319520D01*
G01X5317040Y821064D02*
X5313320D01*
G01X5341220Y814606D02*
X5339980Y814814D01*
X5338895Y815647D01*
X5337965Y816898D01*
X5337345Y818356D01*
X5337035Y820023D01*
Y821689D01*
X5337345Y823356D01*
X5337965Y824814D01*
X5338895Y826064D01*
X5339980Y826898D01*
X5341220Y827106D01*
X5342460Y826898D01*
X5343545Y826064D01*
X5344475Y824814D01*
X5345095Y823356D01*
X5345405Y821689D01*
Y820023D01*
X5345095Y818356D01*
X5344475Y816898D01*
X5343545Y815647D01*
X5342460Y814814D01*
X5341220Y814606D01*
G01X5350675D02*
Y827106D01*
X5356565D01*
G01X5354395Y821064D02*
X5350675D01*
G01X5374390Y814606D02*
Y827106D01*
X5378420Y816689D01*
X5382450Y827106D01*
Y814606D01*
G01X5387410Y827106D02*
Y818148D01*
X5388030Y816272D01*
X5389270Y815023D01*
X5390820Y814606D01*
X5392370Y815023D01*
X5393610Y816272D01*
X5394230Y818148D01*
Y827106D01*
G01X5399965Y816272D02*
X5401205Y815231D01*
X5402600Y814606D01*
X5403840D01*
X5405080Y815231D01*
X5406010Y816272D01*
X5406475Y817731D01*
X5406165Y819189D01*
X5405390Y820439D01*
X5403995Y821273D01*
X5402135Y821689D01*
X5401050Y822523D01*
X5400585Y823981D01*
X5400895Y825439D01*
X5401670Y826481D01*
X5402755Y827106D01*
X5403840D01*
X5404925Y826689D01*
X5405855Y825648D01*
G01X5415620Y827106D02*
Y814606D01*
G01X5412055Y827106D02*
X5419185D01*
G01X5426005Y818773D02*
X5430035D01*
G01X5436855Y814606D02*
Y827106D01*
X5443985Y814606D01*
Y827106D01*
G01X5452820Y814606D02*
X5451580Y814814D01*
X5450495Y815647D01*
X5449565Y816898D01*
X5448945Y818356D01*
X5448635Y820023D01*
Y821689D01*
X5448945Y823356D01*
X5449565Y824814D01*
X5450495Y826064D01*
X5451580Y826898D01*
X5452820Y827106D01*
X5454060Y826898D01*
X5455145Y826064D01*
X5456075Y824814D01*
X5456695Y823356D01*
X5457005Y821689D01*
Y820023D01*
X5456695Y818356D01*
X5456075Y816898D01*
X5455145Y815647D01*
X5454060Y814814D01*
X5452820Y814606D01*
G01X5465220Y827106D02*
Y814606D01*
G01X5461655Y827106D02*
X5468785D01*
G01X5475605Y818773D02*
X5479635D01*
G01X5493430Y826064D02*
X5492500Y826689D01*
X5491415Y827106D01*
X5490175D01*
X5488780Y826481D01*
X5487695Y825439D01*
X5486920Y824189D01*
X5486300Y822106D01*
X5486145Y820231D01*
X5486455Y818356D01*
X5486920Y817106D01*
X5487850Y815856D01*
X5488935Y815023D01*
X5490020Y814606D01*
X5491105D01*
X5492190Y815023D01*
X5493120Y815647D01*
X5493895Y816481D01*
G01X5499010Y827106D02*
Y818148D01*
X5499630Y816272D01*
X5500870Y815023D01*
X5502420Y814606D01*
X5503970Y815023D01*
X5505210Y816272D01*
X5505830Y818148D01*
Y827106D01*
G01X5514820D02*
Y814606D01*
G01X5511255Y827106D02*
X5518385D01*
G01X5525205Y818773D02*
X5529235D01*
G01X5536520Y827106D02*
Y814606D01*
X5542720D01*
G01X5548145D02*
X5552020Y827106D01*
X5555895Y814606D01*
G01X5554500Y818981D02*
X5549540D01*
G01X5564420Y814606D02*
Y820231D01*
X5561320Y827106D01*
G01X5567520D02*
X5564420Y820231D01*
G01X5579920Y814606D02*
X5573720D01*
Y827106D01*
X5579920D01*
G01X5577440Y821064D02*
X5573720D01*
G01X5586120Y814606D02*
Y827106D01*
X5589995D01*
X5591235Y826481D01*
X5592010Y825648D01*
X5592320Y823981D01*
X5592010Y822314D01*
X5591080Y821273D01*
X5589995Y820648D01*
X5586120D01*
G01X5589995D02*
X5592320Y814606D01*
G01X5078805Y837523D02*
X5082835D01*
G01X5101590Y833356D02*
Y845856D01*
X5105620Y835439D01*
X5109650Y845856D01*
Y833356D01*
G01X5114145D02*
X5118020Y845856D01*
X5121895Y833356D01*
G01X5120500Y837731D02*
X5115540D01*
G01X5127165Y833356D02*
X5133675Y845856D01*
G01X5127165D02*
X5133675Y833356D01*
G01X5138170Y829189D02*
X5147470D01*
G01X5151810Y833356D02*
Y845856D01*
X5154910D01*
X5156150Y845231D01*
X5157080Y844398D01*
X5157855Y843148D01*
X5158475Y841689D01*
X5158630Y839606D01*
X5158475Y837523D01*
X5157855Y836064D01*
X5157080Y834814D01*
X5156150Y833981D01*
X5154910Y833356D01*
X5151810D01*
G01X5170720D02*
X5164520D01*
Y845856D01*
X5170720D01*
G01X5168240Y839814D02*
X5164520D01*
G01X5176920Y833356D02*
Y845856D01*
X5180640D01*
X5181880Y845231D01*
X5182810Y843773D01*
X5183120Y842106D01*
X5182810Y840439D01*
X5182035Y839189D01*
X5180640Y838564D01*
X5176920D01*
G01X5192420Y845856D02*
Y833356D01*
G01X5188855Y845856D02*
X5195985D01*
G01X5201565Y833356D02*
Y845856D01*
G01X5208075D02*
Y833356D01*
G01Y839606D02*
X5201565D01*
G01X5217220Y832939D02*
X5216910Y833148D01*
Y833564D01*
X5217220Y833773D01*
X5217530Y833564D01*
Y833148D01*
X5217220Y832939D01*
G01Y838564D02*
X5216910Y838773D01*
Y839189D01*
X5217220Y839398D01*
X5217530Y839189D01*
Y838773D01*
X5217220Y838564D01*
G01X5238610Y833356D02*
Y845856D01*
X5241710D01*
X5242950Y845231D01*
X5243880Y844398D01*
X5244655Y843148D01*
X5245275Y841689D01*
X5245430Y839606D01*
X5245275Y837523D01*
X5244655Y836064D01*
X5243880Y834814D01*
X5242950Y833981D01*
X5241710Y833356D01*
X5238610D01*
G01X5257520D02*
X5251320D01*
Y845856D01*
X5257520D01*
G01X5255040Y839814D02*
X5251320D01*
G01X5263720Y833356D02*
Y845856D01*
X5267440D01*
X5268680Y845231D01*
X5269610Y843773D01*
X5269920Y842106D01*
X5269610Y840439D01*
X5268835Y839189D01*
X5267440Y838564D01*
X5263720D01*
G01X5279220Y845856D02*
Y833356D01*
G01X5275655Y845856D02*
X5282785D01*
G01X5288365Y833356D02*
Y845856D01*
G01X5294875D02*
Y833356D01*
G01Y839606D02*
X5288365D01*
G01X5313475Y833356D02*
Y845856D01*
X5319365D01*
G01X5317195Y839814D02*
X5313475D01*
G01X5325720Y833356D02*
Y845856D01*
X5329595D01*
X5330835Y845231D01*
X5331610Y844398D01*
X5331920Y842731D01*
X5331610Y841064D01*
X5330680Y840023D01*
X5329595Y839398D01*
X5325720D01*
G01X5329595D02*
X5331920Y833356D01*
G01X5341220D02*
X5339980Y833564D01*
X5338895Y834397D01*
X5337965Y835648D01*
X5337345Y837106D01*
X5337035Y838773D01*
Y840439D01*
X5337345Y842106D01*
X5337965Y843564D01*
X5338895Y844814D01*
X5339980Y845648D01*
X5341220Y845856D01*
X5342460Y845648D01*
X5343545Y844814D01*
X5344475Y843564D01*
X5345095Y842106D01*
X5345405Y840439D01*
Y838773D01*
X5345095Y837106D01*
X5344475Y835648D01*
X5343545Y834397D01*
X5342460Y833564D01*
X5341220Y833356D01*
G01X5349590D02*
Y845856D01*
X5353620Y835439D01*
X5357650Y845856D01*
Y833356D01*
G01X5375165Y835022D02*
X5376405Y833981D01*
X5377800Y833356D01*
X5379040D01*
X5380280Y833981D01*
X5381210Y835022D01*
X5381675Y836481D01*
X5381365Y837939D01*
X5380590Y839189D01*
X5379195Y840023D01*
X5377335Y840439D01*
X5376250Y841273D01*
X5375785Y842731D01*
X5376095Y844189D01*
X5376870Y845231D01*
X5377955Y845856D01*
X5379040D01*
X5380125Y845439D01*
X5381055Y844398D01*
G01X5390820Y845856D02*
Y833356D01*
G01X5387255Y845856D02*
X5394385D01*
G01X5399345Y833356D02*
X5403220Y845856D01*
X5407095Y833356D01*
G01X5405700Y837731D02*
X5400740D01*
G01X5412520Y833356D02*
Y845856D01*
X5416395D01*
X5417635Y845231D01*
X5418410Y844398D01*
X5418720Y842731D01*
X5418410Y841064D01*
X5417480Y840023D01*
X5416395Y839398D01*
X5412520D01*
G01X5416395D02*
X5418720Y833356D01*
G01X5428020Y845856D02*
Y833356D01*
G01X5424455Y845856D02*
X5431585D01*
G01X5449720D02*
Y833356D01*
X5455920D01*
G01X5461345D02*
X5465220Y845856D01*
X5469095Y833356D01*
G01X5467700Y837731D02*
X5462740D01*
G01X5477620Y833356D02*
Y838981D01*
X5474520Y845856D01*
G01X5480720D02*
X5477620Y838981D01*
G01X5493120Y833356D02*
X5486920D01*
Y845856D01*
X5493120D01*
G01X5490640Y839814D02*
X5486920D01*
G01X5499320Y833356D02*
Y845856D01*
X5503195D01*
X5504435Y845231D01*
X5505210Y844398D01*
X5505520Y842731D01*
X5505210Y841064D01*
X5504280Y840023D01*
X5503195Y839398D01*
X5499320D01*
G01X5503195D02*
X5505520Y833356D01*
G01X5527220Y845856D02*
Y833356D01*
G01X5523655Y845856D02*
X5530785D01*
G01X5539620Y833356D02*
X5538380Y833564D01*
X5537295Y834397D01*
X5536365Y835648D01*
X5535745Y837106D01*
X5535435Y838773D01*
Y840439D01*
X5535745Y842106D01*
X5536365Y843564D01*
X5537295Y844814D01*
X5538380Y845648D01*
X5539620Y845856D01*
X5540860Y845648D01*
X5541945Y844814D01*
X5542875Y843564D01*
X5543495Y842106D01*
X5543805Y840439D01*
Y838773D01*
X5543495Y837106D01*
X5542875Y835648D01*
X5541945Y834397D01*
X5540860Y833564D01*
X5539620Y833356D01*
G01X5564420Y845856D02*
Y833356D01*
G01X5560855Y845856D02*
X5567985D01*
G01X5573565Y833356D02*
Y845856D01*
G01X5580075D02*
Y833356D01*
G01Y839606D02*
X5573565D01*
G01X5592320Y833356D02*
X5586120D01*
Y845856D01*
X5592320D01*
G01X5589840Y839814D02*
X5586120D01*
G01X5078805Y856273D02*
X5082835D01*
G01X5101590Y852106D02*
Y864606D01*
X5105620Y854189D01*
X5109650Y864606D01*
Y852106D01*
G01X5114455D02*
Y864606D01*
X5121585Y852106D01*
Y864606D01*
G01X5133830Y863564D02*
X5132900Y864189D01*
X5131815Y864606D01*
X5130575D01*
X5129180Y863981D01*
X5128095Y862939D01*
X5127320Y861689D01*
X5126700Y859606D01*
X5126545Y857731D01*
X5126855Y855856D01*
X5127320Y854606D01*
X5128250Y853356D01*
X5129335Y852523D01*
X5130420Y852106D01*
X5131505D01*
X5132590Y852523D01*
X5133520Y853147D01*
X5134295Y853981D01*
G01X5138170Y847939D02*
X5147470D01*
G01X5152120Y864606D02*
Y852106D01*
X5158320D01*
G01X5163745D02*
X5167620Y864606D01*
X5171495Y852106D01*
G01X5170100Y856481D02*
X5165140D01*
G01X5180020Y852106D02*
Y857731D01*
X5176920Y864606D01*
G01X5183120D02*
X5180020Y857731D01*
G01X5195520Y852106D02*
X5189320D01*
Y864606D01*
X5195520D01*
G01X5193040Y858564D02*
X5189320D01*
G01X5201720Y852106D02*
Y864606D01*
X5205595D01*
X5206835Y863981D01*
X5207610Y863148D01*
X5207920Y861481D01*
X5207610Y859814D01*
X5206680Y858773D01*
X5205595Y858148D01*
X5201720D01*
G01X5205595D02*
X5207920Y852106D01*
G01X5217220Y851689D02*
X5216910Y851898D01*
Y852314D01*
X5217220Y852523D01*
X5217530Y852314D01*
Y851898D01*
X5217220Y851689D01*
G01Y857314D02*
X5216910Y857523D01*
Y857939D01*
X5217220Y858148D01*
X5217530Y857939D01*
Y857523D01*
X5217220Y857314D01*
G01X5237990Y852106D02*
Y864606D01*
X5242020Y854189D01*
X5246050Y864606D01*
Y852106D01*
G01X5251010Y864606D02*
Y855648D01*
X5251630Y853772D01*
X5252870Y852523D01*
X5254420Y852106D01*
X5255970Y852523D01*
X5257210Y853772D01*
X5257830Y855648D01*
Y864606D01*
G01X5263565Y853772D02*
X5264805Y852731D01*
X5266200Y852106D01*
X5267440D01*
X5268680Y852731D01*
X5269610Y853772D01*
X5270075Y855231D01*
X5269765Y856689D01*
X5268990Y857939D01*
X5267595Y858773D01*
X5265735Y859189D01*
X5264650Y860023D01*
X5264185Y861481D01*
X5264495Y862939D01*
X5265270Y863981D01*
X5266355Y864606D01*
X5267440D01*
X5268525Y864189D01*
X5269455Y863148D01*
G01X5279220Y864606D02*
Y852106D01*
G01X5275655Y864606D02*
X5282785D01*
G01X5289605Y856273D02*
X5293635D01*
G01X5300455Y852106D02*
Y864606D01*
X5307585Y852106D01*
Y864606D01*
G01X5316420Y852106D02*
X5315180Y852314D01*
X5314095Y853147D01*
X5313165Y854398D01*
X5312545Y855856D01*
X5312235Y857523D01*
Y859189D01*
X5312545Y860856D01*
X5313165Y862314D01*
X5314095Y863564D01*
X5315180Y864398D01*
X5316420Y864606D01*
X5317660Y864398D01*
X5318745Y863564D01*
X5319675Y862314D01*
X5320295Y860856D01*
X5320605Y859189D01*
Y857523D01*
X5320295Y855856D01*
X5319675Y854398D01*
X5318745Y853147D01*
X5317660Y852314D01*
X5316420Y852106D01*
G01X5328820Y864606D02*
Y852106D01*
G01X5325255Y864606D02*
X5332385D01*
G01X5339205Y856273D02*
X5343235D01*
G01X5357030Y863564D02*
X5356100Y864189D01*
X5355015Y864606D01*
X5353775D01*
X5352380Y863981D01*
X5351295Y862939D01*
X5350520Y861689D01*
X5349900Y859606D01*
X5349745Y857731D01*
X5350055Y855856D01*
X5350520Y854606D01*
X5351450Y853356D01*
X5352535Y852523D01*
X5353620Y852106D01*
X5354705D01*
X5355790Y852523D01*
X5356720Y853147D01*
X5357495Y853981D01*
G01X5362610Y864606D02*
Y855648D01*
X5363230Y853772D01*
X5364470Y852523D01*
X5366020Y852106D01*
X5367570Y852523D01*
X5368810Y853772D01*
X5369430Y855648D01*
Y864606D01*
G01X5378420D02*
Y852106D01*
G01X5374855Y864606D02*
X5381985D01*
G01X5388805Y856273D02*
X5392835D01*
G01X5400120Y864606D02*
Y852106D01*
X5406320D01*
G01X5411745D02*
X5415620Y864606D01*
X5419495Y852106D01*
G01X5418100Y856481D02*
X5413140D01*
G01X5428020Y852106D02*
Y857731D01*
X5424920Y864606D01*
G01X5431120D02*
X5428020Y857731D01*
G01X5443520Y852106D02*
X5437320D01*
Y864606D01*
X5443520D01*
G01X5441040Y858564D02*
X5437320D01*
G01X5449720Y852106D02*
Y864606D01*
X5453595D01*
X5454835Y863981D01*
X5455610Y863148D01*
X5455920Y861481D01*
X5455610Y859814D01*
X5454680Y858773D01*
X5453595Y858148D01*
X5449720D01*
G01X5453595D02*
X5455920Y852106D01*
G01X5077255Y870856D02*
Y883356D01*
X5084385Y870856D01*
Y883356D01*
G01X5093220Y870856D02*
X5091980Y871064D01*
X5090895Y871897D01*
X5089965Y873148D01*
X5089345Y874606D01*
X5089035Y876273D01*
Y877939D01*
X5089345Y879606D01*
X5089965Y881064D01*
X5090895Y882314D01*
X5091980Y883148D01*
X5093220Y883356D01*
X5094460Y883148D01*
X5095545Y882314D01*
X5096475Y881064D01*
X5097095Y879606D01*
X5097405Y877939D01*
Y876273D01*
X5097095Y874606D01*
X5096475Y873148D01*
X5095545Y871897D01*
X5094460Y871064D01*
X5093220Y870856D01*
G01X5105620Y883356D02*
Y870856D01*
G01X5102055Y883356D02*
X5109185D01*
G01X5121120Y870856D02*
X5114920D01*
Y883356D01*
X5121120D01*
G01X5118640Y877314D02*
X5114920D01*
G01X5127165Y872522D02*
X5128405Y871481D01*
X5129800Y870856D01*
X5131040D01*
X5132280Y871481D01*
X5133210Y872522D01*
X5133675Y873981D01*
X5133365Y875439D01*
X5132590Y876689D01*
X5131195Y877523D01*
X5129335Y877939D01*
X5128250Y878773D01*
X5127785Y880231D01*
X5128095Y881689D01*
X5128870Y882731D01*
X5129955Y883356D01*
X5131040D01*
X5132125Y882939D01*
X5133055Y881898D01*
G01X5142820Y870439D02*
X5142510Y870648D01*
Y871064D01*
X5142820Y871273D01*
X5143130Y871064D01*
Y870648D01*
X5142820Y870439D01*
G01Y876064D02*
X5142510Y876273D01*
Y876689D01*
X5142820Y876898D01*
X5143130Y876689D01*
Y876273D01*
X5142820Y876064D01*
G01X5087175Y1014606D02*
Y1027106D01*
X5093065D01*
G01X5090895Y1021064D02*
X5087175D01*
G01X5100660Y1027106D02*
X5104380D01*
G01X5102520D02*
Y1014606D01*
G01X5100660D02*
X5104380D01*
G01X5115850Y1020856D02*
X5118950D01*
Y1017106D01*
X5118020Y1015856D01*
X5116935Y1015023D01*
X5115385Y1014606D01*
X5113835Y1015023D01*
X5112750Y1015856D01*
X5111820Y1017106D01*
X5111200Y1018564D01*
X5110890Y1020231D01*
Y1021689D01*
X5111200Y1022939D01*
X5111820Y1024398D01*
X5112750Y1025648D01*
X5113680Y1026481D01*
X5114920Y1027106D01*
X5116005D01*
X5117245Y1026689D01*
X5118175Y1025856D01*
G01X5123910Y1027106D02*
Y1018148D01*
X5124530Y1016272D01*
X5125770Y1015023D01*
X5127320Y1014606D01*
X5128870Y1015023D01*
X5130110Y1016272D01*
X5130730Y1018148D01*
Y1027106D01*
G01X5136620Y1014606D02*
Y1027106D01*
X5140495D01*
X5141735Y1026481D01*
X5142510Y1025648D01*
X5142820Y1023981D01*
X5142510Y1022314D01*
X5141580Y1021273D01*
X5140495Y1020648D01*
X5136620D01*
G01X5140495D02*
X5142820Y1014606D01*
G01X5155220D02*
X5149020D01*
Y1027106D01*
X5155220D01*
G01X5152740Y1021064D02*
X5149020D01*
G01X5086175Y1328606D02*
Y1341106D01*
X5092065D01*
G01X5089895Y1335064D02*
X5086175D01*
G01X5099660Y1341106D02*
X5103380D01*
G01X5101520D02*
Y1328606D01*
G01X5099660D02*
X5103380D01*
G01X5114850Y1334856D02*
X5117950D01*
Y1331106D01*
X5117020Y1329856D01*
X5115935Y1329023D01*
X5114385Y1328606D01*
X5112835Y1329023D01*
X5111750Y1329856D01*
X5110820Y1331106D01*
X5110200Y1332564D01*
X5109890Y1334231D01*
Y1335689D01*
X5110200Y1336939D01*
X5110820Y1338398D01*
X5111750Y1339648D01*
X5112680Y1340481D01*
X5113920Y1341106D01*
X5115005D01*
X5116245Y1340689D01*
X5117175Y1339856D01*
G01X5122910Y1341106D02*
Y1332148D01*
X5123530Y1330272D01*
X5124770Y1329023D01*
X5126320Y1328606D01*
X5127870Y1329023D01*
X5129110Y1330272D01*
X5129730Y1332148D01*
Y1341106D01*
G01X5135620Y1328606D02*
Y1341106D01*
X5139495D01*
X5140735Y1340481D01*
X5141510Y1339648D01*
X5141820Y1337981D01*
X5141510Y1336314D01*
X5140580Y1335273D01*
X5139495Y1334648D01*
X5135620D01*
G01X5139495D02*
X5141820Y1328606D01*
G01X5154220D02*
X5148020D01*
Y1341106D01*
X5154220D01*
G01X5151740Y1335064D02*
X5148020D01*
G01X5086175Y1644106D02*
Y1656606D01*
X5092065D01*
G01X5089895Y1650564D02*
X5086175D01*
G01X5099660Y1656606D02*
X5103380D01*
G01X5101520D02*
Y1644106D01*
G01X5099660D02*
X5103380D01*
G01X5114850Y1650356D02*
X5117950D01*
Y1646606D01*
X5117020Y1645356D01*
X5115935Y1644523D01*
X5114385Y1644106D01*
X5112835Y1644523D01*
X5111750Y1645356D01*
X5110820Y1646606D01*
X5110200Y1648064D01*
X5109890Y1649731D01*
Y1651189D01*
X5110200Y1652439D01*
X5110820Y1653898D01*
X5111750Y1655148D01*
X5112680Y1655981D01*
X5113920Y1656606D01*
X5115005D01*
X5116245Y1656189D01*
X5117175Y1655356D01*
G01X5122910Y1656606D02*
Y1647648D01*
X5123530Y1645772D01*
X5124770Y1644523D01*
X5126320Y1644106D01*
X5127870Y1644523D01*
X5129110Y1645772D01*
X5129730Y1647648D01*
Y1656606D01*
G01X5135620Y1644106D02*
Y1656606D01*
X5139495D01*
X5140735Y1655981D01*
X5141510Y1655148D01*
X5141820Y1653481D01*
X5141510Y1651814D01*
X5140580Y1650773D01*
X5139495Y1650148D01*
X5135620D01*
G01X5139495D02*
X5141820Y1644106D01*
G01X5154220D02*
X5148020D01*
Y1656606D01*
X5154220D01*
G01X5151740Y1650564D02*
X5148020D01*
G01X5189104Y169783D02*
X5189724Y170408D01*
X5190189Y171449D01*
X5190499Y172908D01*
X5190189Y174158D01*
X5189569Y174991D01*
X5188484Y175616D01*
X5184299D01*
Y163116D01*
X5189414D01*
X5190499Y163949D01*
X5191119Y165199D01*
X5191429Y166658D01*
X5191119Y168116D01*
X5190189Y169366D01*
X5189104Y169783D01*
X5184299D01*
G01X5196854Y163116D02*
Y175616D01*
X5199954D01*
X5201194Y174991D01*
X5202124Y174158D01*
X5202899Y172908D01*
X5203519Y171449D01*
X5203674Y169366D01*
X5203519Y167283D01*
X5202899Y165824D01*
X5202124Y164574D01*
X5201194Y163741D01*
X5199954Y163116D01*
X5196854D01*
G01X5208014Y158949D02*
X5217314D01*
G01X5221809Y164782D02*
X5223049Y163741D01*
X5224444Y163116D01*
X5225684D01*
X5226924Y163741D01*
X5227854Y164782D01*
X5228319Y166241D01*
X5228009Y167699D01*
X5227234Y168949D01*
X5225839Y169783D01*
X5223979Y170199D01*
X5222894Y171033D01*
X5222429Y172491D01*
X5222739Y173949D01*
X5223514Y174991D01*
X5224599Y175616D01*
X5225684D01*
X5226769Y175199D01*
X5227699Y174158D01*
G01X5235604Y175616D02*
X5239324D01*
G01X5237464D02*
Y163116D01*
G01X5235604D02*
X5239324D01*
G01X5246919Y175616D02*
X5252809D01*
X5246919Y163116D01*
X5252809D01*
G01X5265364D02*
X5259164D01*
Y175616D01*
X5265364D01*
G01X5262884Y169574D02*
X5259164D01*
G01X5189070Y442602D02*
X5189690Y443227D01*
X5190155Y444268D01*
X5190465Y445727D01*
X5190155Y446977D01*
X5189535Y447810D01*
X5188450Y448435D01*
X5184265D01*
Y435935D01*
X5189380D01*
X5190465Y436768D01*
X5191085Y438018D01*
X5191395Y439477D01*
X5191085Y440935D01*
X5190155Y442185D01*
X5189070Y442602D01*
X5184265D01*
G01X5196820Y435935D02*
Y448435D01*
X5199920D01*
X5201160Y447810D01*
X5202090Y446977D01*
X5202865Y445727D01*
X5203485Y444268D01*
X5203640Y442185D01*
X5203485Y440102D01*
X5202865Y438643D01*
X5202090Y437393D01*
X5201160Y436560D01*
X5199920Y435935D01*
X5196820D01*
G01X5207980Y431768D02*
X5217280D01*
G01X5221775Y437601D02*
X5223015Y436560D01*
X5224410Y435935D01*
X5225650D01*
X5226890Y436560D01*
X5227820Y437601D01*
X5228285Y439060D01*
X5227975Y440518D01*
X5227200Y441768D01*
X5225805Y442602D01*
X5223945Y443018D01*
X5222860Y443852D01*
X5222395Y445310D01*
X5222705Y446768D01*
X5223480Y447810D01*
X5224565Y448435D01*
X5225650D01*
X5226735Y448018D01*
X5227665Y446977D01*
G01X5235570Y448435D02*
X5239290D01*
G01X5237430D02*
Y435935D01*
G01X5235570D02*
X5239290D01*
G01X5246885Y448435D02*
X5252775D01*
X5246885Y435935D01*
X5252775D01*
G01X5265330D02*
X5259130D01*
Y448435D01*
X5265330D01*
G01X5262850Y442393D02*
X5259130D01*
G01X5191660Y713773D02*
X5192280Y714398D01*
X5192745Y715439D01*
X5193055Y716898D01*
X5192745Y718148D01*
X5192125Y718981D01*
X5191040Y719606D01*
X5186855D01*
Y707106D01*
X5191970D01*
X5193055Y707939D01*
X5193675Y709189D01*
X5193985Y710648D01*
X5193675Y712106D01*
X5192745Y713356D01*
X5191660Y713773D01*
X5186855D01*
G01X5199410Y707106D02*
Y719606D01*
X5202510D01*
X5203750Y718981D01*
X5204680Y718148D01*
X5205455Y716898D01*
X5206075Y715439D01*
X5206230Y713356D01*
X5206075Y711273D01*
X5205455Y709814D01*
X5204680Y708564D01*
X5203750Y707731D01*
X5202510Y707106D01*
X5199410D01*
G01X5210570Y702939D02*
X5219870D01*
G01X5224365Y708772D02*
X5225605Y707731D01*
X5227000Y707106D01*
X5228240D01*
X5229480Y707731D01*
X5230410Y708772D01*
X5230875Y710231D01*
X5230565Y711689D01*
X5229790Y712939D01*
X5228395Y713773D01*
X5226535Y714189D01*
X5225450Y715023D01*
X5224985Y716481D01*
X5225295Y717939D01*
X5226070Y718981D01*
X5227155Y719606D01*
X5228240D01*
X5229325Y719189D01*
X5230255Y718148D01*
G01X5238160Y719606D02*
X5241880D01*
G01X5240020D02*
Y707106D01*
G01X5238160D02*
X5241880D01*
G01X5249475Y719606D02*
X5255365D01*
X5249475Y707106D01*
X5255365D01*
G01X5267920D02*
X5261720D01*
Y719606D01*
X5267920D01*
G01X5265440Y713564D02*
X5261720D01*
G01X5193660Y1021273D02*
X5194280Y1021898D01*
X5194745Y1022939D01*
X5195055Y1024398D01*
X5194745Y1025648D01*
X5194125Y1026481D01*
X5193040Y1027106D01*
X5188855D01*
Y1014606D01*
X5193970D01*
X5195055Y1015439D01*
X5195675Y1016689D01*
X5195985Y1018148D01*
X5195675Y1019606D01*
X5194745Y1020856D01*
X5193660Y1021273D01*
X5188855D01*
G01X5201410Y1014606D02*
Y1027106D01*
X5204510D01*
X5205750Y1026481D01*
X5206680Y1025648D01*
X5207455Y1024398D01*
X5208075Y1022939D01*
X5208230Y1020856D01*
X5208075Y1018773D01*
X5207455Y1017314D01*
X5206680Y1016064D01*
X5205750Y1015231D01*
X5204510Y1014606D01*
X5201410D01*
G01X5212570Y1010439D02*
X5221870D01*
G01X5226365Y1016272D02*
X5227605Y1015231D01*
X5229000Y1014606D01*
X5230240D01*
X5231480Y1015231D01*
X5232410Y1016272D01*
X5232875Y1017731D01*
X5232565Y1019189D01*
X5231790Y1020439D01*
X5230395Y1021273D01*
X5228535Y1021689D01*
X5227450Y1022523D01*
X5226985Y1023981D01*
X5227295Y1025439D01*
X5228070Y1026481D01*
X5229155Y1027106D01*
X5230240D01*
X5231325Y1026689D01*
X5232255Y1025648D01*
G01X5240160Y1027106D02*
X5243880D01*
G01X5242020D02*
Y1014606D01*
G01X5240160D02*
X5243880D01*
G01X5251475Y1027106D02*
X5257365D01*
X5251475Y1014606D01*
X5257365D01*
G01X5269920D02*
X5263720D01*
Y1027106D01*
X5269920D01*
G01X5267440Y1021064D02*
X5263720D01*
G01X5192660Y1335273D02*
X5193280Y1335898D01*
X5193745Y1336939D01*
X5194055Y1338398D01*
X5193745Y1339648D01*
X5193125Y1340481D01*
X5192040Y1341106D01*
X5187855D01*
Y1328606D01*
X5192970D01*
X5194055Y1329439D01*
X5194675Y1330689D01*
X5194985Y1332148D01*
X5194675Y1333606D01*
X5193745Y1334856D01*
X5192660Y1335273D01*
X5187855D01*
G01X5200410Y1328606D02*
Y1341106D01*
X5203510D01*
X5204750Y1340481D01*
X5205680Y1339648D01*
X5206455Y1338398D01*
X5207075Y1336939D01*
X5207230Y1334856D01*
X5207075Y1332773D01*
X5206455Y1331314D01*
X5205680Y1330064D01*
X5204750Y1329231D01*
X5203510Y1328606D01*
X5200410D01*
G01X5211570Y1324439D02*
X5220870D01*
G01X5225365Y1330272D02*
X5226605Y1329231D01*
X5228000Y1328606D01*
X5229240D01*
X5230480Y1329231D01*
X5231410Y1330272D01*
X5231875Y1331731D01*
X5231565Y1333189D01*
X5230790Y1334439D01*
X5229395Y1335273D01*
X5227535Y1335689D01*
X5226450Y1336523D01*
X5225985Y1337981D01*
X5226295Y1339439D01*
X5227070Y1340481D01*
X5228155Y1341106D01*
X5229240D01*
X5230325Y1340689D01*
X5231255Y1339648D01*
G01X5239160Y1341106D02*
X5242880D01*
G01X5241020D02*
Y1328606D01*
G01X5239160D02*
X5242880D01*
G01X5250475Y1341106D02*
X5256365D01*
X5250475Y1328606D01*
X5256365D01*
G01X5268920D02*
X5262720D01*
Y1341106D01*
X5268920D01*
G01X5266440Y1335064D02*
X5262720D01*
G01X5192660Y1650773D02*
X5193280Y1651398D01*
X5193745Y1652439D01*
X5194055Y1653898D01*
X5193745Y1655148D01*
X5193125Y1655981D01*
X5192040Y1656606D01*
X5187855D01*
Y1644106D01*
X5192970D01*
X5194055Y1644939D01*
X5194675Y1646189D01*
X5194985Y1647648D01*
X5194675Y1649106D01*
X5193745Y1650356D01*
X5192660Y1650773D01*
X5187855D01*
G01X5200410Y1644106D02*
Y1656606D01*
X5203510D01*
X5204750Y1655981D01*
X5205680Y1655148D01*
X5206455Y1653898D01*
X5207075Y1652439D01*
X5207230Y1650356D01*
X5207075Y1648273D01*
X5206455Y1646814D01*
X5205680Y1645564D01*
X5204750Y1644731D01*
X5203510Y1644106D01*
X5200410D01*
G01X5211570Y1639939D02*
X5220870D01*
G01X5225365Y1645772D02*
X5226605Y1644731D01*
X5228000Y1644106D01*
X5229240D01*
X5230480Y1644731D01*
X5231410Y1645772D01*
X5231875Y1647231D01*
X5231565Y1648689D01*
X5230790Y1649939D01*
X5229395Y1650773D01*
X5227535Y1651189D01*
X5226450Y1652023D01*
X5225985Y1653481D01*
X5226295Y1654939D01*
X5227070Y1655981D01*
X5228155Y1656606D01*
X5229240D01*
X5230325Y1656189D01*
X5231255Y1655148D01*
G01X5239160Y1656606D02*
X5242880D01*
G01X5241020D02*
Y1644106D01*
G01X5239160D02*
X5242880D01*
G01X5250475Y1656606D02*
X5256365D01*
X5250475Y1644106D01*
X5256365D01*
G01X5268920D02*
X5262720D01*
Y1656606D01*
X5268920D01*
G01X5266440Y1650564D02*
X5262720D01*
G01X5206464Y113116D02*
Y125616D01*
X5204604Y123116D01*
G01Y113116D02*
X5208324D01*
G01X5218554D02*
X5218864Y115824D01*
X5219329Y118116D01*
X5219949Y120199D01*
X5220724Y122491D01*
X5221964Y125616D01*
X5215764D01*
G01X5231264Y112699D02*
X5230954Y112908D01*
Y113324D01*
X5231264Y113533D01*
X5231574Y113324D01*
Y112908D01*
X5231264Y112699D01*
G01X5243664Y125616D02*
X5242424Y125199D01*
X5241494Y124158D01*
X5240874Y122908D01*
X5240409Y121241D01*
X5240254Y119366D01*
X5240409Y117491D01*
X5240874Y115824D01*
X5241494Y114574D01*
X5242424Y113533D01*
X5243664Y113116D01*
X5244904Y113533D01*
X5245834Y114574D01*
X5246454Y115824D01*
X5246919Y117491D01*
X5247074Y119366D01*
X5246919Y121241D01*
X5246454Y122908D01*
X5245834Y124158D01*
X5244904Y125199D01*
X5243664Y125616D01*
G01X5206464Y138116D02*
Y150616D01*
X5204604Y148116D01*
G01Y138116D02*
X5208324D01*
G01X5220724D02*
Y150616D01*
X5214989Y141658D01*
X5222739D01*
G01X5231264Y137699D02*
X5230954Y137908D01*
Y138324D01*
X5231264Y138533D01*
X5231574Y138324D01*
Y137908D01*
X5231264Y137699D01*
G01X5243664Y138116D02*
X5244749Y138324D01*
X5245989Y138949D01*
X5246764Y139991D01*
X5247074Y141449D01*
X5246764Y142907D01*
X5245834Y144158D01*
X5244439Y144783D01*
X5242889D01*
X5241959Y145199D01*
X5241184Y146241D01*
X5240874Y147699D01*
X5241339Y149158D01*
X5242424Y150199D01*
X5243664Y150616D01*
X5244904Y150199D01*
X5245989Y149158D01*
X5246454Y147699D01*
X5246144Y146241D01*
X5245369Y145199D01*
X5244439Y144783D01*
X5242889D01*
X5241494Y144158D01*
X5240564Y142907D01*
X5240254Y141449D01*
X5240564Y139991D01*
X5241339Y138949D01*
X5242579Y138324D01*
X5243664Y138116D01*
G01X5206430Y385935D02*
Y398435D01*
X5204570Y395935D01*
G01Y385935D02*
X5208290D01*
G01X5218520D02*
X5218830Y388643D01*
X5219295Y390935D01*
X5219915Y393018D01*
X5220690Y395310D01*
X5221930Y398435D01*
X5215730D01*
G01X5231230Y385518D02*
X5230920Y385727D01*
Y386143D01*
X5231230Y386352D01*
X5231540Y386143D01*
Y385727D01*
X5231230Y385518D01*
G01X5243630Y398435D02*
X5242390Y398018D01*
X5241460Y396977D01*
X5240840Y395727D01*
X5240375Y394060D01*
X5240220Y392185D01*
X5240375Y390310D01*
X5240840Y388643D01*
X5241460Y387393D01*
X5242390Y386352D01*
X5243630Y385935D01*
X5244870Y386352D01*
X5245800Y387393D01*
X5246420Y388643D01*
X5246885Y390310D01*
X5247040Y392185D01*
X5246885Y394060D01*
X5246420Y395727D01*
X5245800Y396977D01*
X5244870Y398018D01*
X5243630Y398435D01*
G01X5206430Y410935D02*
Y423435D01*
X5204570Y420935D01*
G01Y410935D02*
X5208290D01*
G01X5220690D02*
Y423435D01*
X5214955Y414477D01*
X5222705D01*
G01X5231230Y410518D02*
X5230920Y410727D01*
Y411143D01*
X5231230Y411352D01*
X5231540Y411143D01*
Y410727D01*
X5231230Y410518D01*
G01X5243630Y410935D02*
X5244715Y411143D01*
X5245955Y411768D01*
X5246730Y412810D01*
X5247040Y414268D01*
X5246730Y415726D01*
X5245800Y416977D01*
X5244405Y417602D01*
X5242855D01*
X5241925Y418018D01*
X5241150Y419060D01*
X5240840Y420518D01*
X5241305Y421977D01*
X5242390Y423018D01*
X5243630Y423435D01*
X5244870Y423018D01*
X5245955Y421977D01*
X5246420Y420518D01*
X5246110Y419060D01*
X5245335Y418018D01*
X5244405Y417602D01*
X5242855D01*
X5241460Y416977D01*
X5240530Y415726D01*
X5240220Y414268D01*
X5240530Y412810D01*
X5241305Y411768D01*
X5242545Y411143D01*
X5243630Y410935D01*
G01X5209020Y657106D02*
Y669606D01*
X5207160Y667106D01*
G01Y657106D02*
X5210880D01*
G01X5221110D02*
X5221420Y659814D01*
X5221885Y662106D01*
X5222505Y664189D01*
X5223280Y666481D01*
X5224520Y669606D01*
X5218320D01*
G01X5233820Y656689D02*
X5233510Y656898D01*
Y657314D01*
X5233820Y657523D01*
X5234130Y657314D01*
Y656898D01*
X5233820Y656689D01*
G01X5246220Y669606D02*
X5244980Y669189D01*
X5244050Y668148D01*
X5243430Y666898D01*
X5242965Y665231D01*
X5242810Y663356D01*
X5242965Y661481D01*
X5243430Y659814D01*
X5244050Y658564D01*
X5244980Y657523D01*
X5246220Y657106D01*
X5247460Y657523D01*
X5248390Y658564D01*
X5249010Y659814D01*
X5249475Y661481D01*
X5249630Y663356D01*
X5249475Y665231D01*
X5249010Y666898D01*
X5248390Y668148D01*
X5247460Y669189D01*
X5246220Y669606D01*
G01X5209020Y682106D02*
Y694606D01*
X5207160Y692106D01*
G01Y682106D02*
X5210880D01*
G01X5223280D02*
Y694606D01*
X5217545Y685648D01*
X5225295D01*
G01X5233820Y681689D02*
X5233510Y681898D01*
Y682314D01*
X5233820Y682523D01*
X5234130Y682314D01*
Y681898D01*
X5233820Y681689D01*
G01X5246220Y682106D02*
X5247305Y682314D01*
X5248545Y682939D01*
X5249320Y683981D01*
X5249630Y685439D01*
X5249320Y686897D01*
X5248390Y688148D01*
X5246995Y688773D01*
X5245445D01*
X5244515Y689189D01*
X5243740Y690231D01*
X5243430Y691689D01*
X5243895Y693148D01*
X5244980Y694189D01*
X5246220Y694606D01*
X5247460Y694189D01*
X5248545Y693148D01*
X5249010Y691689D01*
X5248700Y690231D01*
X5247925Y689189D01*
X5246995Y688773D01*
X5245445D01*
X5244050Y688148D01*
X5243120Y686897D01*
X5242810Y685439D01*
X5243120Y683981D01*
X5243895Y682939D01*
X5245135Y682314D01*
X5246220Y682106D01*
G01X5201875Y925023D02*
X5202805Y926272D01*
X5203890Y926898D01*
X5205130Y927106D01*
X5206680Y926689D01*
X5207765Y925648D01*
X5208075Y924398D01*
X5207920Y923147D01*
X5207300Y922106D01*
X5204200Y920023D01*
X5202805Y918564D01*
X5201875Y916481D01*
X5201565Y914606D01*
X5208075D01*
G01X5217220D02*
Y927106D01*
X5215360Y924606D01*
G01Y914606D02*
X5219080D01*
G01X5229620Y914189D02*
X5229310Y914398D01*
Y914814D01*
X5229620Y915023D01*
X5229930Y914814D01*
Y914398D01*
X5229620Y914189D01*
G01X5242020Y914606D02*
Y927106D01*
X5240160Y924606D01*
G01Y914606D02*
X5243880D01*
G01X5254110D02*
X5254420Y917314D01*
X5254885Y919606D01*
X5255505Y921689D01*
X5256280Y923981D01*
X5257520Y927106D01*
X5251320D01*
G01X5211020Y939606D02*
Y952106D01*
X5209160Y949606D01*
G01Y939606D02*
X5212880D01*
G01X5223110D02*
X5223420Y942314D01*
X5223885Y944606D01*
X5224505Y946689D01*
X5225280Y948981D01*
X5226520Y952106D01*
X5220320D01*
G01X5235820Y939189D02*
X5235510Y939398D01*
Y939814D01*
X5235820Y940023D01*
X5236130Y939814D01*
Y939398D01*
X5235820Y939189D01*
G01X5248220Y952106D02*
X5246980Y951689D01*
X5246050Y950648D01*
X5245430Y949398D01*
X5244965Y947731D01*
X5244810Y945856D01*
X5244965Y943981D01*
X5245430Y942314D01*
X5246050Y941064D01*
X5246980Y940023D01*
X5248220Y939606D01*
X5249460Y940023D01*
X5250390Y941064D01*
X5251010Y942314D01*
X5251475Y943981D01*
X5251630Y945856D01*
X5251475Y947731D01*
X5251010Y949398D01*
X5250390Y950648D01*
X5249460Y951689D01*
X5248220Y952106D01*
G01X5211020Y964606D02*
Y977106D01*
X5209160Y974606D01*
G01Y964606D02*
X5212880D01*
G01X5225280D02*
Y977106D01*
X5219545Y968148D01*
X5227295D01*
G01X5235820Y964189D02*
X5235510Y964398D01*
Y964814D01*
X5235820Y965023D01*
X5236130Y964814D01*
Y964398D01*
X5235820Y964189D01*
G01X5248220Y964606D02*
X5249305Y964814D01*
X5250545Y965439D01*
X5251320Y966481D01*
X5251630Y967939D01*
X5251320Y969397D01*
X5250390Y970648D01*
X5248995Y971273D01*
X5247445D01*
X5246515Y971689D01*
X5245740Y972731D01*
X5245430Y974189D01*
X5245895Y975648D01*
X5246980Y976689D01*
X5248220Y977106D01*
X5249460Y976689D01*
X5250545Y975648D01*
X5251010Y974189D01*
X5250700Y972731D01*
X5249925Y971689D01*
X5248995Y971273D01*
X5247445D01*
X5246050Y970648D01*
X5245120Y969397D01*
X5244810Y967939D01*
X5245120Y966481D01*
X5245895Y965439D01*
X5247135Y964814D01*
X5248220Y964606D01*
G01X5211020Y989606D02*
Y1002106D01*
X5209160Y999606D01*
G01Y989606D02*
X5212880D01*
G01X5225280D02*
Y1002106D01*
X5219545Y993148D01*
X5227295D01*
G01X5235820Y989189D02*
X5235510Y989398D01*
Y989814D01*
X5235820Y990023D01*
X5236130Y989814D01*
Y989398D01*
X5235820Y989189D01*
G01X5248220Y989606D02*
X5249305Y989814D01*
X5250545Y990439D01*
X5251320Y991481D01*
X5251630Y992939D01*
X5251320Y994397D01*
X5250390Y995648D01*
X5248995Y996273D01*
X5247445D01*
X5246515Y996689D01*
X5245740Y997731D01*
X5245430Y999189D01*
X5245895Y1000648D01*
X5246980Y1001689D01*
X5248220Y1002106D01*
X5249460Y1001689D01*
X5250545Y1000648D01*
X5251010Y999189D01*
X5250700Y997731D01*
X5249925Y996689D01*
X5248995Y996273D01*
X5247445D01*
X5246050Y995648D01*
X5245120Y994397D01*
X5244810Y992939D01*
X5245120Y991481D01*
X5245895Y990439D01*
X5247135Y989814D01*
X5248220Y989606D01*
G01X5200875Y1239023D02*
X5201805Y1240272D01*
X5202890Y1240898D01*
X5204130Y1241106D01*
X5205680Y1240689D01*
X5206765Y1239648D01*
X5207075Y1238398D01*
X5206920Y1237147D01*
X5206300Y1236106D01*
X5203200Y1234023D01*
X5201805Y1232564D01*
X5200875Y1230481D01*
X5200565Y1228606D01*
X5207075D01*
G01X5216220D02*
Y1241106D01*
X5214360Y1238606D01*
G01Y1228606D02*
X5218080D01*
G01X5228620Y1228189D02*
X5228310Y1228398D01*
Y1228814D01*
X5228620Y1229023D01*
X5228930Y1228814D01*
Y1228398D01*
X5228620Y1228189D01*
G01X5241020Y1228606D02*
Y1241106D01*
X5239160Y1238606D01*
G01Y1228606D02*
X5242880D01*
G01X5253110D02*
X5253420Y1231314D01*
X5253885Y1233606D01*
X5254505Y1235689D01*
X5255280Y1237981D01*
X5256520Y1241106D01*
X5250320D01*
G01X5210020Y1253606D02*
Y1266106D01*
X5208160Y1263606D01*
G01Y1253606D02*
X5211880D01*
G01X5222110D02*
X5222420Y1256314D01*
X5222885Y1258606D01*
X5223505Y1260689D01*
X5224280Y1262981D01*
X5225520Y1266106D01*
X5219320D01*
G01X5234820Y1253189D02*
X5234510Y1253398D01*
Y1253814D01*
X5234820Y1254023D01*
X5235130Y1253814D01*
Y1253398D01*
X5234820Y1253189D01*
G01X5247220Y1266106D02*
X5245980Y1265689D01*
X5245050Y1264648D01*
X5244430Y1263398D01*
X5243965Y1261731D01*
X5243810Y1259856D01*
X5243965Y1257981D01*
X5244430Y1256314D01*
X5245050Y1255064D01*
X5245980Y1254023D01*
X5247220Y1253606D01*
X5248460Y1254023D01*
X5249390Y1255064D01*
X5250010Y1256314D01*
X5250475Y1257981D01*
X5250630Y1259856D01*
X5250475Y1261731D01*
X5250010Y1263398D01*
X5249390Y1264648D01*
X5248460Y1265689D01*
X5247220Y1266106D01*
G01X5210020Y1278606D02*
Y1291106D01*
X5208160Y1288606D01*
G01Y1278606D02*
X5211880D01*
G01X5224280D02*
Y1291106D01*
X5218545Y1282148D01*
X5226295D01*
G01X5234820Y1278189D02*
X5234510Y1278398D01*
Y1278814D01*
X5234820Y1279023D01*
X5235130Y1278814D01*
Y1278398D01*
X5234820Y1278189D01*
G01X5247220Y1278606D02*
X5248305Y1278814D01*
X5249545Y1279439D01*
X5250320Y1280481D01*
X5250630Y1281939D01*
X5250320Y1283397D01*
X5249390Y1284648D01*
X5247995Y1285273D01*
X5246445D01*
X5245515Y1285689D01*
X5244740Y1286731D01*
X5244430Y1288189D01*
X5244895Y1289648D01*
X5245980Y1290689D01*
X5247220Y1291106D01*
X5248460Y1290689D01*
X5249545Y1289648D01*
X5250010Y1288189D01*
X5249700Y1286731D01*
X5248925Y1285689D01*
X5247995Y1285273D01*
X5246445D01*
X5245050Y1284648D01*
X5244120Y1283397D01*
X5243810Y1281939D01*
X5244120Y1280481D01*
X5244895Y1279439D01*
X5246135Y1278814D01*
X5247220Y1278606D01*
G01X5210020Y1303606D02*
Y1316106D01*
X5208160Y1313606D01*
G01Y1303606D02*
X5211880D01*
G01X5224280D02*
Y1316106D01*
X5218545Y1307148D01*
X5226295D01*
G01X5234820Y1303189D02*
X5234510Y1303398D01*
Y1303814D01*
X5234820Y1304023D01*
X5235130Y1303814D01*
Y1303398D01*
X5234820Y1303189D01*
G01X5247220Y1303606D02*
X5248305Y1303814D01*
X5249545Y1304439D01*
X5250320Y1305481D01*
X5250630Y1306939D01*
X5250320Y1308397D01*
X5249390Y1309648D01*
X5247995Y1310273D01*
X5246445D01*
X5245515Y1310689D01*
X5244740Y1311731D01*
X5244430Y1313189D01*
X5244895Y1314648D01*
X5245980Y1315689D01*
X5247220Y1316106D01*
X5248460Y1315689D01*
X5249545Y1314648D01*
X5250010Y1313189D01*
X5249700Y1311731D01*
X5248925Y1310689D01*
X5247995Y1310273D01*
X5246445D01*
X5245050Y1309648D01*
X5244120Y1308397D01*
X5243810Y1306939D01*
X5244120Y1305481D01*
X5244895Y1304439D01*
X5246135Y1303814D01*
X5247220Y1303606D01*
G01X5200875Y1554523D02*
X5201805Y1555772D01*
X5202890Y1556398D01*
X5204130Y1556606D01*
X5205680Y1556189D01*
X5206765Y1555148D01*
X5207075Y1553898D01*
X5206920Y1552647D01*
X5206300Y1551606D01*
X5203200Y1549523D01*
X5201805Y1548064D01*
X5200875Y1545981D01*
X5200565Y1544106D01*
X5207075D01*
G01X5216220D02*
Y1556606D01*
X5214360Y1554106D01*
G01Y1544106D02*
X5218080D01*
G01X5228620Y1543689D02*
X5228310Y1543898D01*
Y1544314D01*
X5228620Y1544523D01*
X5228930Y1544314D01*
Y1543898D01*
X5228620Y1543689D01*
G01X5241020Y1544106D02*
Y1556606D01*
X5239160Y1554106D01*
G01Y1544106D02*
X5242880D01*
G01X5253110D02*
X5253420Y1546814D01*
X5253885Y1549106D01*
X5254505Y1551189D01*
X5255280Y1553481D01*
X5256520Y1556606D01*
X5250320D01*
G01X5210020Y1569106D02*
Y1581606D01*
X5208160Y1579106D01*
G01Y1569106D02*
X5211880D01*
G01X5222110D02*
X5222420Y1571814D01*
X5222885Y1574106D01*
X5223505Y1576189D01*
X5224280Y1578481D01*
X5225520Y1581606D01*
X5219320D01*
G01X5234820Y1568689D02*
X5234510Y1568898D01*
Y1569314D01*
X5234820Y1569523D01*
X5235130Y1569314D01*
Y1568898D01*
X5234820Y1568689D01*
G01X5247220Y1581606D02*
X5245980Y1581189D01*
X5245050Y1580148D01*
X5244430Y1578898D01*
X5243965Y1577231D01*
X5243810Y1575356D01*
X5243965Y1573481D01*
X5244430Y1571814D01*
X5245050Y1570564D01*
X5245980Y1569523D01*
X5247220Y1569106D01*
X5248460Y1569523D01*
X5249390Y1570564D01*
X5250010Y1571814D01*
X5250475Y1573481D01*
X5250630Y1575356D01*
X5250475Y1577231D01*
X5250010Y1578898D01*
X5249390Y1580148D01*
X5248460Y1581189D01*
X5247220Y1581606D01*
G01X5210020Y1594106D02*
Y1606606D01*
X5208160Y1604106D01*
G01Y1594106D02*
X5211880D01*
G01X5224280D02*
Y1606606D01*
X5218545Y1597648D01*
X5226295D01*
G01X5234820Y1593689D02*
X5234510Y1593898D01*
Y1594314D01*
X5234820Y1594523D01*
X5235130Y1594314D01*
Y1593898D01*
X5234820Y1593689D01*
G01X5247220Y1594106D02*
X5248305Y1594314D01*
X5249545Y1594939D01*
X5250320Y1595981D01*
X5250630Y1597439D01*
X5250320Y1598897D01*
X5249390Y1600148D01*
X5247995Y1600773D01*
X5246445D01*
X5245515Y1601189D01*
X5244740Y1602231D01*
X5244430Y1603689D01*
X5244895Y1605148D01*
X5245980Y1606189D01*
X5247220Y1606606D01*
X5248460Y1606189D01*
X5249545Y1605148D01*
X5250010Y1603689D01*
X5249700Y1602231D01*
X5248925Y1601189D01*
X5247995Y1600773D01*
X5246445D01*
X5245050Y1600148D01*
X5244120Y1598897D01*
X5243810Y1597439D01*
X5244120Y1595981D01*
X5244895Y1594939D01*
X5246135Y1594314D01*
X5247220Y1594106D01*
G01X5210020Y1619106D02*
Y1631606D01*
X5208160Y1629106D01*
G01Y1619106D02*
X5211880D01*
G01X5224280D02*
Y1631606D01*
X5218545Y1622648D01*
X5226295D01*
G01X5234820Y1618689D02*
X5234510Y1618898D01*
Y1619314D01*
X5234820Y1619523D01*
X5235130Y1619314D01*
Y1618898D01*
X5234820Y1618689D01*
G01X5247220Y1619106D02*
X5248305Y1619314D01*
X5249545Y1619939D01*
X5250320Y1620981D01*
X5250630Y1622439D01*
X5250320Y1623897D01*
X5249390Y1625148D01*
X5247995Y1625773D01*
X5246445D01*
X5245515Y1626189D01*
X5244740Y1627231D01*
X5244430Y1628689D01*
X5244895Y1630148D01*
X5245980Y1631189D01*
X5247220Y1631606D01*
X5248460Y1631189D01*
X5249545Y1630148D01*
X5250010Y1628689D01*
X5249700Y1627231D01*
X5248925Y1626189D01*
X5247995Y1625773D01*
X5246445D01*
X5245050Y1625148D01*
X5244120Y1623897D01*
X5243810Y1622439D01*
X5244120Y1620981D01*
X5244895Y1619939D01*
X5246135Y1619314D01*
X5247220Y1619106D01*
G01X5299154Y219783D02*
X5299774Y220408D01*
X5300239Y221449D01*
X5300549Y222908D01*
X5300239Y224158D01*
X5299619Y224991D01*
X5298534Y225616D01*
X5294349D01*
Y213116D01*
X5299464D01*
X5300549Y213949D01*
X5301169Y215199D01*
X5301479Y216658D01*
X5301169Y218116D01*
X5300239Y219366D01*
X5299154Y219783D01*
X5294349D01*
G01X5306439Y213116D02*
X5310314Y225616D01*
X5314189Y213116D01*
G01X5312794Y217491D02*
X5307834D01*
G01X5326124Y224574D02*
X5325194Y225199D01*
X5324109Y225616D01*
X5322869D01*
X5321474Y224991D01*
X5320389Y223949D01*
X5319614Y222699D01*
X5318994Y220616D01*
X5318839Y218741D01*
X5319149Y216866D01*
X5319614Y215616D01*
X5320544Y214366D01*
X5321629Y213533D01*
X5322714Y213116D01*
X5323799D01*
X5324884Y213533D01*
X5325814Y214157D01*
X5326589Y214991D01*
G01X5331704Y213116D02*
Y225616D01*
G01X5337594D02*
X5331704Y217907D01*
G01X5338524Y213116D02*
X5334339Y221449D01*
G01X5344104Y213116D02*
Y225616D01*
X5347204D01*
X5348444Y224991D01*
X5349374Y224158D01*
X5350149Y222908D01*
X5350769Y221449D01*
X5350924Y219366D01*
X5350769Y217283D01*
X5350149Y215824D01*
X5349374Y214574D01*
X5348444Y213741D01*
X5347204Y213116D01*
X5344104D01*
G01X5356814D02*
Y225616D01*
X5360689D01*
X5361929Y224991D01*
X5362704Y224158D01*
X5363014Y222491D01*
X5362704Y220824D01*
X5361774Y219783D01*
X5360689Y219158D01*
X5356814D01*
G01X5360689D02*
X5363014Y213116D01*
G01X5370454Y225616D02*
X5374174D01*
G01X5372314D02*
Y213116D01*
G01X5370454D02*
X5374174D01*
G01X5381614Y225616D02*
Y213116D01*
X5387814D01*
G01X5394014Y225616D02*
Y213116D01*
X5400214D01*
G01X5409514Y212699D02*
X5409204Y212908D01*
Y213324D01*
X5409514Y213533D01*
X5409824Y213324D01*
Y212908D01*
X5409514Y212699D01*
G01Y218324D02*
X5409204Y218533D01*
Y218949D01*
X5409514Y219158D01*
X5409824Y218949D01*
Y218533D01*
X5409514Y218324D01*
G01X5435554Y219783D02*
X5436174Y220408D01*
X5436639Y221449D01*
X5436949Y222908D01*
X5436639Y224158D01*
X5436019Y224991D01*
X5434934Y225616D01*
X5430749D01*
Y213116D01*
X5435864D01*
X5436949Y213949D01*
X5437569Y215199D01*
X5437879Y216658D01*
X5437569Y218116D01*
X5436639Y219366D01*
X5435554Y219783D01*
X5430749D01*
G01X5446714Y213116D02*
X5445474Y213324D01*
X5444389Y214157D01*
X5443459Y215408D01*
X5442839Y216866D01*
X5442529Y218533D01*
Y220199D01*
X5442839Y221866D01*
X5443459Y223324D01*
X5444389Y224574D01*
X5445474Y225408D01*
X5446714Y225616D01*
X5447954Y225408D01*
X5449039Y224574D01*
X5449969Y223324D01*
X5450589Y221866D01*
X5450899Y220199D01*
Y218533D01*
X5450589Y216866D01*
X5449969Y215408D01*
X5449039Y214157D01*
X5447954Y213324D01*
X5446714Y213116D01*
G01X5459114Y225616D02*
Y213116D01*
G01X5455549Y225616D02*
X5462679D01*
G01X5471514D02*
Y213116D01*
G01X5467949Y225616D02*
X5475079D01*
G01X5483914Y213116D02*
X5482674Y213324D01*
X5481589Y214157D01*
X5480659Y215408D01*
X5480039Y216866D01*
X5479729Y218533D01*
Y220199D01*
X5480039Y221866D01*
X5480659Y223324D01*
X5481589Y224574D01*
X5482674Y225408D01*
X5483914Y225616D01*
X5485154Y225408D01*
X5486239Y224574D01*
X5487169Y223324D01*
X5487789Y221866D01*
X5488099Y220199D01*
Y218533D01*
X5487789Y216866D01*
X5487169Y215408D01*
X5486239Y214157D01*
X5485154Y213324D01*
X5483914Y213116D01*
G01X5492284D02*
Y225616D01*
X5496314Y215199D01*
X5500344Y225616D01*
Y213116D01*
G01X5521114Y225616D02*
Y213116D01*
G01X5518944Y221449D02*
X5523284D01*
G01X5533514Y213116D02*
X5532584Y213324D01*
X5531654Y214157D01*
X5531034Y215616D01*
X5530724Y217283D01*
X5531034Y218949D01*
X5531654Y220408D01*
X5532584Y221241D01*
X5533514Y221449D01*
X5534444Y221241D01*
X5535374Y220408D01*
X5535994Y218949D01*
X5536149Y217283D01*
X5535994Y215616D01*
X5535374Y214157D01*
X5534444Y213324D01*
X5533514Y213116D01*
G01X5559244Y219366D02*
X5562344D01*
Y215616D01*
X5561414Y214366D01*
X5560329Y213533D01*
X5558779Y213116D01*
X5557229Y213533D01*
X5556144Y214366D01*
X5555214Y215616D01*
X5554594Y217074D01*
X5554284Y218741D01*
Y220199D01*
X5554594Y221449D01*
X5555214Y222908D01*
X5556144Y224158D01*
X5557074Y224991D01*
X5558314Y225616D01*
X5559399D01*
X5560639Y225199D01*
X5561569Y224366D01*
G01X5567149Y213116D02*
Y225616D01*
X5574279Y213116D01*
Y225616D01*
G01X5579704Y213116D02*
Y225616D01*
X5582804D01*
X5584044Y224991D01*
X5584974Y224158D01*
X5585749Y222908D01*
X5586369Y221449D01*
X5586524Y219366D01*
X5586369Y217283D01*
X5585749Y215824D01*
X5584974Y214574D01*
X5584044Y213741D01*
X5582804Y213116D01*
X5579704D01*
G01X5595514D02*
Y225616D01*
X5593654Y223116D01*
G01Y213116D02*
X5597374D01*
G01X5299120Y492602D02*
X5299740Y493227D01*
X5300205Y494268D01*
X5300515Y495727D01*
X5300205Y496977D01*
X5299585Y497810D01*
X5298500Y498435D01*
X5294315D01*
Y485935D01*
X5299430D01*
X5300515Y486768D01*
X5301135Y488018D01*
X5301445Y489477D01*
X5301135Y490935D01*
X5300205Y492185D01*
X5299120Y492602D01*
X5294315D01*
G01X5306405Y485935D02*
X5310280Y498435D01*
X5314155Y485935D01*
G01X5312760Y490310D02*
X5307800D01*
G01X5326090Y497393D02*
X5325160Y498018D01*
X5324075Y498435D01*
X5322835D01*
X5321440Y497810D01*
X5320355Y496768D01*
X5319580Y495518D01*
X5318960Y493435D01*
X5318805Y491560D01*
X5319115Y489685D01*
X5319580Y488435D01*
X5320510Y487185D01*
X5321595Y486352D01*
X5322680Y485935D01*
X5323765D01*
X5324850Y486352D01*
X5325780Y486976D01*
X5326555Y487810D01*
G01X5331670Y485935D02*
Y498435D01*
G01X5337560D02*
X5331670Y490726D01*
G01X5338490Y485935D02*
X5334305Y494268D01*
G01X5344070Y485935D02*
Y498435D01*
X5347170D01*
X5348410Y497810D01*
X5349340Y496977D01*
X5350115Y495727D01*
X5350735Y494268D01*
X5350890Y492185D01*
X5350735Y490102D01*
X5350115Y488643D01*
X5349340Y487393D01*
X5348410Y486560D01*
X5347170Y485935D01*
X5344070D01*
G01X5356780D02*
Y498435D01*
X5360655D01*
X5361895Y497810D01*
X5362670Y496977D01*
X5362980Y495310D01*
X5362670Y493643D01*
X5361740Y492602D01*
X5360655Y491977D01*
X5356780D01*
G01X5360655D02*
X5362980Y485935D01*
G01X5370420Y498435D02*
X5374140D01*
G01X5372280D02*
Y485935D01*
G01X5370420D02*
X5374140D01*
G01X5381580Y498435D02*
Y485935D01*
X5387780D01*
G01X5393980Y498435D02*
Y485935D01*
X5400180D01*
G01X5409480Y485518D02*
X5409170Y485727D01*
Y486143D01*
X5409480Y486352D01*
X5409790Y486143D01*
Y485727D01*
X5409480Y485518D01*
G01Y491143D02*
X5409170Y491352D01*
Y491768D01*
X5409480Y491977D01*
X5409790Y491768D01*
Y491352D01*
X5409480Y491143D01*
G01X5435520Y492602D02*
X5436140Y493227D01*
X5436605Y494268D01*
X5436915Y495727D01*
X5436605Y496977D01*
X5435985Y497810D01*
X5434900Y498435D01*
X5430715D01*
Y485935D01*
X5435830D01*
X5436915Y486768D01*
X5437535Y488018D01*
X5437845Y489477D01*
X5437535Y490935D01*
X5436605Y492185D01*
X5435520Y492602D01*
X5430715D01*
G01X5446680Y485935D02*
X5445440Y486143D01*
X5444355Y486976D01*
X5443425Y488227D01*
X5442805Y489685D01*
X5442495Y491352D01*
Y493018D01*
X5442805Y494685D01*
X5443425Y496143D01*
X5444355Y497393D01*
X5445440Y498227D01*
X5446680Y498435D01*
X5447920Y498227D01*
X5449005Y497393D01*
X5449935Y496143D01*
X5450555Y494685D01*
X5450865Y493018D01*
Y491352D01*
X5450555Y489685D01*
X5449935Y488227D01*
X5449005Y486976D01*
X5447920Y486143D01*
X5446680Y485935D01*
G01X5459080Y498435D02*
Y485935D01*
G01X5455515Y498435D02*
X5462645D01*
G01X5471480D02*
Y485935D01*
G01X5467915Y498435D02*
X5475045D01*
G01X5483880Y485935D02*
X5482640Y486143D01*
X5481555Y486976D01*
X5480625Y488227D01*
X5480005Y489685D01*
X5479695Y491352D01*
Y493018D01*
X5480005Y494685D01*
X5480625Y496143D01*
X5481555Y497393D01*
X5482640Y498227D01*
X5483880Y498435D01*
X5485120Y498227D01*
X5486205Y497393D01*
X5487135Y496143D01*
X5487755Y494685D01*
X5488065Y493018D01*
Y491352D01*
X5487755Y489685D01*
X5487135Y488227D01*
X5486205Y486976D01*
X5485120Y486143D01*
X5483880Y485935D01*
G01X5492250D02*
Y498435D01*
X5496280Y488018D01*
X5500310Y498435D01*
Y485935D01*
G01X5521080Y498435D02*
Y485935D01*
G01X5518910Y494268D02*
X5523250D01*
G01X5533480Y485935D02*
X5532550Y486143D01*
X5531620Y486976D01*
X5531000Y488435D01*
X5530690Y490102D01*
X5531000Y491768D01*
X5531620Y493227D01*
X5532550Y494060D01*
X5533480Y494268D01*
X5534410Y494060D01*
X5535340Y493227D01*
X5535960Y491768D01*
X5536115Y490102D01*
X5535960Y488435D01*
X5535340Y486976D01*
X5534410Y486143D01*
X5533480Y485935D01*
G01X5559210Y492185D02*
X5562310D01*
Y488435D01*
X5561380Y487185D01*
X5560295Y486352D01*
X5558745Y485935D01*
X5557195Y486352D01*
X5556110Y487185D01*
X5555180Y488435D01*
X5554560Y489893D01*
X5554250Y491560D01*
Y493018D01*
X5554560Y494268D01*
X5555180Y495727D01*
X5556110Y496977D01*
X5557040Y497810D01*
X5558280Y498435D01*
X5559365D01*
X5560605Y498018D01*
X5561535Y497185D01*
G01X5567115Y485935D02*
Y498435D01*
X5574245Y485935D01*
Y498435D01*
G01X5579670Y485935D02*
Y498435D01*
X5582770D01*
X5584010Y497810D01*
X5584940Y496977D01*
X5585715Y495727D01*
X5586335Y494268D01*
X5586490Y492185D01*
X5586335Y490102D01*
X5585715Y488643D01*
X5584940Y487393D01*
X5584010Y486560D01*
X5582770Y485935D01*
X5579670D01*
G01X5592535Y496352D02*
X5593465Y497601D01*
X5594550Y498227D01*
X5595790Y498435D01*
X5597340Y498018D01*
X5598425Y496977D01*
X5598735Y495727D01*
X5598580Y494476D01*
X5597960Y493435D01*
X5594860Y491352D01*
X5593465Y489893D01*
X5592535Y487810D01*
X5592225Y485935D01*
X5598735D01*
G01X5301710Y763773D02*
X5302330Y764398D01*
X5302795Y765439D01*
X5303105Y766898D01*
X5302795Y768148D01*
X5302175Y768981D01*
X5301090Y769606D01*
X5296905D01*
Y757106D01*
X5302020D01*
X5303105Y757939D01*
X5303725Y759189D01*
X5304035Y760648D01*
X5303725Y762106D01*
X5302795Y763356D01*
X5301710Y763773D01*
X5296905D01*
G01X5308995Y757106D02*
X5312870Y769606D01*
X5316745Y757106D01*
G01X5315350Y761481D02*
X5310390D01*
G01X5328680Y768564D02*
X5327750Y769189D01*
X5326665Y769606D01*
X5325425D01*
X5324030Y768981D01*
X5322945Y767939D01*
X5322170Y766689D01*
X5321550Y764606D01*
X5321395Y762731D01*
X5321705Y760856D01*
X5322170Y759606D01*
X5323100Y758356D01*
X5324185Y757523D01*
X5325270Y757106D01*
X5326355D01*
X5327440Y757523D01*
X5328370Y758147D01*
X5329145Y758981D01*
G01X5334260Y757106D02*
Y769606D01*
G01X5340150D02*
X5334260Y761897D01*
G01X5341080Y757106D02*
X5336895Y765439D01*
G01X5346660Y757106D02*
Y769606D01*
X5349760D01*
X5351000Y768981D01*
X5351930Y768148D01*
X5352705Y766898D01*
X5353325Y765439D01*
X5353480Y763356D01*
X5353325Y761273D01*
X5352705Y759814D01*
X5351930Y758564D01*
X5351000Y757731D01*
X5349760Y757106D01*
X5346660D01*
G01X5359370D02*
Y769606D01*
X5363245D01*
X5364485Y768981D01*
X5365260Y768148D01*
X5365570Y766481D01*
X5365260Y764814D01*
X5364330Y763773D01*
X5363245Y763148D01*
X5359370D01*
G01X5363245D02*
X5365570Y757106D01*
G01X5373010Y769606D02*
X5376730D01*
G01X5374870D02*
Y757106D01*
G01X5373010D02*
X5376730D01*
G01X5384170Y769606D02*
Y757106D01*
X5390370D01*
G01X5396570Y769606D02*
Y757106D01*
X5402770D01*
G01X5412070Y756689D02*
X5411760Y756898D01*
Y757314D01*
X5412070Y757523D01*
X5412380Y757314D01*
Y756898D01*
X5412070Y756689D01*
G01Y762314D02*
X5411760Y762523D01*
Y762939D01*
X5412070Y763148D01*
X5412380Y762939D01*
Y762523D01*
X5412070Y762314D01*
G01X5438110Y763773D02*
X5438730Y764398D01*
X5439195Y765439D01*
X5439505Y766898D01*
X5439195Y768148D01*
X5438575Y768981D01*
X5437490Y769606D01*
X5433305D01*
Y757106D01*
X5438420D01*
X5439505Y757939D01*
X5440125Y759189D01*
X5440435Y760648D01*
X5440125Y762106D01*
X5439195Y763356D01*
X5438110Y763773D01*
X5433305D01*
G01X5449270Y757106D02*
X5448030Y757314D01*
X5446945Y758147D01*
X5446015Y759398D01*
X5445395Y760856D01*
X5445085Y762523D01*
Y764189D01*
X5445395Y765856D01*
X5446015Y767314D01*
X5446945Y768564D01*
X5448030Y769398D01*
X5449270Y769606D01*
X5450510Y769398D01*
X5451595Y768564D01*
X5452525Y767314D01*
X5453145Y765856D01*
X5453455Y764189D01*
Y762523D01*
X5453145Y760856D01*
X5452525Y759398D01*
X5451595Y758147D01*
X5450510Y757314D01*
X5449270Y757106D01*
G01X5461670Y769606D02*
Y757106D01*
G01X5458105Y769606D02*
X5465235D01*
G01X5474070D02*
Y757106D01*
G01X5470505Y769606D02*
X5477635D01*
G01X5486470Y757106D02*
X5485230Y757314D01*
X5484145Y758147D01*
X5483215Y759398D01*
X5482595Y760856D01*
X5482285Y762523D01*
Y764189D01*
X5482595Y765856D01*
X5483215Y767314D01*
X5484145Y768564D01*
X5485230Y769398D01*
X5486470Y769606D01*
X5487710Y769398D01*
X5488795Y768564D01*
X5489725Y767314D01*
X5490345Y765856D01*
X5490655Y764189D01*
Y762523D01*
X5490345Y760856D01*
X5489725Y759398D01*
X5488795Y758147D01*
X5487710Y757314D01*
X5486470Y757106D01*
G01X5494840D02*
Y769606D01*
X5498870Y759189D01*
X5502900Y769606D01*
Y757106D01*
G01X5523670Y769606D02*
Y757106D01*
G01X5521500Y765439D02*
X5525840D01*
G01X5536070Y757106D02*
X5535140Y757314D01*
X5534210Y758147D01*
X5533590Y759606D01*
X5533280Y761273D01*
X5533590Y762939D01*
X5534210Y764398D01*
X5535140Y765231D01*
X5536070Y765439D01*
X5537000Y765231D01*
X5537930Y764398D01*
X5538550Y762939D01*
X5538705Y761273D01*
X5538550Y759606D01*
X5537930Y758147D01*
X5537000Y757314D01*
X5536070Y757106D01*
G01X5561800Y763356D02*
X5564900D01*
Y759606D01*
X5563970Y758356D01*
X5562885Y757523D01*
X5561335Y757106D01*
X5559785Y757523D01*
X5558700Y758356D01*
X5557770Y759606D01*
X5557150Y761064D01*
X5556840Y762731D01*
Y764189D01*
X5557150Y765439D01*
X5557770Y766898D01*
X5558700Y768148D01*
X5559630Y768981D01*
X5560870Y769606D01*
X5561955D01*
X5563195Y769189D01*
X5564125Y768356D01*
G01X5569705Y757106D02*
Y769606D01*
X5576835Y757106D01*
Y769606D01*
G01X5582260Y757106D02*
Y769606D01*
X5585360D01*
X5586600Y768981D01*
X5587530Y768148D01*
X5588305Y766898D01*
X5588925Y765439D01*
X5589080Y763356D01*
X5588925Y761273D01*
X5588305Y759814D01*
X5587530Y758564D01*
X5586600Y757731D01*
X5585360Y757106D01*
X5582260D01*
G01X5594660Y759606D02*
X5595590Y758147D01*
X5596830Y757314D01*
X5598225Y757106D01*
X5599465Y757314D01*
X5600705Y758356D01*
X5601480Y759606D01*
X5601635Y760856D01*
X5601325Y762314D01*
X5600240Y763356D01*
X5599155Y763773D01*
X5597760D01*
G01X5599155D02*
X5600085Y764398D01*
X5600860Y765439D01*
X5601170Y766689D01*
X5600860Y767939D01*
X5600085Y768981D01*
X5598690Y769606D01*
X5597295Y769398D01*
X5595900Y768564D01*
G01X5303710Y1071273D02*
X5304330Y1071898D01*
X5304795Y1072939D01*
X5305105Y1074398D01*
X5304795Y1075648D01*
X5304175Y1076481D01*
X5303090Y1077106D01*
X5298905D01*
Y1064606D01*
X5304020D01*
X5305105Y1065439D01*
X5305725Y1066689D01*
X5306035Y1068148D01*
X5305725Y1069606D01*
X5304795Y1070856D01*
X5303710Y1071273D01*
X5298905D01*
G01X5310995Y1064606D02*
X5314870Y1077106D01*
X5318745Y1064606D01*
G01X5317350Y1068981D02*
X5312390D01*
G01X5330680Y1076064D02*
X5329750Y1076689D01*
X5328665Y1077106D01*
X5327425D01*
X5326030Y1076481D01*
X5324945Y1075439D01*
X5324170Y1074189D01*
X5323550Y1072106D01*
X5323395Y1070231D01*
X5323705Y1068356D01*
X5324170Y1067106D01*
X5325100Y1065856D01*
X5326185Y1065023D01*
X5327270Y1064606D01*
X5328355D01*
X5329440Y1065023D01*
X5330370Y1065647D01*
X5331145Y1066481D01*
G01X5336260Y1064606D02*
Y1077106D01*
G01X5342150D02*
X5336260Y1069397D01*
G01X5343080Y1064606D02*
X5338895Y1072939D01*
G01X5348660Y1064606D02*
Y1077106D01*
X5351760D01*
X5353000Y1076481D01*
X5353930Y1075648D01*
X5354705Y1074398D01*
X5355325Y1072939D01*
X5355480Y1070856D01*
X5355325Y1068773D01*
X5354705Y1067314D01*
X5353930Y1066064D01*
X5353000Y1065231D01*
X5351760Y1064606D01*
X5348660D01*
G01X5361370D02*
Y1077106D01*
X5365245D01*
X5366485Y1076481D01*
X5367260Y1075648D01*
X5367570Y1073981D01*
X5367260Y1072314D01*
X5366330Y1071273D01*
X5365245Y1070648D01*
X5361370D01*
G01X5365245D02*
X5367570Y1064606D01*
G01X5375010Y1077106D02*
X5378730D01*
G01X5376870D02*
Y1064606D01*
G01X5375010D02*
X5378730D01*
G01X5386170Y1077106D02*
Y1064606D01*
X5392370D01*
G01X5398570Y1077106D02*
Y1064606D01*
X5404770D01*
G01X5414070Y1064189D02*
X5413760Y1064398D01*
Y1064814D01*
X5414070Y1065023D01*
X5414380Y1064814D01*
Y1064398D01*
X5414070Y1064189D01*
G01Y1069814D02*
X5413760Y1070023D01*
Y1070439D01*
X5414070Y1070648D01*
X5414380Y1070439D01*
Y1070023D01*
X5414070Y1069814D01*
G01X5440110Y1071273D02*
X5440730Y1071898D01*
X5441195Y1072939D01*
X5441505Y1074398D01*
X5441195Y1075648D01*
X5440575Y1076481D01*
X5439490Y1077106D01*
X5435305D01*
Y1064606D01*
X5440420D01*
X5441505Y1065439D01*
X5442125Y1066689D01*
X5442435Y1068148D01*
X5442125Y1069606D01*
X5441195Y1070856D01*
X5440110Y1071273D01*
X5435305D01*
G01X5451270Y1064606D02*
X5450030Y1064814D01*
X5448945Y1065647D01*
X5448015Y1066898D01*
X5447395Y1068356D01*
X5447085Y1070023D01*
Y1071689D01*
X5447395Y1073356D01*
X5448015Y1074814D01*
X5448945Y1076064D01*
X5450030Y1076898D01*
X5451270Y1077106D01*
X5452510Y1076898D01*
X5453595Y1076064D01*
X5454525Y1074814D01*
X5455145Y1073356D01*
X5455455Y1071689D01*
Y1070023D01*
X5455145Y1068356D01*
X5454525Y1066898D01*
X5453595Y1065647D01*
X5452510Y1064814D01*
X5451270Y1064606D01*
G01X5463670Y1077106D02*
Y1064606D01*
G01X5460105Y1077106D02*
X5467235D01*
G01X5476070D02*
Y1064606D01*
G01X5472505Y1077106D02*
X5479635D01*
G01X5488470Y1064606D02*
X5487230Y1064814D01*
X5486145Y1065647D01*
X5485215Y1066898D01*
X5484595Y1068356D01*
X5484285Y1070023D01*
Y1071689D01*
X5484595Y1073356D01*
X5485215Y1074814D01*
X5486145Y1076064D01*
X5487230Y1076898D01*
X5488470Y1077106D01*
X5489710Y1076898D01*
X5490795Y1076064D01*
X5491725Y1074814D01*
X5492345Y1073356D01*
X5492655Y1071689D01*
Y1070023D01*
X5492345Y1068356D01*
X5491725Y1066898D01*
X5490795Y1065647D01*
X5489710Y1064814D01*
X5488470Y1064606D01*
G01X5496840D02*
Y1077106D01*
X5500870Y1066689D01*
X5504900Y1077106D01*
Y1064606D01*
G01X5525670Y1077106D02*
Y1064606D01*
G01X5523500Y1072939D02*
X5527840D01*
G01X5538070Y1064606D02*
X5537140Y1064814D01*
X5536210Y1065647D01*
X5535590Y1067106D01*
X5535280Y1068773D01*
X5535590Y1070439D01*
X5536210Y1071898D01*
X5537140Y1072731D01*
X5538070Y1072939D01*
X5539000Y1072731D01*
X5539930Y1071898D01*
X5540550Y1070439D01*
X5540705Y1068773D01*
X5540550Y1067106D01*
X5539930Y1065647D01*
X5539000Y1064814D01*
X5538070Y1064606D01*
G01X5563800Y1070856D02*
X5566900D01*
Y1067106D01*
X5565970Y1065856D01*
X5564885Y1065023D01*
X5563335Y1064606D01*
X5561785Y1065023D01*
X5560700Y1065856D01*
X5559770Y1067106D01*
X5559150Y1068564D01*
X5558840Y1070231D01*
Y1071689D01*
X5559150Y1072939D01*
X5559770Y1074398D01*
X5560700Y1075648D01*
X5561630Y1076481D01*
X5562870Y1077106D01*
X5563955D01*
X5565195Y1076689D01*
X5566125Y1075856D01*
G01X5571705Y1064606D02*
Y1077106D01*
X5578835Y1064606D01*
Y1077106D01*
G01X5584260Y1064606D02*
Y1077106D01*
X5587360D01*
X5588600Y1076481D01*
X5589530Y1075648D01*
X5590305Y1074398D01*
X5590925Y1072939D01*
X5591080Y1070856D01*
X5590925Y1068773D01*
X5590305Y1067314D01*
X5589530Y1066064D01*
X5588600Y1065231D01*
X5587360Y1064606D01*
X5584260D01*
G01X5596660Y1066481D02*
X5597590Y1065439D01*
X5598675Y1064814D01*
X5600070Y1064606D01*
X5601465Y1065023D01*
X5602550Y1065856D01*
X5603325Y1067314D01*
X5603480Y1068981D01*
X5603170Y1070648D01*
X5602395Y1071689D01*
X5601310Y1072523D01*
X5600225Y1072731D01*
X5599140Y1072523D01*
X5597745Y1071689D01*
X5598210Y1077106D01*
X5602395D01*
G01X5302710Y1385273D02*
X5303330Y1385898D01*
X5303795Y1386939D01*
X5304105Y1388398D01*
X5303795Y1389648D01*
X5303175Y1390481D01*
X5302090Y1391106D01*
X5297905D01*
Y1378606D01*
X5303020D01*
X5304105Y1379439D01*
X5304725Y1380689D01*
X5305035Y1382148D01*
X5304725Y1383606D01*
X5303795Y1384856D01*
X5302710Y1385273D01*
X5297905D01*
G01X5309995Y1378606D02*
X5313870Y1391106D01*
X5317745Y1378606D01*
G01X5316350Y1382981D02*
X5311390D01*
G01X5329680Y1390064D02*
X5328750Y1390689D01*
X5327665Y1391106D01*
X5326425D01*
X5325030Y1390481D01*
X5323945Y1389439D01*
X5323170Y1388189D01*
X5322550Y1386106D01*
X5322395Y1384231D01*
X5322705Y1382356D01*
X5323170Y1381106D01*
X5324100Y1379856D01*
X5325185Y1379023D01*
X5326270Y1378606D01*
X5327355D01*
X5328440Y1379023D01*
X5329370Y1379647D01*
X5330145Y1380481D01*
G01X5335260Y1378606D02*
Y1391106D01*
G01X5341150D02*
X5335260Y1383397D01*
G01X5342080Y1378606D02*
X5337895Y1386939D01*
G01X5347660Y1378606D02*
Y1391106D01*
X5350760D01*
X5352000Y1390481D01*
X5352930Y1389648D01*
X5353705Y1388398D01*
X5354325Y1386939D01*
X5354480Y1384856D01*
X5354325Y1382773D01*
X5353705Y1381314D01*
X5352930Y1380064D01*
X5352000Y1379231D01*
X5350760Y1378606D01*
X5347660D01*
G01X5360370D02*
Y1391106D01*
X5364245D01*
X5365485Y1390481D01*
X5366260Y1389648D01*
X5366570Y1387981D01*
X5366260Y1386314D01*
X5365330Y1385273D01*
X5364245Y1384648D01*
X5360370D01*
G01X5364245D02*
X5366570Y1378606D01*
G01X5374010Y1391106D02*
X5377730D01*
G01X5375870D02*
Y1378606D01*
G01X5374010D02*
X5377730D01*
G01X5385170Y1391106D02*
Y1378606D01*
X5391370D01*
G01X5397570Y1391106D02*
Y1378606D01*
X5403770D01*
G01X5413070Y1378189D02*
X5412760Y1378398D01*
Y1378814D01*
X5413070Y1379023D01*
X5413380Y1378814D01*
Y1378398D01*
X5413070Y1378189D01*
G01Y1383814D02*
X5412760Y1384023D01*
Y1384439D01*
X5413070Y1384648D01*
X5413380Y1384439D01*
Y1384023D01*
X5413070Y1383814D01*
G01X5439110Y1385273D02*
X5439730Y1385898D01*
X5440195Y1386939D01*
X5440505Y1388398D01*
X5440195Y1389648D01*
X5439575Y1390481D01*
X5438490Y1391106D01*
X5434305D01*
Y1378606D01*
X5439420D01*
X5440505Y1379439D01*
X5441125Y1380689D01*
X5441435Y1382148D01*
X5441125Y1383606D01*
X5440195Y1384856D01*
X5439110Y1385273D01*
X5434305D01*
G01X5450270Y1378606D02*
X5449030Y1378814D01*
X5447945Y1379647D01*
X5447015Y1380898D01*
X5446395Y1382356D01*
X5446085Y1384023D01*
Y1385689D01*
X5446395Y1387356D01*
X5447015Y1388814D01*
X5447945Y1390064D01*
X5449030Y1390898D01*
X5450270Y1391106D01*
X5451510Y1390898D01*
X5452595Y1390064D01*
X5453525Y1388814D01*
X5454145Y1387356D01*
X5454455Y1385689D01*
Y1384023D01*
X5454145Y1382356D01*
X5453525Y1380898D01*
X5452595Y1379647D01*
X5451510Y1378814D01*
X5450270Y1378606D01*
G01X5462670Y1391106D02*
Y1378606D01*
G01X5459105Y1391106D02*
X5466235D01*
G01X5475070D02*
Y1378606D01*
G01X5471505Y1391106D02*
X5478635D01*
G01X5487470Y1378606D02*
X5486230Y1378814D01*
X5485145Y1379647D01*
X5484215Y1380898D01*
X5483595Y1382356D01*
X5483285Y1384023D01*
Y1385689D01*
X5483595Y1387356D01*
X5484215Y1388814D01*
X5485145Y1390064D01*
X5486230Y1390898D01*
X5487470Y1391106D01*
X5488710Y1390898D01*
X5489795Y1390064D01*
X5490725Y1388814D01*
X5491345Y1387356D01*
X5491655Y1385689D01*
Y1384023D01*
X5491345Y1382356D01*
X5490725Y1380898D01*
X5489795Y1379647D01*
X5488710Y1378814D01*
X5487470Y1378606D01*
G01X5495840D02*
Y1391106D01*
X5499870Y1380689D01*
X5503900Y1391106D01*
Y1378606D01*
G01X5524670Y1391106D02*
Y1378606D01*
G01X5522500Y1386939D02*
X5526840D01*
G01X5537070Y1378606D02*
X5536140Y1378814D01*
X5535210Y1379647D01*
X5534590Y1381106D01*
X5534280Y1382773D01*
X5534590Y1384439D01*
X5535210Y1385898D01*
X5536140Y1386731D01*
X5537070Y1386939D01*
X5538000Y1386731D01*
X5538930Y1385898D01*
X5539550Y1384439D01*
X5539705Y1382773D01*
X5539550Y1381106D01*
X5538930Y1379647D01*
X5538000Y1378814D01*
X5537070Y1378606D01*
G01X5562800Y1384856D02*
X5565900D01*
Y1381106D01*
X5564970Y1379856D01*
X5563885Y1379023D01*
X5562335Y1378606D01*
X5560785Y1379023D01*
X5559700Y1379856D01*
X5558770Y1381106D01*
X5558150Y1382564D01*
X5557840Y1384231D01*
Y1385689D01*
X5558150Y1386939D01*
X5558770Y1388398D01*
X5559700Y1389648D01*
X5560630Y1390481D01*
X5561870Y1391106D01*
X5562955D01*
X5564195Y1390689D01*
X5565125Y1389856D01*
G01X5570705Y1378606D02*
Y1391106D01*
X5577835Y1378606D01*
Y1391106D01*
G01X5583260Y1378606D02*
Y1391106D01*
X5586360D01*
X5587600Y1390481D01*
X5588530Y1389648D01*
X5589305Y1388398D01*
X5589925Y1386939D01*
X5590080Y1384856D01*
X5589925Y1382773D01*
X5589305Y1381314D01*
X5588530Y1380064D01*
X5587600Y1379231D01*
X5586360Y1378606D01*
X5583260D01*
G01X5596125Y1383814D02*
X5597210Y1385273D01*
X5598140Y1386106D01*
X5599380Y1386523D01*
X5600465Y1386106D01*
X5601240Y1385273D01*
X5601860Y1384023D01*
X5602015Y1382564D01*
X5601860Y1381314D01*
X5601240Y1380064D01*
X5600310Y1379023D01*
X5599225Y1378606D01*
X5597985Y1379023D01*
X5596900Y1380272D01*
X5596280Y1382148D01*
X5596125Y1384231D01*
X5596435Y1386939D01*
X5596900Y1388398D01*
X5597675Y1389856D01*
X5598760Y1390898D01*
X5599845Y1391106D01*
X5600930Y1390689D01*
X5601705Y1389648D01*
G01X5302710Y1700773D02*
X5303330Y1701398D01*
X5303795Y1702439D01*
X5304105Y1703898D01*
X5303795Y1705148D01*
X5303175Y1705981D01*
X5302090Y1706606D01*
X5297905D01*
Y1694106D01*
X5303020D01*
X5304105Y1694939D01*
X5304725Y1696189D01*
X5305035Y1697648D01*
X5304725Y1699106D01*
X5303795Y1700356D01*
X5302710Y1700773D01*
X5297905D01*
G01X5309995Y1694106D02*
X5313870Y1706606D01*
X5317745Y1694106D01*
G01X5316350Y1698481D02*
X5311390D01*
G01X5329680Y1705564D02*
X5328750Y1706189D01*
X5327665Y1706606D01*
X5326425D01*
X5325030Y1705981D01*
X5323945Y1704939D01*
X5323170Y1703689D01*
X5322550Y1701606D01*
X5322395Y1699731D01*
X5322705Y1697856D01*
X5323170Y1696606D01*
X5324100Y1695356D01*
X5325185Y1694523D01*
X5326270Y1694106D01*
X5327355D01*
X5328440Y1694523D01*
X5329370Y1695147D01*
X5330145Y1695981D01*
G01X5335260Y1694106D02*
Y1706606D01*
G01X5341150D02*
X5335260Y1698897D01*
G01X5342080Y1694106D02*
X5337895Y1702439D01*
G01X5347660Y1694106D02*
Y1706606D01*
X5350760D01*
X5352000Y1705981D01*
X5352930Y1705148D01*
X5353705Y1703898D01*
X5354325Y1702439D01*
X5354480Y1700356D01*
X5354325Y1698273D01*
X5353705Y1696814D01*
X5352930Y1695564D01*
X5352000Y1694731D01*
X5350760Y1694106D01*
X5347660D01*
G01X5360370D02*
Y1706606D01*
X5364245D01*
X5365485Y1705981D01*
X5366260Y1705148D01*
X5366570Y1703481D01*
X5366260Y1701814D01*
X5365330Y1700773D01*
X5364245Y1700148D01*
X5360370D01*
G01X5364245D02*
X5366570Y1694106D01*
G01X5374010Y1706606D02*
X5377730D01*
G01X5375870D02*
Y1694106D01*
G01X5374010D02*
X5377730D01*
G01X5385170Y1706606D02*
Y1694106D01*
X5391370D01*
G01X5397570Y1706606D02*
Y1694106D01*
X5403770D01*
G01X5413070Y1693689D02*
X5412760Y1693898D01*
Y1694314D01*
X5413070Y1694523D01*
X5413380Y1694314D01*
Y1693898D01*
X5413070Y1693689D01*
G01Y1699314D02*
X5412760Y1699523D01*
Y1699939D01*
X5413070Y1700148D01*
X5413380Y1699939D01*
Y1699523D01*
X5413070Y1699314D01*
G01X5439110Y1700773D02*
X5439730Y1701398D01*
X5440195Y1702439D01*
X5440505Y1703898D01*
X5440195Y1705148D01*
X5439575Y1705981D01*
X5438490Y1706606D01*
X5434305D01*
Y1694106D01*
X5439420D01*
X5440505Y1694939D01*
X5441125Y1696189D01*
X5441435Y1697648D01*
X5441125Y1699106D01*
X5440195Y1700356D01*
X5439110Y1700773D01*
X5434305D01*
G01X5450270Y1694106D02*
X5449030Y1694314D01*
X5447945Y1695147D01*
X5447015Y1696398D01*
X5446395Y1697856D01*
X5446085Y1699523D01*
Y1701189D01*
X5446395Y1702856D01*
X5447015Y1704314D01*
X5447945Y1705564D01*
X5449030Y1706398D01*
X5450270Y1706606D01*
X5451510Y1706398D01*
X5452595Y1705564D01*
X5453525Y1704314D01*
X5454145Y1702856D01*
X5454455Y1701189D01*
Y1699523D01*
X5454145Y1697856D01*
X5453525Y1696398D01*
X5452595Y1695147D01*
X5451510Y1694314D01*
X5450270Y1694106D01*
G01X5462670Y1706606D02*
Y1694106D01*
G01X5459105Y1706606D02*
X5466235D01*
G01X5475070D02*
Y1694106D01*
G01X5471505Y1706606D02*
X5478635D01*
G01X5487470Y1694106D02*
X5486230Y1694314D01*
X5485145Y1695147D01*
X5484215Y1696398D01*
X5483595Y1697856D01*
X5483285Y1699523D01*
Y1701189D01*
X5483595Y1702856D01*
X5484215Y1704314D01*
X5485145Y1705564D01*
X5486230Y1706398D01*
X5487470Y1706606D01*
X5488710Y1706398D01*
X5489795Y1705564D01*
X5490725Y1704314D01*
X5491345Y1702856D01*
X5491655Y1701189D01*
Y1699523D01*
X5491345Y1697856D01*
X5490725Y1696398D01*
X5489795Y1695147D01*
X5488710Y1694314D01*
X5487470Y1694106D01*
G01X5495840D02*
Y1706606D01*
X5499870Y1696189D01*
X5503900Y1706606D01*
Y1694106D01*
G01X5524670Y1706606D02*
Y1694106D01*
G01X5522500Y1702439D02*
X5526840D01*
G01X5537070Y1694106D02*
X5536140Y1694314D01*
X5535210Y1695147D01*
X5534590Y1696606D01*
X5534280Y1698273D01*
X5534590Y1699939D01*
X5535210Y1701398D01*
X5536140Y1702231D01*
X5537070Y1702439D01*
X5538000Y1702231D01*
X5538930Y1701398D01*
X5539550Y1699939D01*
X5539705Y1698273D01*
X5539550Y1696606D01*
X5538930Y1695147D01*
X5538000Y1694314D01*
X5537070Y1694106D01*
G01X5562800Y1700356D02*
X5565900D01*
Y1696606D01*
X5564970Y1695356D01*
X5563885Y1694523D01*
X5562335Y1694106D01*
X5560785Y1694523D01*
X5559700Y1695356D01*
X5558770Y1696606D01*
X5558150Y1698064D01*
X5557840Y1699731D01*
Y1701189D01*
X5558150Y1702439D01*
X5558770Y1703898D01*
X5559700Y1705148D01*
X5560630Y1705981D01*
X5561870Y1706606D01*
X5562955D01*
X5564195Y1706189D01*
X5565125Y1705356D01*
G01X5570705Y1694106D02*
Y1706606D01*
X5577835Y1694106D01*
Y1706606D01*
G01X5583260Y1694106D02*
Y1706606D01*
X5586360D01*
X5587600Y1705981D01*
X5588530Y1705148D01*
X5589305Y1703898D01*
X5589925Y1702439D01*
X5590080Y1700356D01*
X5589925Y1698273D01*
X5589305Y1696814D01*
X5588530Y1695564D01*
X5587600Y1694731D01*
X5586360Y1694106D01*
X5583260D01*
G01X5598760D02*
X5599070Y1696814D01*
X5599535Y1699106D01*
X5600155Y1701189D01*
X5600930Y1703481D01*
X5602170Y1706606D01*
X5595970D01*
G01X5318839Y188116D02*
X5322714Y200616D01*
X5326589Y188116D01*
G01X5325194Y192491D02*
X5320234D01*
G01X5332014Y200616D02*
Y188116D01*
X5338214D01*
G01X5344414Y200616D02*
Y188116D01*
X5350614D01*
G01X5368904Y200616D02*
Y191658D01*
X5369524Y189782D01*
X5370764Y188533D01*
X5372314Y188116D01*
X5373864Y188533D01*
X5375104Y189782D01*
X5375724Y191658D01*
Y200616D01*
G01X5381149Y188116D02*
Y200616D01*
X5388279Y188116D01*
Y200616D01*
G01X5395254D02*
X5398974D01*
G01X5397114D02*
Y188116D01*
G01X5395254D02*
X5398974D01*
G01X5409514Y200616D02*
Y188116D01*
G01X5405949Y200616D02*
X5413079D01*
G01X5418659Y189782D02*
X5419899Y188741D01*
X5421294Y188116D01*
X5422534D01*
X5423774Y188741D01*
X5424704Y189782D01*
X5425169Y191241D01*
X5424859Y192699D01*
X5424084Y193949D01*
X5422689Y194783D01*
X5420829Y195199D01*
X5419744Y196033D01*
X5419279Y197491D01*
X5419589Y198949D01*
X5420364Y199991D01*
X5421449Y200616D01*
X5422534D01*
X5423619Y200199D01*
X5424549Y199158D01*
G01X5442839Y188116D02*
X5446714Y200616D01*
X5450589Y188116D01*
G01X5449194Y192491D02*
X5444234D01*
G01X5456014Y188116D02*
Y200616D01*
X5459889D01*
X5461129Y199991D01*
X5461904Y199158D01*
X5462214Y197491D01*
X5461904Y195824D01*
X5460974Y194783D01*
X5459889Y194158D01*
X5456014D01*
G01X5459889D02*
X5462214Y188116D01*
G01X5474614D02*
X5468414D01*
Y200616D01*
X5474614D01*
G01X5472134Y194574D02*
X5468414D01*
G01X5494454Y200616D02*
X5498174D01*
G01X5496314D02*
Y188116D01*
G01X5494454D02*
X5498174D01*
G01X5505149D02*
Y200616D01*
X5512279Y188116D01*
Y200616D01*
G01X5529484Y188116D02*
Y200616D01*
X5533514Y190199D01*
X5537544Y200616D01*
Y188116D01*
G01X5544054Y200616D02*
X5547774D01*
G01X5545914D02*
Y188116D01*
G01X5544054D02*
X5547774D01*
G01X5555214Y200616D02*
Y188116D01*
X5561414D01*
G01X5567459Y189782D02*
X5568699Y188741D01*
X5570094Y188116D01*
X5571334D01*
X5572574Y188741D01*
X5573504Y189782D01*
X5573969Y191241D01*
X5573659Y192699D01*
X5572884Y193949D01*
X5571489Y194783D01*
X5569629Y195199D01*
X5568544Y196033D01*
X5568079Y197491D01*
X5568389Y198949D01*
X5569164Y199991D01*
X5570249Y200616D01*
X5571334D01*
X5572419Y200199D01*
X5573349Y199158D01*
G01X5318805Y460935D02*
X5322680Y473435D01*
X5326555Y460935D01*
G01X5325160Y465310D02*
X5320200D01*
G01X5331980Y473435D02*
Y460935D01*
X5338180D01*
G01X5344380Y473435D02*
Y460935D01*
X5350580D01*
G01X5368870Y473435D02*
Y464477D01*
X5369490Y462601D01*
X5370730Y461352D01*
X5372280Y460935D01*
X5373830Y461352D01*
X5375070Y462601D01*
X5375690Y464477D01*
Y473435D01*
G01X5381115Y460935D02*
Y473435D01*
X5388245Y460935D01*
Y473435D01*
G01X5395220D02*
X5398940D01*
G01X5397080D02*
Y460935D01*
G01X5395220D02*
X5398940D01*
G01X5409480Y473435D02*
Y460935D01*
G01X5405915Y473435D02*
X5413045D01*
G01X5418625Y462601D02*
X5419865Y461560D01*
X5421260Y460935D01*
X5422500D01*
X5423740Y461560D01*
X5424670Y462601D01*
X5425135Y464060D01*
X5424825Y465518D01*
X5424050Y466768D01*
X5422655Y467602D01*
X5420795Y468018D01*
X5419710Y468852D01*
X5419245Y470310D01*
X5419555Y471768D01*
X5420330Y472810D01*
X5421415Y473435D01*
X5422500D01*
X5423585Y473018D01*
X5424515Y471977D01*
G01X5442805Y460935D02*
X5446680Y473435D01*
X5450555Y460935D01*
G01X5449160Y465310D02*
X5444200D01*
G01X5455980Y460935D02*
Y473435D01*
X5459855D01*
X5461095Y472810D01*
X5461870Y471977D01*
X5462180Y470310D01*
X5461870Y468643D01*
X5460940Y467602D01*
X5459855Y466977D01*
X5455980D01*
G01X5459855D02*
X5462180Y460935D01*
G01X5474580D02*
X5468380D01*
Y473435D01*
X5474580D01*
G01X5472100Y467393D02*
X5468380D01*
G01X5494420Y473435D02*
X5498140D01*
G01X5496280D02*
Y460935D01*
G01X5494420D02*
X5498140D01*
G01X5505115D02*
Y473435D01*
X5512245Y460935D01*
Y473435D01*
G01X5529450Y460935D02*
Y473435D01*
X5533480Y463018D01*
X5537510Y473435D01*
Y460935D01*
G01X5544020Y473435D02*
X5547740D01*
G01X5545880D02*
Y460935D01*
G01X5544020D02*
X5547740D01*
G01X5555180Y473435D02*
Y460935D01*
X5561380D01*
G01X5567425Y462601D02*
X5568665Y461560D01*
X5570060Y460935D01*
X5571300D01*
X5572540Y461560D01*
X5573470Y462601D01*
X5573935Y464060D01*
X5573625Y465518D01*
X5572850Y466768D01*
X5571455Y467602D01*
X5569595Y468018D01*
X5568510Y468852D01*
X5568045Y470310D01*
X5568355Y471768D01*
X5569130Y472810D01*
X5570215Y473435D01*
X5571300D01*
X5572385Y473018D01*
X5573315Y471977D01*
G01X5321395Y732106D02*
X5325270Y744606D01*
X5329145Y732106D01*
G01X5327750Y736481D02*
X5322790D01*
G01X5334570Y744606D02*
Y732106D01*
X5340770D01*
G01X5346970Y744606D02*
Y732106D01*
X5353170D01*
G01X5371460Y744606D02*
Y735648D01*
X5372080Y733772D01*
X5373320Y732523D01*
X5374870Y732106D01*
X5376420Y732523D01*
X5377660Y733772D01*
X5378280Y735648D01*
Y744606D01*
G01X5383705Y732106D02*
Y744606D01*
X5390835Y732106D01*
Y744606D01*
G01X5397810D02*
X5401530D01*
G01X5399670D02*
Y732106D01*
G01X5397810D02*
X5401530D01*
G01X5412070Y744606D02*
Y732106D01*
G01X5408505Y744606D02*
X5415635D01*
G01X5421215Y733772D02*
X5422455Y732731D01*
X5423850Y732106D01*
X5425090D01*
X5426330Y732731D01*
X5427260Y733772D01*
X5427725Y735231D01*
X5427415Y736689D01*
X5426640Y737939D01*
X5425245Y738773D01*
X5423385Y739189D01*
X5422300Y740023D01*
X5421835Y741481D01*
X5422145Y742939D01*
X5422920Y743981D01*
X5424005Y744606D01*
X5425090D01*
X5426175Y744189D01*
X5427105Y743148D01*
G01X5445395Y732106D02*
X5449270Y744606D01*
X5453145Y732106D01*
G01X5451750Y736481D02*
X5446790D01*
G01X5458570Y732106D02*
Y744606D01*
X5462445D01*
X5463685Y743981D01*
X5464460Y743148D01*
X5464770Y741481D01*
X5464460Y739814D01*
X5463530Y738773D01*
X5462445Y738148D01*
X5458570D01*
G01X5462445D02*
X5464770Y732106D01*
G01X5477170D02*
X5470970D01*
Y744606D01*
X5477170D01*
G01X5474690Y738564D02*
X5470970D01*
G01X5497010Y744606D02*
X5500730D01*
G01X5498870D02*
Y732106D01*
G01X5497010D02*
X5500730D01*
G01X5507705D02*
Y744606D01*
X5514835Y732106D01*
Y744606D01*
G01X5532040Y732106D02*
Y744606D01*
X5536070Y734189D01*
X5540100Y744606D01*
Y732106D01*
G01X5546610Y744606D02*
X5550330D01*
G01X5548470D02*
Y732106D01*
G01X5546610D02*
X5550330D01*
G01X5557770Y744606D02*
Y732106D01*
X5563970D01*
G01X5570015Y733772D02*
X5571255Y732731D01*
X5572650Y732106D01*
X5573890D01*
X5575130Y732731D01*
X5576060Y733772D01*
X5576525Y735231D01*
X5576215Y736689D01*
X5575440Y737939D01*
X5574045Y738773D01*
X5572185Y739189D01*
X5571100Y740023D01*
X5570635Y741481D01*
X5570945Y742939D01*
X5571720Y743981D01*
X5572805Y744606D01*
X5573890D01*
X5574975Y744189D01*
X5575905Y743148D01*
G01X5323395Y1039606D02*
X5327270Y1052106D01*
X5331145Y1039606D01*
G01X5329750Y1043981D02*
X5324790D01*
G01X5336570Y1052106D02*
Y1039606D01*
X5342770D01*
G01X5348970Y1052106D02*
Y1039606D01*
X5355170D01*
G01X5373460Y1052106D02*
Y1043148D01*
X5374080Y1041272D01*
X5375320Y1040023D01*
X5376870Y1039606D01*
X5378420Y1040023D01*
X5379660Y1041272D01*
X5380280Y1043148D01*
Y1052106D01*
G01X5385705Y1039606D02*
Y1052106D01*
X5392835Y1039606D01*
Y1052106D01*
G01X5399810D02*
X5403530D01*
G01X5401670D02*
Y1039606D01*
G01X5399810D02*
X5403530D01*
G01X5414070Y1052106D02*
Y1039606D01*
G01X5410505Y1052106D02*
X5417635D01*
G01X5423215Y1041272D02*
X5424455Y1040231D01*
X5425850Y1039606D01*
X5427090D01*
X5428330Y1040231D01*
X5429260Y1041272D01*
X5429725Y1042731D01*
X5429415Y1044189D01*
X5428640Y1045439D01*
X5427245Y1046273D01*
X5425385Y1046689D01*
X5424300Y1047523D01*
X5423835Y1048981D01*
X5424145Y1050439D01*
X5424920Y1051481D01*
X5426005Y1052106D01*
X5427090D01*
X5428175Y1051689D01*
X5429105Y1050648D01*
G01X5447395Y1039606D02*
X5451270Y1052106D01*
X5455145Y1039606D01*
G01X5453750Y1043981D02*
X5448790D01*
G01X5460570Y1039606D02*
Y1052106D01*
X5464445D01*
X5465685Y1051481D01*
X5466460Y1050648D01*
X5466770Y1048981D01*
X5466460Y1047314D01*
X5465530Y1046273D01*
X5464445Y1045648D01*
X5460570D01*
G01X5464445D02*
X5466770Y1039606D01*
G01X5479170D02*
X5472970D01*
Y1052106D01*
X5479170D01*
G01X5476690Y1046064D02*
X5472970D01*
G01X5499010Y1052106D02*
X5502730D01*
G01X5500870D02*
Y1039606D01*
G01X5499010D02*
X5502730D01*
G01X5509705D02*
Y1052106D01*
X5516835Y1039606D01*
Y1052106D01*
G01X5534040Y1039606D02*
Y1052106D01*
X5538070Y1041689D01*
X5542100Y1052106D01*
Y1039606D01*
G01X5548610Y1052106D02*
X5552330D01*
G01X5550470D02*
Y1039606D01*
G01X5548610D02*
X5552330D01*
G01X5559770Y1052106D02*
Y1039606D01*
X5565970D01*
G01X5572015Y1041272D02*
X5573255Y1040231D01*
X5574650Y1039606D01*
X5575890D01*
X5577130Y1040231D01*
X5578060Y1041272D01*
X5578525Y1042731D01*
X5578215Y1044189D01*
X5577440Y1045439D01*
X5576045Y1046273D01*
X5574185Y1046689D01*
X5573100Y1047523D01*
X5572635Y1048981D01*
X5572945Y1050439D01*
X5573720Y1051481D01*
X5574805Y1052106D01*
X5575890D01*
X5576975Y1051689D01*
X5577905Y1050648D01*
G01X5322395Y1353606D02*
X5326270Y1366106D01*
X5330145Y1353606D01*
G01X5328750Y1357981D02*
X5323790D01*
G01X5335570Y1366106D02*
Y1353606D01*
X5341770D01*
G01X5347970Y1366106D02*
Y1353606D01*
X5354170D01*
G01X5372460Y1366106D02*
Y1357148D01*
X5373080Y1355272D01*
X5374320Y1354023D01*
X5375870Y1353606D01*
X5377420Y1354023D01*
X5378660Y1355272D01*
X5379280Y1357148D01*
Y1366106D01*
G01X5384705Y1353606D02*
Y1366106D01*
X5391835Y1353606D01*
Y1366106D01*
G01X5398810D02*
X5402530D01*
G01X5400670D02*
Y1353606D01*
G01X5398810D02*
X5402530D01*
G01X5413070Y1366106D02*
Y1353606D01*
G01X5409505Y1366106D02*
X5416635D01*
G01X5422215Y1355272D02*
X5423455Y1354231D01*
X5424850Y1353606D01*
X5426090D01*
X5427330Y1354231D01*
X5428260Y1355272D01*
X5428725Y1356731D01*
X5428415Y1358189D01*
X5427640Y1359439D01*
X5426245Y1360273D01*
X5424385Y1360689D01*
X5423300Y1361523D01*
X5422835Y1362981D01*
X5423145Y1364439D01*
X5423920Y1365481D01*
X5425005Y1366106D01*
X5426090D01*
X5427175Y1365689D01*
X5428105Y1364648D01*
G01X5446395Y1353606D02*
X5450270Y1366106D01*
X5454145Y1353606D01*
G01X5452750Y1357981D02*
X5447790D01*
G01X5459570Y1353606D02*
Y1366106D01*
X5463445D01*
X5464685Y1365481D01*
X5465460Y1364648D01*
X5465770Y1362981D01*
X5465460Y1361314D01*
X5464530Y1360273D01*
X5463445Y1359648D01*
X5459570D01*
G01X5463445D02*
X5465770Y1353606D01*
G01X5478170D02*
X5471970D01*
Y1366106D01*
X5478170D01*
G01X5475690Y1360064D02*
X5471970D01*
G01X5498010Y1366106D02*
X5501730D01*
G01X5499870D02*
Y1353606D01*
G01X5498010D02*
X5501730D01*
G01X5508705D02*
Y1366106D01*
X5515835Y1353606D01*
Y1366106D01*
G01X5533040Y1353606D02*
Y1366106D01*
X5537070Y1355689D01*
X5541100Y1366106D01*
Y1353606D01*
G01X5547610Y1366106D02*
X5551330D01*
G01X5549470D02*
Y1353606D01*
G01X5547610D02*
X5551330D01*
G01X5558770Y1366106D02*
Y1353606D01*
X5564970D01*
G01X5571015Y1355272D02*
X5572255Y1354231D01*
X5573650Y1353606D01*
X5574890D01*
X5576130Y1354231D01*
X5577060Y1355272D01*
X5577525Y1356731D01*
X5577215Y1358189D01*
X5576440Y1359439D01*
X5575045Y1360273D01*
X5573185Y1360689D01*
X5572100Y1361523D01*
X5571635Y1362981D01*
X5571945Y1364439D01*
X5572720Y1365481D01*
X5573805Y1366106D01*
X5574890D01*
X5575975Y1365689D01*
X5576905Y1364648D01*
G01X5322395Y1669106D02*
X5326270Y1681606D01*
X5330145Y1669106D01*
G01X5328750Y1673481D02*
X5323790D01*
G01X5335570Y1681606D02*
Y1669106D01*
X5341770D01*
G01X5347970Y1681606D02*
Y1669106D01*
X5354170D01*
G01X5372460Y1681606D02*
Y1672648D01*
X5373080Y1670772D01*
X5374320Y1669523D01*
X5375870Y1669106D01*
X5377420Y1669523D01*
X5378660Y1670772D01*
X5379280Y1672648D01*
Y1681606D01*
G01X5384705Y1669106D02*
Y1681606D01*
X5391835Y1669106D01*
Y1681606D01*
G01X5398810D02*
X5402530D01*
G01X5400670D02*
Y1669106D01*
G01X5398810D02*
X5402530D01*
G01X5413070Y1681606D02*
Y1669106D01*
G01X5409505Y1681606D02*
X5416635D01*
G01X5422215Y1670772D02*
X5423455Y1669731D01*
X5424850Y1669106D01*
X5426090D01*
X5427330Y1669731D01*
X5428260Y1670772D01*
X5428725Y1672231D01*
X5428415Y1673689D01*
X5427640Y1674939D01*
X5426245Y1675773D01*
X5424385Y1676189D01*
X5423300Y1677023D01*
X5422835Y1678481D01*
X5423145Y1679939D01*
X5423920Y1680981D01*
X5425005Y1681606D01*
X5426090D01*
X5427175Y1681189D01*
X5428105Y1680148D01*
G01X5446395Y1669106D02*
X5450270Y1681606D01*
X5454145Y1669106D01*
G01X5452750Y1673481D02*
X5447790D01*
G01X5459570Y1669106D02*
Y1681606D01*
X5463445D01*
X5464685Y1680981D01*
X5465460Y1680148D01*
X5465770Y1678481D01*
X5465460Y1676814D01*
X5464530Y1675773D01*
X5463445Y1675148D01*
X5459570D01*
G01X5463445D02*
X5465770Y1669106D01*
G01X5478170D02*
X5471970D01*
Y1681606D01*
X5478170D01*
G01X5475690Y1675564D02*
X5471970D01*
G01X5498010Y1681606D02*
X5501730D01*
G01X5499870D02*
Y1669106D01*
G01X5498010D02*
X5501730D01*
G01X5508705D02*
Y1681606D01*
X5515835Y1669106D01*
Y1681606D01*
G01X5533040Y1669106D02*
Y1681606D01*
X5537070Y1671189D01*
X5541100Y1681606D01*
Y1669106D01*
G01X5547610Y1681606D02*
X5551330D01*
G01X5549470D02*
Y1669106D01*
G01X5547610D02*
X5551330D01*
G01X5558770Y1681606D02*
Y1669106D01*
X5564970D01*
G01X5571015Y1670772D02*
X5572255Y1669731D01*
X5573650Y1669106D01*
X5574890D01*
X5576130Y1669731D01*
X5577060Y1670772D01*
X5577525Y1672231D01*
X5577215Y1673689D01*
X5576440Y1674939D01*
X5575045Y1675773D01*
X5573185Y1676189D01*
X5572100Y1677023D01*
X5571635Y1678481D01*
X5571945Y1679939D01*
X5572720Y1680981D01*
X5573805Y1681606D01*
X5574890D01*
X5575975Y1681189D01*
X5576905Y1680148D01*
G01X5335734Y163116D02*
Y175616D01*
X5339764Y165199D01*
X5343794Y175616D01*
Y163116D01*
G01X5348599D02*
Y175616D01*
X5355729Y163116D01*
Y175616D01*
G01X5367974Y174574D02*
X5367044Y175199D01*
X5365959Y175616D01*
X5364719D01*
X5363324Y174991D01*
X5362239Y173949D01*
X5361464Y172699D01*
X5360844Y170616D01*
X5360689Y168741D01*
X5360999Y166866D01*
X5361464Y165616D01*
X5362394Y164366D01*
X5363479Y163533D01*
X5364564Y163116D01*
X5365649D01*
X5366734Y163533D01*
X5367664Y164157D01*
X5368439Y164991D01*
G01X5372314Y158949D02*
X5381614D01*
G01X5386264Y175616D02*
Y163116D01*
X5392464D01*
G01X5397889D02*
X5401764Y175616D01*
X5405639Y163116D01*
G01X5404244Y167491D02*
X5399284D01*
G01X5414164Y163116D02*
Y168741D01*
X5411064Y175616D01*
G01X5417264D02*
X5414164Y168741D01*
G01X5429664Y163116D02*
X5423464D01*
Y175616D01*
X5429664D01*
G01X5427184Y169574D02*
X5423464D01*
G01X5435864Y163116D02*
Y175616D01*
X5439739D01*
X5440979Y174991D01*
X5441754Y174158D01*
X5442064Y172491D01*
X5441754Y170824D01*
X5440824Y169783D01*
X5439739Y169158D01*
X5435864D01*
G01X5439739D02*
X5442064Y163116D01*
G01X5335700Y435935D02*
Y448435D01*
X5339730Y438018D01*
X5343760Y448435D01*
Y435935D01*
G01X5348565D02*
Y448435D01*
X5355695Y435935D01*
Y448435D01*
G01X5367940Y447393D02*
X5367010Y448018D01*
X5365925Y448435D01*
X5364685D01*
X5363290Y447810D01*
X5362205Y446768D01*
X5361430Y445518D01*
X5360810Y443435D01*
X5360655Y441560D01*
X5360965Y439685D01*
X5361430Y438435D01*
X5362360Y437185D01*
X5363445Y436352D01*
X5364530Y435935D01*
X5365615D01*
X5366700Y436352D01*
X5367630Y436976D01*
X5368405Y437810D01*
G01X5372280Y431768D02*
X5381580D01*
G01X5386230Y448435D02*
Y435935D01*
X5392430D01*
G01X5397855D02*
X5401730Y448435D01*
X5405605Y435935D01*
G01X5404210Y440310D02*
X5399250D01*
G01X5414130Y435935D02*
Y441560D01*
X5411030Y448435D01*
G01X5417230D02*
X5414130Y441560D01*
G01X5429630Y435935D02*
X5423430D01*
Y448435D01*
X5429630D01*
G01X5427150Y442393D02*
X5423430D01*
G01X5435830Y435935D02*
Y448435D01*
X5439705D01*
X5440945Y447810D01*
X5441720Y446977D01*
X5442030Y445310D01*
X5441720Y443643D01*
X5440790Y442602D01*
X5439705Y441977D01*
X5435830D01*
G01X5439705D02*
X5442030Y435935D01*
G01X5338290Y707106D02*
Y719606D01*
X5342320Y709189D01*
X5346350Y719606D01*
Y707106D01*
G01X5351155D02*
Y719606D01*
X5358285Y707106D01*
Y719606D01*
G01X5370530Y718564D02*
X5369600Y719189D01*
X5368515Y719606D01*
X5367275D01*
X5365880Y718981D01*
X5364795Y717939D01*
X5364020Y716689D01*
X5363400Y714606D01*
X5363245Y712731D01*
X5363555Y710856D01*
X5364020Y709606D01*
X5364950Y708356D01*
X5366035Y707523D01*
X5367120Y707106D01*
X5368205D01*
X5369290Y707523D01*
X5370220Y708147D01*
X5370995Y708981D01*
G01X5374870Y702939D02*
X5384170D01*
G01X5388820Y719606D02*
Y707106D01*
X5395020D01*
G01X5400445D02*
X5404320Y719606D01*
X5408195Y707106D01*
G01X5406800Y711481D02*
X5401840D01*
G01X5416720Y707106D02*
Y712731D01*
X5413620Y719606D01*
G01X5419820D02*
X5416720Y712731D01*
G01X5432220Y707106D02*
X5426020D01*
Y719606D01*
X5432220D01*
G01X5429740Y713564D02*
X5426020D01*
G01X5438420Y707106D02*
Y719606D01*
X5442295D01*
X5443535Y718981D01*
X5444310Y718148D01*
X5444620Y716481D01*
X5444310Y714814D01*
X5443380Y713773D01*
X5442295Y713148D01*
X5438420D01*
G01X5442295D02*
X5444620Y707106D01*
G01X5340290Y1014606D02*
Y1027106D01*
X5344320Y1016689D01*
X5348350Y1027106D01*
Y1014606D01*
G01X5353155D02*
Y1027106D01*
X5360285Y1014606D01*
Y1027106D01*
G01X5372530Y1026064D02*
X5371600Y1026689D01*
X5370515Y1027106D01*
X5369275D01*
X5367880Y1026481D01*
X5366795Y1025439D01*
X5366020Y1024189D01*
X5365400Y1022106D01*
X5365245Y1020231D01*
X5365555Y1018356D01*
X5366020Y1017106D01*
X5366950Y1015856D01*
X5368035Y1015023D01*
X5369120Y1014606D01*
X5370205D01*
X5371290Y1015023D01*
X5372220Y1015647D01*
X5372995Y1016481D01*
G01X5376870Y1010439D02*
X5386170D01*
G01X5390820Y1027106D02*
Y1014606D01*
X5397020D01*
G01X5402445D02*
X5406320Y1027106D01*
X5410195Y1014606D01*
G01X5408800Y1018981D02*
X5403840D01*
G01X5418720Y1014606D02*
Y1020231D01*
X5415620Y1027106D01*
G01X5421820D02*
X5418720Y1020231D01*
G01X5434220Y1014606D02*
X5428020D01*
Y1027106D01*
X5434220D01*
G01X5431740Y1021064D02*
X5428020D01*
G01X5440420Y1014606D02*
Y1027106D01*
X5444295D01*
X5445535Y1026481D01*
X5446310Y1025648D01*
X5446620Y1023981D01*
X5446310Y1022314D01*
X5445380Y1021273D01*
X5444295Y1020648D01*
X5440420D01*
G01X5444295D02*
X5446620Y1014606D01*
G01X5339290Y1328606D02*
Y1341106D01*
X5343320Y1330689D01*
X5347350Y1341106D01*
Y1328606D01*
G01X5352155D02*
Y1341106D01*
X5359285Y1328606D01*
Y1341106D01*
G01X5371530Y1340064D02*
X5370600Y1340689D01*
X5369515Y1341106D01*
X5368275D01*
X5366880Y1340481D01*
X5365795Y1339439D01*
X5365020Y1338189D01*
X5364400Y1336106D01*
X5364245Y1334231D01*
X5364555Y1332356D01*
X5365020Y1331106D01*
X5365950Y1329856D01*
X5367035Y1329023D01*
X5368120Y1328606D01*
X5369205D01*
X5370290Y1329023D01*
X5371220Y1329647D01*
X5371995Y1330481D01*
G01X5375870Y1324439D02*
X5385170D01*
G01X5389820Y1341106D02*
Y1328606D01*
X5396020D01*
G01X5401445D02*
X5405320Y1341106D01*
X5409195Y1328606D01*
G01X5407800Y1332981D02*
X5402840D01*
G01X5417720Y1328606D02*
Y1334231D01*
X5414620Y1341106D01*
G01X5420820D02*
X5417720Y1334231D01*
G01X5433220Y1328606D02*
X5427020D01*
Y1341106D01*
X5433220D01*
G01X5430740Y1335064D02*
X5427020D01*
G01X5439420Y1328606D02*
Y1341106D01*
X5443295D01*
X5444535Y1340481D01*
X5445310Y1339648D01*
X5445620Y1337981D01*
X5445310Y1336314D01*
X5444380Y1335273D01*
X5443295Y1334648D01*
X5439420D01*
G01X5443295D02*
X5445620Y1328606D01*
G01X5339290Y1644106D02*
Y1656606D01*
X5343320Y1646189D01*
X5347350Y1656606D01*
Y1644106D01*
G01X5352155D02*
Y1656606D01*
X5359285Y1644106D01*
Y1656606D01*
G01X5371530Y1655564D02*
X5370600Y1656189D01*
X5369515Y1656606D01*
X5368275D01*
X5366880Y1655981D01*
X5365795Y1654939D01*
X5365020Y1653689D01*
X5364400Y1651606D01*
X5364245Y1649731D01*
X5364555Y1647856D01*
X5365020Y1646606D01*
X5365950Y1645356D01*
X5367035Y1644523D01*
X5368120Y1644106D01*
X5369205D01*
X5370290Y1644523D01*
X5371220Y1645147D01*
X5371995Y1645981D01*
G01X5375870Y1639939D02*
X5385170D01*
G01X5389820Y1656606D02*
Y1644106D01*
X5396020D01*
G01X5401445D02*
X5405320Y1656606D01*
X5409195Y1644106D01*
G01X5407800Y1648481D02*
X5402840D01*
G01X5417720Y1644106D02*
Y1649731D01*
X5414620Y1656606D01*
G01X5420820D02*
X5417720Y1649731D01*
G01X5433220Y1644106D02*
X5427020D01*
Y1656606D01*
X5433220D01*
G01X5430740Y1650564D02*
X5427020D01*
G01X5439420Y1644106D02*
Y1656606D01*
X5443295D01*
X5444535Y1655981D01*
X5445310Y1655148D01*
X5445620Y1653481D01*
X5445310Y1651814D01*
X5444380Y1650773D01*
X5443295Y1650148D01*
X5439420D01*
G01X5443295D02*
X5445620Y1644106D01*
G01X5375104Y125616D02*
X5378824D01*
G01X5376964D02*
Y113116D01*
G01X5375104D02*
X5378824D01*
G01X5385799D02*
Y125616D01*
X5392929Y113116D01*
Y125616D01*
G01X5401764Y113116D02*
Y125616D01*
X5399904Y123116D01*
G01Y113116D02*
X5403624D01*
G01X5375104Y150616D02*
X5378824D01*
G01X5376964D02*
Y138116D01*
G01X5375104D02*
X5378824D01*
G01X5385799D02*
Y150616D01*
X5392929Y138116D01*
Y150616D01*
G01X5401764Y138116D02*
Y150616D01*
X5399904Y148116D01*
G01Y138116D02*
X5403624D01*
G01X5375070Y398435D02*
X5378790D01*
G01X5376930D02*
Y385935D01*
G01X5375070D02*
X5378790D01*
G01X5385765D02*
Y398435D01*
X5392895Y385935D01*
Y398435D01*
G01X5398785Y396352D02*
X5399715Y397601D01*
X5400800Y398227D01*
X5402040Y398435D01*
X5403590Y398018D01*
X5404675Y396977D01*
X5404985Y395727D01*
X5404830Y394476D01*
X5404210Y393435D01*
X5401110Y391352D01*
X5399715Y389893D01*
X5398785Y387810D01*
X5398475Y385935D01*
X5404985D01*
G01X5375070Y423435D02*
X5378790D01*
G01X5376930D02*
Y410935D01*
G01X5375070D02*
X5378790D01*
G01X5385765D02*
Y423435D01*
X5392895Y410935D01*
Y423435D01*
G01X5398785Y421352D02*
X5399715Y422601D01*
X5400800Y423227D01*
X5402040Y423435D01*
X5403590Y423018D01*
X5404675Y421977D01*
X5404985Y420727D01*
X5404830Y419476D01*
X5404210Y418435D01*
X5401110Y416352D01*
X5399715Y414893D01*
X5398785Y412810D01*
X5398475Y410935D01*
X5404985D01*
G01X5377660Y669606D02*
X5381380D01*
G01X5379520D02*
Y657106D01*
G01X5377660D02*
X5381380D01*
G01X5388355D02*
Y669606D01*
X5395485Y657106D01*
Y669606D01*
G01X5400910Y659606D02*
X5401840Y658147D01*
X5403080Y657314D01*
X5404475Y657106D01*
X5405715Y657314D01*
X5406955Y658356D01*
X5407730Y659606D01*
X5407885Y660856D01*
X5407575Y662314D01*
X5406490Y663356D01*
X5405405Y663773D01*
X5404010D01*
G01X5405405D02*
X5406335Y664398D01*
X5407110Y665439D01*
X5407420Y666689D01*
X5407110Y667939D01*
X5406335Y668981D01*
X5404940Y669606D01*
X5403545Y669398D01*
X5402150Y668564D01*
G01X5377660Y694606D02*
X5381380D01*
G01X5379520D02*
Y682106D01*
G01X5377660D02*
X5381380D01*
G01X5388355D02*
Y694606D01*
X5395485Y682106D01*
Y694606D01*
G01X5400910Y684606D02*
X5401840Y683147D01*
X5403080Y682314D01*
X5404475Y682106D01*
X5405715Y682314D01*
X5406955Y683356D01*
X5407730Y684606D01*
X5407885Y685856D01*
X5407575Y687314D01*
X5406490Y688356D01*
X5405405Y688773D01*
X5404010D01*
G01X5405405D02*
X5406335Y689398D01*
X5407110Y690439D01*
X5407420Y691689D01*
X5407110Y692939D01*
X5406335Y693981D01*
X5404940Y694606D01*
X5403545Y694398D01*
X5402150Y693564D01*
G01X5379660Y927106D02*
X5383380D01*
G01X5381520D02*
Y914606D01*
G01X5379660D02*
X5383380D01*
G01X5390355D02*
Y927106D01*
X5397485Y914606D01*
Y927106D01*
G01X5408180Y914606D02*
Y927106D01*
X5402445Y918148D01*
X5410195D01*
G01X5379660Y952106D02*
X5383380D01*
G01X5381520D02*
Y939606D01*
G01X5379660D02*
X5383380D01*
G01X5390355D02*
Y952106D01*
X5397485Y939606D01*
Y952106D01*
G01X5408180Y939606D02*
Y952106D01*
X5402445Y943148D01*
X5410195D01*
G01X5379660Y977106D02*
X5383380D01*
G01X5381520D02*
Y964606D01*
G01X5379660D02*
X5383380D01*
G01X5390355D02*
Y977106D01*
X5397485Y964606D01*
Y977106D01*
G01X5408180Y964606D02*
Y977106D01*
X5402445Y968148D01*
X5410195D01*
G01X5379660Y1002106D02*
X5383380D01*
G01X5381520D02*
Y989606D01*
G01X5379660D02*
X5383380D01*
G01X5390355D02*
Y1002106D01*
X5397485Y989606D01*
Y1002106D01*
G01X5408180Y989606D02*
Y1002106D01*
X5402445Y993148D01*
X5410195D01*
G01X5378660Y1241106D02*
X5382380D01*
G01X5380520D02*
Y1228606D01*
G01X5378660D02*
X5382380D01*
G01X5389355D02*
Y1241106D01*
X5396485Y1228606D01*
Y1241106D01*
G01X5401910Y1230481D02*
X5402840Y1229439D01*
X5403925Y1228814D01*
X5405320Y1228606D01*
X5406715Y1229023D01*
X5407800Y1229856D01*
X5408575Y1231314D01*
X5408730Y1232981D01*
X5408420Y1234648D01*
X5407645Y1235689D01*
X5406560Y1236523D01*
X5405475Y1236731D01*
X5404390Y1236523D01*
X5402995Y1235689D01*
X5403460Y1241106D01*
X5407645D01*
G01X5378660Y1266106D02*
X5382380D01*
G01X5380520D02*
Y1253606D01*
G01X5378660D02*
X5382380D01*
G01X5389355D02*
Y1266106D01*
X5396485Y1253606D01*
Y1266106D01*
G01X5401910Y1255481D02*
X5402840Y1254439D01*
X5403925Y1253814D01*
X5405320Y1253606D01*
X5406715Y1254023D01*
X5407800Y1254856D01*
X5408575Y1256314D01*
X5408730Y1257981D01*
X5408420Y1259648D01*
X5407645Y1260689D01*
X5406560Y1261523D01*
X5405475Y1261731D01*
X5404390Y1261523D01*
X5402995Y1260689D01*
X5403460Y1266106D01*
X5407645D01*
G01X5378660Y1291106D02*
X5382380D01*
G01X5380520D02*
Y1278606D01*
G01X5378660D02*
X5382380D01*
G01X5389355D02*
Y1291106D01*
X5396485Y1278606D01*
Y1291106D01*
G01X5401910Y1280481D02*
X5402840Y1279439D01*
X5403925Y1278814D01*
X5405320Y1278606D01*
X5406715Y1279023D01*
X5407800Y1279856D01*
X5408575Y1281314D01*
X5408730Y1282981D01*
X5408420Y1284648D01*
X5407645Y1285689D01*
X5406560Y1286523D01*
X5405475Y1286731D01*
X5404390Y1286523D01*
X5402995Y1285689D01*
X5403460Y1291106D01*
X5407645D01*
G01X5378660Y1316106D02*
X5382380D01*
G01X5380520D02*
Y1303606D01*
G01X5378660D02*
X5382380D01*
G01X5389355D02*
Y1316106D01*
X5396485Y1303606D01*
Y1316106D01*
G01X5401910Y1305481D02*
X5402840Y1304439D01*
X5403925Y1303814D01*
X5405320Y1303606D01*
X5406715Y1304023D01*
X5407800Y1304856D01*
X5408575Y1306314D01*
X5408730Y1307981D01*
X5408420Y1309648D01*
X5407645Y1310689D01*
X5406560Y1311523D01*
X5405475Y1311731D01*
X5404390Y1311523D01*
X5402995Y1310689D01*
X5403460Y1316106D01*
X5407645D01*
G01X5378660Y1556606D02*
X5382380D01*
G01X5380520D02*
Y1544106D01*
G01X5378660D02*
X5382380D01*
G01X5389355D02*
Y1556606D01*
X5396485Y1544106D01*
Y1556606D01*
G01X5402375Y1549314D02*
X5403460Y1550773D01*
X5404390Y1551606D01*
X5405630Y1552023D01*
X5406715Y1551606D01*
X5407490Y1550773D01*
X5408110Y1549523D01*
X5408265Y1548064D01*
X5408110Y1546814D01*
X5407490Y1545564D01*
X5406560Y1544523D01*
X5405475Y1544106D01*
X5404235Y1544523D01*
X5403150Y1545772D01*
X5402530Y1547648D01*
X5402375Y1549731D01*
X5402685Y1552439D01*
X5403150Y1553898D01*
X5403925Y1555356D01*
X5405010Y1556398D01*
X5406095Y1556606D01*
X5407180Y1556189D01*
X5407955Y1555148D01*
G01X5378660Y1581606D02*
X5382380D01*
G01X5380520D02*
Y1569106D01*
G01X5378660D02*
X5382380D01*
G01X5389355D02*
Y1581606D01*
X5396485Y1569106D01*
Y1581606D01*
G01X5402375Y1574314D02*
X5403460Y1575773D01*
X5404390Y1576606D01*
X5405630Y1577023D01*
X5406715Y1576606D01*
X5407490Y1575773D01*
X5408110Y1574523D01*
X5408265Y1573064D01*
X5408110Y1571814D01*
X5407490Y1570564D01*
X5406560Y1569523D01*
X5405475Y1569106D01*
X5404235Y1569523D01*
X5403150Y1570772D01*
X5402530Y1572648D01*
X5402375Y1574731D01*
X5402685Y1577439D01*
X5403150Y1578898D01*
X5403925Y1580356D01*
X5405010Y1581398D01*
X5406095Y1581606D01*
X5407180Y1581189D01*
X5407955Y1580148D01*
G01X5378660Y1606606D02*
X5382380D01*
G01X5380520D02*
Y1594106D01*
G01X5378660D02*
X5382380D01*
G01X5389355D02*
Y1606606D01*
X5396485Y1594106D01*
Y1606606D01*
G01X5402375Y1599314D02*
X5403460Y1600773D01*
X5404390Y1601606D01*
X5405630Y1602023D01*
X5406715Y1601606D01*
X5407490Y1600773D01*
X5408110Y1599523D01*
X5408265Y1598064D01*
X5408110Y1596814D01*
X5407490Y1595564D01*
X5406560Y1594523D01*
X5405475Y1594106D01*
X5404235Y1594523D01*
X5403150Y1595772D01*
X5402530Y1597648D01*
X5402375Y1599731D01*
X5402685Y1602439D01*
X5403150Y1603898D01*
X5403925Y1605356D01*
X5405010Y1606398D01*
X5406095Y1606606D01*
X5407180Y1606189D01*
X5407955Y1605148D01*
G01X5378660Y1631606D02*
X5382380D01*
G01X5380520D02*
Y1619106D01*
G01X5378660D02*
X5382380D01*
G01X5389355D02*
Y1631606D01*
X5396485Y1619106D01*
Y1631606D01*
G01X5402375Y1624314D02*
X5403460Y1625773D01*
X5404390Y1626606D01*
X5405630Y1627023D01*
X5406715Y1626606D01*
X5407490Y1625773D01*
X5408110Y1624523D01*
X5408265Y1623064D01*
X5408110Y1621814D01*
X5407490Y1620564D01*
X5406560Y1619523D01*
X5405475Y1619106D01*
X5404235Y1619523D01*
X5403150Y1620772D01*
X5402530Y1622648D01*
X5402375Y1624731D01*
X5402685Y1627439D01*
X5403150Y1628898D01*
X5403925Y1630356D01*
X5405010Y1631398D01*
X5406095Y1631606D01*
X5407180Y1631189D01*
X5407955Y1630148D01*
G01X5500034Y163116D02*
Y175616D01*
X5504064Y165199D01*
X5508094Y175616D01*
Y163116D01*
G01X5512589D02*
X5516464Y175616D01*
X5520339Y163116D01*
G01X5518944Y167491D02*
X5513984D01*
G01X5525609Y163116D02*
X5532119Y175616D01*
G01X5525609D02*
X5532119Y163116D01*
G01X5536614Y158949D02*
X5545914D01*
G01X5550254Y163116D02*
Y175616D01*
X5553354D01*
X5554594Y174991D01*
X5555524Y174158D01*
X5556299Y172908D01*
X5556919Y171449D01*
X5557074Y169366D01*
X5556919Y167283D01*
X5556299Y165824D01*
X5555524Y164574D01*
X5554594Y163741D01*
X5553354Y163116D01*
X5550254D01*
G01X5569164D02*
X5562964D01*
Y175616D01*
X5569164D01*
G01X5566684Y169574D02*
X5562964D01*
G01X5575364Y163116D02*
Y175616D01*
X5579084D01*
X5580324Y174991D01*
X5581254Y173533D01*
X5581564Y171866D01*
X5581254Y170199D01*
X5580479Y168949D01*
X5579084Y168324D01*
X5575364D01*
G01X5590864Y175616D02*
Y163116D01*
G01X5587299Y175616D02*
X5594429D01*
G01X5600009Y163116D02*
Y175616D01*
G01X5606519D02*
Y163116D01*
G01Y169366D02*
X5600009D01*
G01X5500000Y435935D02*
Y448435D01*
X5504030Y438018D01*
X5508060Y448435D01*
Y435935D01*
G01X5512555D02*
X5516430Y448435D01*
X5520305Y435935D01*
G01X5518910Y440310D02*
X5513950D01*
G01X5525575Y435935D02*
X5532085Y448435D01*
G01X5525575D02*
X5532085Y435935D01*
G01X5536580Y431768D02*
X5545880D01*
G01X5550220Y435935D02*
Y448435D01*
X5553320D01*
X5554560Y447810D01*
X5555490Y446977D01*
X5556265Y445727D01*
X5556885Y444268D01*
X5557040Y442185D01*
X5556885Y440102D01*
X5556265Y438643D01*
X5555490Y437393D01*
X5554560Y436560D01*
X5553320Y435935D01*
X5550220D01*
G01X5569130D02*
X5562930D01*
Y448435D01*
X5569130D01*
G01X5566650Y442393D02*
X5562930D01*
G01X5575330Y435935D02*
Y448435D01*
X5579050D01*
X5580290Y447810D01*
X5581220Y446352D01*
X5581530Y444685D01*
X5581220Y443018D01*
X5580445Y441768D01*
X5579050Y441143D01*
X5575330D01*
G01X5590830Y448435D02*
Y435935D01*
G01X5587265Y448435D02*
X5594395D01*
G01X5599975Y435935D02*
Y448435D01*
G01X5606485D02*
Y435935D01*
G01Y442185D02*
X5599975D01*
G01X5502590Y707106D02*
Y719606D01*
X5506620Y709189D01*
X5510650Y719606D01*
Y707106D01*
G01X5515145D02*
X5519020Y719606D01*
X5522895Y707106D01*
G01X5521500Y711481D02*
X5516540D01*
G01X5528165Y707106D02*
X5534675Y719606D01*
G01X5528165D02*
X5534675Y707106D01*
G01X5539170Y702939D02*
X5548470D01*
G01X5552810Y707106D02*
Y719606D01*
X5555910D01*
X5557150Y718981D01*
X5558080Y718148D01*
X5558855Y716898D01*
X5559475Y715439D01*
X5559630Y713356D01*
X5559475Y711273D01*
X5558855Y709814D01*
X5558080Y708564D01*
X5557150Y707731D01*
X5555910Y707106D01*
X5552810D01*
G01X5571720D02*
X5565520D01*
Y719606D01*
X5571720D01*
G01X5569240Y713564D02*
X5565520D01*
G01X5577920Y707106D02*
Y719606D01*
X5581640D01*
X5582880Y718981D01*
X5583810Y717523D01*
X5584120Y715856D01*
X5583810Y714189D01*
X5583035Y712939D01*
X5581640Y712314D01*
X5577920D01*
G01X5593420Y719606D02*
Y707106D01*
G01X5589855Y719606D02*
X5596985D01*
G01X5602565Y707106D02*
Y719606D01*
G01X5609075D02*
Y707106D01*
G01Y713356D02*
X5602565D01*
G01X5504590Y1014606D02*
Y1027106D01*
X5508620Y1016689D01*
X5512650Y1027106D01*
Y1014606D01*
G01X5517145D02*
X5521020Y1027106D01*
X5524895Y1014606D01*
G01X5523500Y1018981D02*
X5518540D01*
G01X5530165Y1014606D02*
X5536675Y1027106D01*
G01X5530165D02*
X5536675Y1014606D01*
G01X5541170Y1010439D02*
X5550470D01*
G01X5554810Y1014606D02*
Y1027106D01*
X5557910D01*
X5559150Y1026481D01*
X5560080Y1025648D01*
X5560855Y1024398D01*
X5561475Y1022939D01*
X5561630Y1020856D01*
X5561475Y1018773D01*
X5560855Y1017314D01*
X5560080Y1016064D01*
X5559150Y1015231D01*
X5557910Y1014606D01*
X5554810D01*
G01X5573720D02*
X5567520D01*
Y1027106D01*
X5573720D01*
G01X5571240Y1021064D02*
X5567520D01*
G01X5579920Y1014606D02*
Y1027106D01*
X5583640D01*
X5584880Y1026481D01*
X5585810Y1025023D01*
X5586120Y1023356D01*
X5585810Y1021689D01*
X5585035Y1020439D01*
X5583640Y1019814D01*
X5579920D01*
G01X5595420Y1027106D02*
Y1014606D01*
G01X5591855Y1027106D02*
X5598985D01*
G01X5604565Y1014606D02*
Y1027106D01*
G01X5611075D02*
Y1014606D01*
G01Y1020856D02*
X5604565D01*
G01X5503590Y1328606D02*
Y1341106D01*
X5507620Y1330689D01*
X5511650Y1341106D01*
Y1328606D01*
G01X5516145D02*
X5520020Y1341106D01*
X5523895Y1328606D01*
G01X5522500Y1332981D02*
X5517540D01*
G01X5529165Y1328606D02*
X5535675Y1341106D01*
G01X5529165D02*
X5535675Y1328606D01*
G01X5540170Y1324439D02*
X5549470D01*
G01X5553810Y1328606D02*
Y1341106D01*
X5556910D01*
X5558150Y1340481D01*
X5559080Y1339648D01*
X5559855Y1338398D01*
X5560475Y1336939D01*
X5560630Y1334856D01*
X5560475Y1332773D01*
X5559855Y1331314D01*
X5559080Y1330064D01*
X5558150Y1329231D01*
X5556910Y1328606D01*
X5553810D01*
G01X5572720D02*
X5566520D01*
Y1341106D01*
X5572720D01*
G01X5570240Y1335064D02*
X5566520D01*
G01X5578920Y1328606D02*
Y1341106D01*
X5582640D01*
X5583880Y1340481D01*
X5584810Y1339023D01*
X5585120Y1337356D01*
X5584810Y1335689D01*
X5584035Y1334439D01*
X5582640Y1333814D01*
X5578920D01*
G01X5594420Y1341106D02*
Y1328606D01*
G01X5590855Y1341106D02*
X5597985D01*
G01X5603565Y1328606D02*
Y1341106D01*
G01X5610075D02*
Y1328606D01*
G01Y1334856D02*
X5603565D01*
G01X5503590Y1644106D02*
Y1656606D01*
X5507620Y1646189D01*
X5511650Y1656606D01*
Y1644106D01*
G01X5516145D02*
X5520020Y1656606D01*
X5523895Y1644106D01*
G01X5522500Y1648481D02*
X5517540D01*
G01X5529165Y1644106D02*
X5535675Y1656606D01*
G01X5529165D02*
X5535675Y1644106D01*
G01X5540170Y1639939D02*
X5549470D01*
G01X5553810Y1644106D02*
Y1656606D01*
X5556910D01*
X5558150Y1655981D01*
X5559080Y1655148D01*
X5559855Y1653898D01*
X5560475Y1652439D01*
X5560630Y1650356D01*
X5560475Y1648273D01*
X5559855Y1646814D01*
X5559080Y1645564D01*
X5558150Y1644731D01*
X5556910Y1644106D01*
X5553810D01*
G01X5572720D02*
X5566520D01*
Y1656606D01*
X5572720D01*
G01X5570240Y1650564D02*
X5566520D01*
G01X5578920Y1644106D02*
Y1656606D01*
X5582640D01*
X5583880Y1655981D01*
X5584810Y1654523D01*
X5585120Y1652856D01*
X5584810Y1651189D01*
X5584035Y1649939D01*
X5582640Y1649314D01*
X5578920D01*
G01X5594420Y1656606D02*
Y1644106D01*
G01X5590855Y1656606D02*
X5597985D01*
G01X5603565Y1644106D02*
Y1656606D01*
G01X5610075D02*
Y1644106D01*
G01Y1650356D02*
X5603565D01*
G01X5535064Y113116D02*
X5536149Y113324D01*
X5537389Y113949D01*
X5538164Y114991D01*
X5538474Y116449D01*
X5538164Y117907D01*
X5537234Y119158D01*
X5535839Y119783D01*
X5534289D01*
X5533359Y120199D01*
X5532584Y121241D01*
X5532274Y122699D01*
X5532739Y124158D01*
X5533824Y125199D01*
X5535064Y125616D01*
X5536304Y125199D01*
X5537389Y124158D01*
X5537854Y122699D01*
X5537544Y121241D01*
X5536769Y120199D01*
X5535839Y119783D01*
X5534289D01*
X5532894Y119158D01*
X5531964Y117907D01*
X5531654Y116449D01*
X5531964Y114991D01*
X5532739Y113949D01*
X5533979Y113324D01*
X5535064Y113116D01*
G01X5544054Y115616D02*
X5544984Y114157D01*
X5546224Y113324D01*
X5547619Y113116D01*
X5548859Y113324D01*
X5550099Y114366D01*
X5550874Y115616D01*
X5551029Y116866D01*
X5550719Y118324D01*
X5549634Y119366D01*
X5548549Y119783D01*
X5547154D01*
G01X5548549D02*
X5549479Y120408D01*
X5550254Y121449D01*
X5550564Y122699D01*
X5550254Y123949D01*
X5549479Y124991D01*
X5548084Y125616D01*
X5546689Y125408D01*
X5545294Y124574D01*
G01X5559864Y112699D02*
X5559554Y112908D01*
Y113324D01*
X5559864Y113533D01*
X5560174Y113324D01*
Y112908D01*
X5559864Y112699D01*
G01X5569319Y118324D02*
X5570404Y119783D01*
X5571334Y120616D01*
X5572574Y121033D01*
X5573659Y120616D01*
X5574434Y119783D01*
X5575054Y118533D01*
X5575209Y117074D01*
X5575054Y115824D01*
X5574434Y114574D01*
X5573504Y113533D01*
X5572419Y113116D01*
X5571179Y113533D01*
X5570094Y114782D01*
X5569474Y116658D01*
X5569319Y118741D01*
X5569629Y121449D01*
X5570094Y122908D01*
X5570869Y124366D01*
X5571954Y125408D01*
X5573039Y125616D01*
X5574124Y125199D01*
X5574899Y124158D01*
G01X5535064Y138116D02*
X5536149Y138324D01*
X5537389Y138949D01*
X5538164Y139991D01*
X5538474Y141449D01*
X5538164Y142907D01*
X5537234Y144158D01*
X5535839Y144783D01*
X5534289D01*
X5533359Y145199D01*
X5532584Y146241D01*
X5532274Y147699D01*
X5532739Y149158D01*
X5533824Y150199D01*
X5535064Y150616D01*
X5536304Y150199D01*
X5537389Y149158D01*
X5537854Y147699D01*
X5537544Y146241D01*
X5536769Y145199D01*
X5535839Y144783D01*
X5534289D01*
X5532894Y144158D01*
X5531964Y142907D01*
X5531654Y141449D01*
X5531964Y139991D01*
X5532739Y138949D01*
X5533979Y138324D01*
X5535064Y138116D01*
G01X5544054Y140616D02*
X5544984Y139157D01*
X5546224Y138324D01*
X5547619Y138116D01*
X5548859Y138324D01*
X5550099Y139366D01*
X5550874Y140616D01*
X5551029Y141866D01*
X5550719Y143324D01*
X5549634Y144366D01*
X5548549Y144783D01*
X5547154D01*
G01X5548549D02*
X5549479Y145408D01*
X5550254Y146449D01*
X5550564Y147699D01*
X5550254Y148949D01*
X5549479Y149991D01*
X5548084Y150616D01*
X5546689Y150408D01*
X5545294Y149574D01*
G01X5559864Y137699D02*
X5559554Y137908D01*
Y138324D01*
X5559864Y138533D01*
X5560174Y138324D01*
Y137908D01*
X5559864Y137699D01*
G01X5569319Y143324D02*
X5570404Y144783D01*
X5571334Y145616D01*
X5572574Y146033D01*
X5573659Y145616D01*
X5574434Y144783D01*
X5575054Y143533D01*
X5575209Y142074D01*
X5575054Y140824D01*
X5574434Y139574D01*
X5573504Y138533D01*
X5572419Y138116D01*
X5571179Y138533D01*
X5570094Y139782D01*
X5569474Y141658D01*
X5569319Y143741D01*
X5569629Y146449D01*
X5570094Y147908D01*
X5570869Y149366D01*
X5571954Y150408D01*
X5573039Y150616D01*
X5574124Y150199D01*
X5574899Y149158D01*
G01X5528520Y385935D02*
X5528830Y388643D01*
X5529295Y390935D01*
X5529915Y393018D01*
X5530690Y395310D01*
X5531930Y398435D01*
X5525730D01*
G01X5538285Y396352D02*
X5539215Y397601D01*
X5540300Y398227D01*
X5541540Y398435D01*
X5543090Y398018D01*
X5544175Y396977D01*
X5544485Y395727D01*
X5544330Y394476D01*
X5543710Y393435D01*
X5540610Y391352D01*
X5539215Y389893D01*
X5538285Y387810D01*
X5537975Y385935D01*
X5544485D01*
G01X5553630Y385518D02*
X5553320Y385727D01*
Y386143D01*
X5553630Y386352D01*
X5553940Y386143D01*
Y385727D01*
X5553630Y385518D01*
G01X5563085Y391143D02*
X5564170Y392602D01*
X5565100Y393435D01*
X5566340Y393852D01*
X5567425Y393435D01*
X5568200Y392602D01*
X5568820Y391352D01*
X5568975Y389893D01*
X5568820Y388643D01*
X5568200Y387393D01*
X5567270Y386352D01*
X5566185Y385935D01*
X5564945Y386352D01*
X5563860Y387601D01*
X5563240Y389477D01*
X5563085Y391560D01*
X5563395Y394268D01*
X5563860Y395727D01*
X5564635Y397185D01*
X5565720Y398227D01*
X5566805Y398435D01*
X5567890Y398018D01*
X5568665Y396977D01*
G01X5575020Y387810D02*
X5575950Y386768D01*
X5577035Y386143D01*
X5578430Y385935D01*
X5579825Y386352D01*
X5580910Y387185D01*
X5581685Y388643D01*
X5581840Y390310D01*
X5581530Y391977D01*
X5580755Y393018D01*
X5579670Y393852D01*
X5578585Y394060D01*
X5577500Y393852D01*
X5576105Y393018D01*
X5576570Y398435D01*
X5580755D01*
G01X5528520Y410935D02*
X5528830Y413643D01*
X5529295Y415935D01*
X5529915Y418018D01*
X5530690Y420310D01*
X5531930Y423435D01*
X5525730D01*
G01X5538285Y421352D02*
X5539215Y422601D01*
X5540300Y423227D01*
X5541540Y423435D01*
X5543090Y423018D01*
X5544175Y421977D01*
X5544485Y420727D01*
X5544330Y419476D01*
X5543710Y418435D01*
X5540610Y416352D01*
X5539215Y414893D01*
X5538285Y412810D01*
X5537975Y410935D01*
X5544485D01*
G01X5553630Y410518D02*
X5553320Y410727D01*
Y411143D01*
X5553630Y411352D01*
X5553940Y411143D01*
Y410727D01*
X5553630Y410518D01*
G01X5563085Y416143D02*
X5564170Y417602D01*
X5565100Y418435D01*
X5566340Y418852D01*
X5567425Y418435D01*
X5568200Y417602D01*
X5568820Y416352D01*
X5568975Y414893D01*
X5568820Y413643D01*
X5568200Y412393D01*
X5567270Y411352D01*
X5566185Y410935D01*
X5564945Y411352D01*
X5563860Y412601D01*
X5563240Y414477D01*
X5563085Y416560D01*
X5563395Y419268D01*
X5563860Y420727D01*
X5564635Y422185D01*
X5565720Y423227D01*
X5566805Y423435D01*
X5567890Y423018D01*
X5568665Y421977D01*
G01X5575020Y412810D02*
X5575950Y411768D01*
X5577035Y411143D01*
X5578430Y410935D01*
X5579825Y411352D01*
X5580910Y412185D01*
X5581685Y413643D01*
X5581840Y415310D01*
X5581530Y416977D01*
X5580755Y418018D01*
X5579670Y418852D01*
X5578585Y419060D01*
X5577500Y418852D01*
X5576105Y418018D01*
X5576570Y423435D01*
X5580755D01*
G01X5534675Y662314D02*
X5535760Y663773D01*
X5536690Y664606D01*
X5537930Y665023D01*
X5539015Y664606D01*
X5539790Y663773D01*
X5540410Y662523D01*
X5540565Y661064D01*
X5540410Y659814D01*
X5539790Y658564D01*
X5538860Y657523D01*
X5537775Y657106D01*
X5536535Y657523D01*
X5535450Y658772D01*
X5534830Y660648D01*
X5534675Y662731D01*
X5534985Y665439D01*
X5535450Y666898D01*
X5536225Y668356D01*
X5537310Y669398D01*
X5538395Y669606D01*
X5539480Y669189D01*
X5540255Y668148D01*
G01X5550020Y657106D02*
Y669606D01*
X5548160Y667106D01*
G01Y657106D02*
X5551880D01*
G01X5562420Y656689D02*
X5562110Y656898D01*
Y657314D01*
X5562420Y657523D01*
X5562730Y657314D01*
Y656898D01*
X5562420Y656689D01*
G01X5574510Y657106D02*
X5574820Y659814D01*
X5575285Y662106D01*
X5575905Y664189D01*
X5576680Y666481D01*
X5577920Y669606D01*
X5571720D01*
G01X5534675Y687314D02*
X5535760Y688773D01*
X5536690Y689606D01*
X5537930Y690023D01*
X5539015Y689606D01*
X5539790Y688773D01*
X5540410Y687523D01*
X5540565Y686064D01*
X5540410Y684814D01*
X5539790Y683564D01*
X5538860Y682523D01*
X5537775Y682106D01*
X5536535Y682523D01*
X5535450Y683772D01*
X5534830Y685648D01*
X5534675Y687731D01*
X5534985Y690439D01*
X5535450Y691898D01*
X5536225Y693356D01*
X5537310Y694398D01*
X5538395Y694606D01*
X5539480Y694189D01*
X5540255Y693148D01*
G01X5550020Y682106D02*
Y694606D01*
X5548160Y692106D01*
G01Y682106D02*
X5551880D01*
G01X5562420Y681689D02*
X5562110Y681898D01*
Y682314D01*
X5562420Y682523D01*
X5562730Y682314D01*
Y681898D01*
X5562420Y681689D01*
G01X5574510Y682106D02*
X5574820Y684814D01*
X5575285Y687106D01*
X5575905Y689189D01*
X5576680Y691481D01*
X5577920Y694606D01*
X5571720D01*
G01X5536210Y917106D02*
X5537140Y915647D01*
X5538380Y914814D01*
X5539775Y914606D01*
X5541015Y914814D01*
X5542255Y915856D01*
X5543030Y917106D01*
X5543185Y918356D01*
X5542875Y919814D01*
X5541790Y920856D01*
X5540705Y921273D01*
X5539310D01*
G01X5540705D02*
X5541635Y921898D01*
X5542410Y922939D01*
X5542720Y924189D01*
X5542410Y925439D01*
X5541635Y926481D01*
X5540240Y927106D01*
X5538845Y926898D01*
X5537450Y926064D01*
G01X5552020Y927106D02*
X5550780Y926689D01*
X5549850Y925648D01*
X5549230Y924398D01*
X5548765Y922731D01*
X5548610Y920856D01*
X5548765Y918981D01*
X5549230Y917314D01*
X5549850Y916064D01*
X5550780Y915023D01*
X5552020Y914606D01*
X5553260Y915023D01*
X5554190Y916064D01*
X5554810Y917314D01*
X5555275Y918981D01*
X5555430Y920856D01*
X5555275Y922731D01*
X5554810Y924398D01*
X5554190Y925648D01*
X5553260Y926689D01*
X5552020Y927106D01*
G01X5564420Y914189D02*
X5564110Y914398D01*
Y914814D01*
X5564420Y915023D01*
X5564730Y914814D01*
Y914398D01*
X5564420Y914189D01*
G01X5576820Y914606D02*
X5577905Y914814D01*
X5579145Y915439D01*
X5579920Y916481D01*
X5580230Y917939D01*
X5579920Y919397D01*
X5578990Y920648D01*
X5577595Y921273D01*
X5576045D01*
X5575115Y921689D01*
X5574340Y922731D01*
X5574030Y924189D01*
X5574495Y925648D01*
X5575580Y926689D01*
X5576820Y927106D01*
X5578060Y926689D01*
X5579145Y925648D01*
X5579610Y924189D01*
X5579300Y922731D01*
X5578525Y921689D01*
X5577595Y921273D01*
X5576045D01*
X5574650Y920648D01*
X5573720Y919397D01*
X5573410Y917939D01*
X5573720Y916481D01*
X5574495Y915439D01*
X5575735Y914814D01*
X5576820Y914606D01*
G01X5536210Y942106D02*
X5537140Y940647D01*
X5538380Y939814D01*
X5539775Y939606D01*
X5541015Y939814D01*
X5542255Y940856D01*
X5543030Y942106D01*
X5543185Y943356D01*
X5542875Y944814D01*
X5541790Y945856D01*
X5540705Y946273D01*
X5539310D01*
G01X5540705D02*
X5541635Y946898D01*
X5542410Y947939D01*
X5542720Y949189D01*
X5542410Y950439D01*
X5541635Y951481D01*
X5540240Y952106D01*
X5538845Y951898D01*
X5537450Y951064D01*
G01X5552020Y952106D02*
X5550780Y951689D01*
X5549850Y950648D01*
X5549230Y949398D01*
X5548765Y947731D01*
X5548610Y945856D01*
X5548765Y943981D01*
X5549230Y942314D01*
X5549850Y941064D01*
X5550780Y940023D01*
X5552020Y939606D01*
X5553260Y940023D01*
X5554190Y941064D01*
X5554810Y942314D01*
X5555275Y943981D01*
X5555430Y945856D01*
X5555275Y947731D01*
X5554810Y949398D01*
X5554190Y950648D01*
X5553260Y951689D01*
X5552020Y952106D01*
G01X5564420Y939189D02*
X5564110Y939398D01*
Y939814D01*
X5564420Y940023D01*
X5564730Y939814D01*
Y939398D01*
X5564420Y939189D01*
G01X5576820Y939606D02*
X5577905Y939814D01*
X5579145Y940439D01*
X5579920Y941481D01*
X5580230Y942939D01*
X5579920Y944397D01*
X5578990Y945648D01*
X5577595Y946273D01*
X5576045D01*
X5575115Y946689D01*
X5574340Y947731D01*
X5574030Y949189D01*
X5574495Y950648D01*
X5575580Y951689D01*
X5576820Y952106D01*
X5578060Y951689D01*
X5579145Y950648D01*
X5579610Y949189D01*
X5579300Y947731D01*
X5578525Y946689D01*
X5577595Y946273D01*
X5576045D01*
X5574650Y945648D01*
X5573720Y944397D01*
X5573410Y942939D01*
X5573720Y941481D01*
X5574495Y940439D01*
X5575735Y939814D01*
X5576820Y939606D01*
G01X5536210Y967106D02*
X5537140Y965647D01*
X5538380Y964814D01*
X5539775Y964606D01*
X5541015Y964814D01*
X5542255Y965856D01*
X5543030Y967106D01*
X5543185Y968356D01*
X5542875Y969814D01*
X5541790Y970856D01*
X5540705Y971273D01*
X5539310D01*
G01X5540705D02*
X5541635Y971898D01*
X5542410Y972939D01*
X5542720Y974189D01*
X5542410Y975439D01*
X5541635Y976481D01*
X5540240Y977106D01*
X5538845Y976898D01*
X5537450Y976064D01*
G01X5552020Y977106D02*
X5550780Y976689D01*
X5549850Y975648D01*
X5549230Y974398D01*
X5548765Y972731D01*
X5548610Y970856D01*
X5548765Y968981D01*
X5549230Y967314D01*
X5549850Y966064D01*
X5550780Y965023D01*
X5552020Y964606D01*
X5553260Y965023D01*
X5554190Y966064D01*
X5554810Y967314D01*
X5555275Y968981D01*
X5555430Y970856D01*
X5555275Y972731D01*
X5554810Y974398D01*
X5554190Y975648D01*
X5553260Y976689D01*
X5552020Y977106D01*
G01X5564420Y964189D02*
X5564110Y964398D01*
Y964814D01*
X5564420Y965023D01*
X5564730Y964814D01*
Y964398D01*
X5564420Y964189D01*
G01X5576820Y964606D02*
X5577905Y964814D01*
X5579145Y965439D01*
X5579920Y966481D01*
X5580230Y967939D01*
X5579920Y969397D01*
X5578990Y970648D01*
X5577595Y971273D01*
X5576045D01*
X5575115Y971689D01*
X5574340Y972731D01*
X5574030Y974189D01*
X5574495Y975648D01*
X5575580Y976689D01*
X5576820Y977106D01*
X5578060Y976689D01*
X5579145Y975648D01*
X5579610Y974189D01*
X5579300Y972731D01*
X5578525Y971689D01*
X5577595Y971273D01*
X5576045D01*
X5574650Y970648D01*
X5573720Y969397D01*
X5573410Y967939D01*
X5573720Y966481D01*
X5574495Y965439D01*
X5575735Y964814D01*
X5576820Y964606D01*
G01X5536210Y992106D02*
X5537140Y990647D01*
X5538380Y989814D01*
X5539775Y989606D01*
X5541015Y989814D01*
X5542255Y990856D01*
X5543030Y992106D01*
X5543185Y993356D01*
X5542875Y994814D01*
X5541790Y995856D01*
X5540705Y996273D01*
X5539310D01*
G01X5540705D02*
X5541635Y996898D01*
X5542410Y997939D01*
X5542720Y999189D01*
X5542410Y1000439D01*
X5541635Y1001481D01*
X5540240Y1002106D01*
X5538845Y1001898D01*
X5537450Y1001064D01*
G01X5552020Y1002106D02*
X5550780Y1001689D01*
X5549850Y1000648D01*
X5549230Y999398D01*
X5548765Y997731D01*
X5548610Y995856D01*
X5548765Y993981D01*
X5549230Y992314D01*
X5549850Y991064D01*
X5550780Y990023D01*
X5552020Y989606D01*
X5553260Y990023D01*
X5554190Y991064D01*
X5554810Y992314D01*
X5555275Y993981D01*
X5555430Y995856D01*
X5555275Y997731D01*
X5554810Y999398D01*
X5554190Y1000648D01*
X5553260Y1001689D01*
X5552020Y1002106D01*
G01X5564420Y989189D02*
X5564110Y989398D01*
Y989814D01*
X5564420Y990023D01*
X5564730Y989814D01*
Y989398D01*
X5564420Y989189D01*
G01X5576820Y989606D02*
X5577905Y989814D01*
X5579145Y990439D01*
X5579920Y991481D01*
X5580230Y992939D01*
X5579920Y994397D01*
X5578990Y995648D01*
X5577595Y996273D01*
X5576045D01*
X5575115Y996689D01*
X5574340Y997731D01*
X5574030Y999189D01*
X5574495Y1000648D01*
X5575580Y1001689D01*
X5576820Y1002106D01*
X5578060Y1001689D01*
X5579145Y1000648D01*
X5579610Y999189D01*
X5579300Y997731D01*
X5578525Y996689D01*
X5577595Y996273D01*
X5576045D01*
X5574650Y995648D01*
X5573720Y994397D01*
X5573410Y992939D01*
X5573720Y991481D01*
X5574495Y990439D01*
X5575735Y989814D01*
X5576820Y989606D01*
G01X5532420Y1228606D02*
Y1241106D01*
X5530560Y1238606D01*
G01Y1228606D02*
X5534280D01*
G01X5542185Y1230064D02*
X5543270Y1229023D01*
X5544510Y1228606D01*
X5545750Y1229023D01*
X5546835Y1230272D01*
X5547610Y1232148D01*
X5547920Y1234023D01*
Y1236314D01*
X5547610Y1238189D01*
X5546835Y1239856D01*
X5545905Y1240689D01*
X5544820Y1241106D01*
X5543580Y1240689D01*
X5542650Y1239856D01*
X5542030Y1238606D01*
X5541720Y1236939D01*
X5542030Y1235481D01*
X5542805Y1234023D01*
X5543735Y1233189D01*
X5544820Y1232981D01*
X5546060Y1233397D01*
X5546990Y1234439D01*
X5547920Y1236314D01*
G01X5557220Y1228189D02*
X5556910Y1228398D01*
Y1228814D01*
X5557220Y1229023D01*
X5557530Y1228814D01*
Y1228398D01*
X5557220Y1228189D01*
G01X5569620Y1228606D02*
X5570705Y1228814D01*
X5571945Y1229439D01*
X5572720Y1230481D01*
X5573030Y1231939D01*
X5572720Y1233397D01*
X5571790Y1234648D01*
X5570395Y1235273D01*
X5568845D01*
X5567915Y1235689D01*
X5567140Y1236731D01*
X5566830Y1238189D01*
X5567295Y1239648D01*
X5568380Y1240689D01*
X5569620Y1241106D01*
X5570860Y1240689D01*
X5571945Y1239648D01*
X5572410Y1238189D01*
X5572100Y1236731D01*
X5571325Y1235689D01*
X5570395Y1235273D01*
X5568845D01*
X5567450Y1234648D01*
X5566520Y1233397D01*
X5566210Y1231939D01*
X5566520Y1230481D01*
X5567295Y1229439D01*
X5568535Y1228814D01*
X5569620Y1228606D01*
G01X5578610Y1230481D02*
X5579540Y1229439D01*
X5580625Y1228814D01*
X5582020Y1228606D01*
X5583415Y1229023D01*
X5584500Y1229856D01*
X5585275Y1231314D01*
X5585430Y1232981D01*
X5585120Y1234648D01*
X5584345Y1235689D01*
X5583260Y1236523D01*
X5582175Y1236731D01*
X5581090Y1236523D01*
X5579695Y1235689D01*
X5580160Y1241106D01*
X5584345D01*
G01X5532420Y1253606D02*
Y1266106D01*
X5530560Y1263606D01*
G01Y1253606D02*
X5534280D01*
G01X5542185Y1255064D02*
X5543270Y1254023D01*
X5544510Y1253606D01*
X5545750Y1254023D01*
X5546835Y1255272D01*
X5547610Y1257148D01*
X5547920Y1259023D01*
Y1261314D01*
X5547610Y1263189D01*
X5546835Y1264856D01*
X5545905Y1265689D01*
X5544820Y1266106D01*
X5543580Y1265689D01*
X5542650Y1264856D01*
X5542030Y1263606D01*
X5541720Y1261939D01*
X5542030Y1260481D01*
X5542805Y1259023D01*
X5543735Y1258189D01*
X5544820Y1257981D01*
X5546060Y1258397D01*
X5546990Y1259439D01*
X5547920Y1261314D01*
G01X5557220Y1253189D02*
X5556910Y1253398D01*
Y1253814D01*
X5557220Y1254023D01*
X5557530Y1253814D01*
Y1253398D01*
X5557220Y1253189D01*
G01X5569620Y1253606D02*
X5570705Y1253814D01*
X5571945Y1254439D01*
X5572720Y1255481D01*
X5573030Y1256939D01*
X5572720Y1258397D01*
X5571790Y1259648D01*
X5570395Y1260273D01*
X5568845D01*
X5567915Y1260689D01*
X5567140Y1261731D01*
X5566830Y1263189D01*
X5567295Y1264648D01*
X5568380Y1265689D01*
X5569620Y1266106D01*
X5570860Y1265689D01*
X5571945Y1264648D01*
X5572410Y1263189D01*
X5572100Y1261731D01*
X5571325Y1260689D01*
X5570395Y1260273D01*
X5568845D01*
X5567450Y1259648D01*
X5566520Y1258397D01*
X5566210Y1256939D01*
X5566520Y1255481D01*
X5567295Y1254439D01*
X5568535Y1253814D01*
X5569620Y1253606D01*
G01X5578610Y1255481D02*
X5579540Y1254439D01*
X5580625Y1253814D01*
X5582020Y1253606D01*
X5583415Y1254023D01*
X5584500Y1254856D01*
X5585275Y1256314D01*
X5585430Y1257981D01*
X5585120Y1259648D01*
X5584345Y1260689D01*
X5583260Y1261523D01*
X5582175Y1261731D01*
X5581090Y1261523D01*
X5579695Y1260689D01*
X5580160Y1266106D01*
X5584345D01*
G01X5532420Y1278606D02*
Y1291106D01*
X5530560Y1288606D01*
G01Y1278606D02*
X5534280D01*
G01X5542185Y1280064D02*
X5543270Y1279023D01*
X5544510Y1278606D01*
X5545750Y1279023D01*
X5546835Y1280272D01*
X5547610Y1282148D01*
X5547920Y1284023D01*
Y1286314D01*
X5547610Y1288189D01*
X5546835Y1289856D01*
X5545905Y1290689D01*
X5544820Y1291106D01*
X5543580Y1290689D01*
X5542650Y1289856D01*
X5542030Y1288606D01*
X5541720Y1286939D01*
X5542030Y1285481D01*
X5542805Y1284023D01*
X5543735Y1283189D01*
X5544820Y1282981D01*
X5546060Y1283397D01*
X5546990Y1284439D01*
X5547920Y1286314D01*
G01X5557220Y1278189D02*
X5556910Y1278398D01*
Y1278814D01*
X5557220Y1279023D01*
X5557530Y1278814D01*
Y1278398D01*
X5557220Y1278189D01*
G01X5569620Y1278606D02*
X5570705Y1278814D01*
X5571945Y1279439D01*
X5572720Y1280481D01*
X5573030Y1281939D01*
X5572720Y1283397D01*
X5571790Y1284648D01*
X5570395Y1285273D01*
X5568845D01*
X5567915Y1285689D01*
X5567140Y1286731D01*
X5566830Y1288189D01*
X5567295Y1289648D01*
X5568380Y1290689D01*
X5569620Y1291106D01*
X5570860Y1290689D01*
X5571945Y1289648D01*
X5572410Y1288189D01*
X5572100Y1286731D01*
X5571325Y1285689D01*
X5570395Y1285273D01*
X5568845D01*
X5567450Y1284648D01*
X5566520Y1283397D01*
X5566210Y1281939D01*
X5566520Y1280481D01*
X5567295Y1279439D01*
X5568535Y1278814D01*
X5569620Y1278606D01*
G01X5578610Y1280481D02*
X5579540Y1279439D01*
X5580625Y1278814D01*
X5582020Y1278606D01*
X5583415Y1279023D01*
X5584500Y1279856D01*
X5585275Y1281314D01*
X5585430Y1282981D01*
X5585120Y1284648D01*
X5584345Y1285689D01*
X5583260Y1286523D01*
X5582175Y1286731D01*
X5581090Y1286523D01*
X5579695Y1285689D01*
X5580160Y1291106D01*
X5584345D01*
G01X5532420Y1303606D02*
Y1316106D01*
X5530560Y1313606D01*
G01Y1303606D02*
X5534280D01*
G01X5542185Y1305064D02*
X5543270Y1304023D01*
X5544510Y1303606D01*
X5545750Y1304023D01*
X5546835Y1305272D01*
X5547610Y1307148D01*
X5547920Y1309023D01*
Y1311314D01*
X5547610Y1313189D01*
X5546835Y1314856D01*
X5545905Y1315689D01*
X5544820Y1316106D01*
X5543580Y1315689D01*
X5542650Y1314856D01*
X5542030Y1313606D01*
X5541720Y1311939D01*
X5542030Y1310481D01*
X5542805Y1309023D01*
X5543735Y1308189D01*
X5544820Y1307981D01*
X5546060Y1308397D01*
X5546990Y1309439D01*
X5547920Y1311314D01*
G01X5557220Y1303189D02*
X5556910Y1303398D01*
Y1303814D01*
X5557220Y1304023D01*
X5557530Y1303814D01*
Y1303398D01*
X5557220Y1303189D01*
G01X5569620Y1303606D02*
X5570705Y1303814D01*
X5571945Y1304439D01*
X5572720Y1305481D01*
X5573030Y1306939D01*
X5572720Y1308397D01*
X5571790Y1309648D01*
X5570395Y1310273D01*
X5568845D01*
X5567915Y1310689D01*
X5567140Y1311731D01*
X5566830Y1313189D01*
X5567295Y1314648D01*
X5568380Y1315689D01*
X5569620Y1316106D01*
X5570860Y1315689D01*
X5571945Y1314648D01*
X5572410Y1313189D01*
X5572100Y1311731D01*
X5571325Y1310689D01*
X5570395Y1310273D01*
X5568845D01*
X5567450Y1309648D01*
X5566520Y1308397D01*
X5566210Y1306939D01*
X5566520Y1305481D01*
X5567295Y1304439D01*
X5568535Y1303814D01*
X5569620Y1303606D01*
G01X5578610Y1305481D02*
X5579540Y1304439D01*
X5580625Y1303814D01*
X5582020Y1303606D01*
X5583415Y1304023D01*
X5584500Y1304856D01*
X5585275Y1306314D01*
X5585430Y1307981D01*
X5585120Y1309648D01*
X5584345Y1310689D01*
X5583260Y1311523D01*
X5582175Y1311731D01*
X5581090Y1311523D01*
X5579695Y1310689D01*
X5580160Y1316106D01*
X5584345D01*
G01X5544264Y100616D02*
Y88116D01*
G01X5540699Y100616D02*
X5547829D01*
G01X5556664Y88116D02*
X5555424Y88324D01*
X5554339Y89157D01*
X5553409Y90408D01*
X5552789Y91866D01*
X5552479Y93533D01*
Y95199D01*
X5552789Y96866D01*
X5553409Y98324D01*
X5554339Y99574D01*
X5555424Y100408D01*
X5556664Y100616D01*
X5557904Y100408D01*
X5558989Y99574D01*
X5559919Y98324D01*
X5560539Y96866D01*
X5560849Y95199D01*
Y93533D01*
X5560539Y91866D01*
X5559919Y90408D01*
X5558989Y89157D01*
X5557904Y88324D01*
X5556664Y88116D01*
G01X5569064Y100616D02*
Y88116D01*
G01X5565499Y100616D02*
X5572629D01*
G01X5577589Y88116D02*
X5581464Y100616D01*
X5585339Y88116D01*
G01X5583944Y92491D02*
X5578984D01*
G01X5590764Y100616D02*
Y88116D01*
X5596964D01*
G01X5619904Y94783D02*
X5620524Y95408D01*
X5620989Y96449D01*
X5621299Y97908D01*
X5620989Y99158D01*
X5620369Y99991D01*
X5619284Y100616D01*
X5615099D01*
Y88116D01*
X5620214D01*
X5621299Y88949D01*
X5621919Y90199D01*
X5622229Y91658D01*
X5621919Y93116D01*
X5620989Y94366D01*
X5619904Y94783D01*
X5615099D01*
G01X5627189Y88116D02*
X5631064Y100616D01*
X5634939Y88116D01*
G01X5633544Y92491D02*
X5628584D01*
G01X5646874Y99574D02*
X5645944Y100199D01*
X5644859Y100616D01*
X5643619D01*
X5642224Y99991D01*
X5641139Y98949D01*
X5640364Y97699D01*
X5639744Y95616D01*
X5639589Y93741D01*
X5639899Y91866D01*
X5640364Y90616D01*
X5641294Y89366D01*
X5642379Y88533D01*
X5643464Y88116D01*
X5644549D01*
X5645634Y88533D01*
X5646564Y89157D01*
X5647339Y89991D01*
G01X5652454Y88116D02*
Y100616D01*
G01X5658344D02*
X5652454Y92907D01*
G01X5659274Y88116D02*
X5655089Y96449D01*
G01X5664854Y88116D02*
Y100616D01*
X5667954D01*
X5669194Y99991D01*
X5670124Y99158D01*
X5670899Y97908D01*
X5671519Y96449D01*
X5671674Y94366D01*
X5671519Y92283D01*
X5670899Y90824D01*
X5670124Y89574D01*
X5669194Y88741D01*
X5667954Y88116D01*
X5664854D01*
G01X5677564D02*
Y100616D01*
X5681439D01*
X5682679Y99991D01*
X5683454Y99158D01*
X5683764Y97491D01*
X5683454Y95824D01*
X5682524Y94783D01*
X5681439Y94158D01*
X5677564D01*
G01X5681439D02*
X5683764Y88116D01*
G01X5691204Y100616D02*
X5694924D01*
G01X5693064D02*
Y88116D01*
G01X5691204D02*
X5694924D01*
G01X5702364Y100616D02*
Y88116D01*
X5708564D01*
G01X5714764Y100616D02*
Y88116D01*
X5720964D01*
G01X5727009Y89782D02*
X5728249Y88741D01*
X5729644Y88116D01*
X5730884D01*
X5732124Y88741D01*
X5733054Y89782D01*
X5733519Y91241D01*
X5733209Y92699D01*
X5732434Y93949D01*
X5731039Y94783D01*
X5729179Y95199D01*
X5728094Y96033D01*
X5727629Y97491D01*
X5727939Y98949D01*
X5728714Y99991D01*
X5729799Y100616D01*
X5730884D01*
X5731969Y100199D01*
X5732899Y99158D01*
G01X5742664Y87699D02*
X5742354Y87908D01*
Y88324D01*
X5742664Y88533D01*
X5742974Y88324D01*
Y87908D01*
X5742664Y87699D01*
G01Y93324D02*
X5742354Y93533D01*
Y93949D01*
X5742664Y94158D01*
X5742974Y93949D01*
Y93533D01*
X5742664Y93324D01*
G01X5767464Y88116D02*
Y100616D01*
X5765604Y98116D01*
G01Y88116D02*
X5769324D01*
G01X5776919Y98533D02*
X5777849Y99782D01*
X5778934Y100408D01*
X5780174Y100616D01*
X5781724Y100199D01*
X5782809Y99158D01*
X5783119Y97908D01*
X5782964Y96657D01*
X5782344Y95616D01*
X5779244Y93533D01*
X5777849Y92074D01*
X5776919Y89991D01*
X5776609Y88116D01*
X5783119D01*
G01X5789629Y89574D02*
X5790714Y88533D01*
X5791954Y88116D01*
X5793194Y88533D01*
X5794279Y89782D01*
X5795054Y91658D01*
X5795364Y93533D01*
Y95824D01*
X5795054Y97699D01*
X5794279Y99366D01*
X5793349Y100199D01*
X5792264Y100616D01*
X5791024Y100199D01*
X5790094Y99366D01*
X5789474Y98116D01*
X5789164Y96449D01*
X5789474Y94991D01*
X5790249Y93533D01*
X5791179Y92699D01*
X5792264Y92491D01*
X5793504Y92907D01*
X5794434Y93949D01*
X5795364Y95824D01*
G01X5801719Y98533D02*
X5802649Y99782D01*
X5803734Y100408D01*
X5804974Y100616D01*
X5806524Y100199D01*
X5807609Y99158D01*
X5807919Y97908D01*
X5807764Y96657D01*
X5807144Y95616D01*
X5804044Y93533D01*
X5802649Y92074D01*
X5801719Y89991D01*
X5801409Y88116D01*
X5807919D01*
G01X5544230Y373435D02*
Y360935D01*
G01X5540665Y373435D02*
X5547795D01*
G01X5556630Y360935D02*
X5555390Y361143D01*
X5554305Y361976D01*
X5553375Y363227D01*
X5552755Y364685D01*
X5552445Y366352D01*
Y368018D01*
X5552755Y369685D01*
X5553375Y371143D01*
X5554305Y372393D01*
X5555390Y373227D01*
X5556630Y373435D01*
X5557870Y373227D01*
X5558955Y372393D01*
X5559885Y371143D01*
X5560505Y369685D01*
X5560815Y368018D01*
Y366352D01*
X5560505Y364685D01*
X5559885Y363227D01*
X5558955Y361976D01*
X5557870Y361143D01*
X5556630Y360935D01*
G01X5569030Y373435D02*
Y360935D01*
G01X5565465Y373435D02*
X5572595D01*
G01X5577555Y360935D02*
X5581430Y373435D01*
X5585305Y360935D01*
G01X5583910Y365310D02*
X5578950D01*
G01X5590730Y373435D02*
Y360935D01*
X5596930D01*
G01X5619870Y367602D02*
X5620490Y368227D01*
X5620955Y369268D01*
X5621265Y370727D01*
X5620955Y371977D01*
X5620335Y372810D01*
X5619250Y373435D01*
X5615065D01*
Y360935D01*
X5620180D01*
X5621265Y361768D01*
X5621885Y363018D01*
X5622195Y364477D01*
X5621885Y365935D01*
X5620955Y367185D01*
X5619870Y367602D01*
X5615065D01*
G01X5627155Y360935D02*
X5631030Y373435D01*
X5634905Y360935D01*
G01X5633510Y365310D02*
X5628550D01*
G01X5646840Y372393D02*
X5645910Y373018D01*
X5644825Y373435D01*
X5643585D01*
X5642190Y372810D01*
X5641105Y371768D01*
X5640330Y370518D01*
X5639710Y368435D01*
X5639555Y366560D01*
X5639865Y364685D01*
X5640330Y363435D01*
X5641260Y362185D01*
X5642345Y361352D01*
X5643430Y360935D01*
X5644515D01*
X5645600Y361352D01*
X5646530Y361976D01*
X5647305Y362810D01*
G01X5652420Y360935D02*
Y373435D01*
G01X5658310D02*
X5652420Y365726D01*
G01X5659240Y360935D02*
X5655055Y369268D01*
G01X5664820Y360935D02*
Y373435D01*
X5667920D01*
X5669160Y372810D01*
X5670090Y371977D01*
X5670865Y370727D01*
X5671485Y369268D01*
X5671640Y367185D01*
X5671485Y365102D01*
X5670865Y363643D01*
X5670090Y362393D01*
X5669160Y361560D01*
X5667920Y360935D01*
X5664820D01*
G01X5677530D02*
Y373435D01*
X5681405D01*
X5682645Y372810D01*
X5683420Y371977D01*
X5683730Y370310D01*
X5683420Y368643D01*
X5682490Y367602D01*
X5681405Y366977D01*
X5677530D01*
G01X5681405D02*
X5683730Y360935D01*
G01X5691170Y373435D02*
X5694890D01*
G01X5693030D02*
Y360935D01*
G01X5691170D02*
X5694890D01*
G01X5702330Y373435D02*
Y360935D01*
X5708530D01*
G01X5714730Y373435D02*
Y360935D01*
X5720930D01*
G01X5726975Y362601D02*
X5728215Y361560D01*
X5729610Y360935D01*
X5730850D01*
X5732090Y361560D01*
X5733020Y362601D01*
X5733485Y364060D01*
X5733175Y365518D01*
X5732400Y366768D01*
X5731005Y367602D01*
X5729145Y368018D01*
X5728060Y368852D01*
X5727595Y370310D01*
X5727905Y371768D01*
X5728680Y372810D01*
X5729765Y373435D01*
X5730850D01*
X5731935Y373018D01*
X5732865Y371977D01*
G01X5742630Y360518D02*
X5742320Y360727D01*
Y361143D01*
X5742630Y361352D01*
X5742940Y361143D01*
Y360727D01*
X5742630Y360518D01*
G01Y366143D02*
X5742320Y366352D01*
Y366768D01*
X5742630Y366977D01*
X5742940Y366768D01*
Y366352D01*
X5742630Y366143D01*
G01X5767430Y360935D02*
Y373435D01*
X5765570Y370935D01*
G01Y360935D02*
X5769290D01*
G01X5779830D02*
X5780915Y361143D01*
X5782155Y361768D01*
X5782930Y362810D01*
X5783240Y364268D01*
X5782930Y365726D01*
X5782000Y366977D01*
X5780605Y367602D01*
X5779055D01*
X5778125Y368018D01*
X5777350Y369060D01*
X5777040Y370518D01*
X5777505Y371977D01*
X5778590Y373018D01*
X5779830Y373435D01*
X5781070Y373018D01*
X5782155Y371977D01*
X5782620Y370518D01*
X5782310Y369060D01*
X5781535Y368018D01*
X5780605Y367602D01*
X5779055D01*
X5777660Y366977D01*
X5776730Y365726D01*
X5776420Y364268D01*
X5776730Y362810D01*
X5777505Y361768D01*
X5778745Y361143D01*
X5779830Y360935D01*
G01X5792230D02*
Y373435D01*
X5790370Y370935D01*
G01Y360935D02*
X5794090D01*
G01X5804630D02*
X5805715Y361143D01*
X5806955Y361768D01*
X5807730Y362810D01*
X5808040Y364268D01*
X5807730Y365726D01*
X5806800Y366977D01*
X5805405Y367602D01*
X5803855D01*
X5802925Y368018D01*
X5802150Y369060D01*
X5801840Y370518D01*
X5802305Y371977D01*
X5803390Y373018D01*
X5804630Y373435D01*
X5805870Y373018D01*
X5806955Y371977D01*
X5807420Y370518D01*
X5807110Y369060D01*
X5806335Y368018D01*
X5805405Y367602D01*
X5803855D01*
X5802460Y366977D01*
X5801530Y365726D01*
X5801220Y364268D01*
X5801530Y362810D01*
X5802305Y361768D01*
X5803545Y361143D01*
X5804630Y360935D01*
G01X5546820Y644606D02*
Y632106D01*
G01X5543255Y644606D02*
X5550385D01*
G01X5559220Y632106D02*
X5557980Y632314D01*
X5556895Y633147D01*
X5555965Y634398D01*
X5555345Y635856D01*
X5555035Y637523D01*
Y639189D01*
X5555345Y640856D01*
X5555965Y642314D01*
X5556895Y643564D01*
X5557980Y644398D01*
X5559220Y644606D01*
X5560460Y644398D01*
X5561545Y643564D01*
X5562475Y642314D01*
X5563095Y640856D01*
X5563405Y639189D01*
Y637523D01*
X5563095Y635856D01*
X5562475Y634398D01*
X5561545Y633147D01*
X5560460Y632314D01*
X5559220Y632106D01*
G01X5571620Y644606D02*
Y632106D01*
G01X5568055Y644606D02*
X5575185D01*
G01X5580145Y632106D02*
X5584020Y644606D01*
X5587895Y632106D01*
G01X5586500Y636481D02*
X5581540D01*
G01X5593320Y644606D02*
Y632106D01*
X5599520D01*
G01X5622460Y638773D02*
X5623080Y639398D01*
X5623545Y640439D01*
X5623855Y641898D01*
X5623545Y643148D01*
X5622925Y643981D01*
X5621840Y644606D01*
X5617655D01*
Y632106D01*
X5622770D01*
X5623855Y632939D01*
X5624475Y634189D01*
X5624785Y635648D01*
X5624475Y637106D01*
X5623545Y638356D01*
X5622460Y638773D01*
X5617655D01*
G01X5629745Y632106D02*
X5633620Y644606D01*
X5637495Y632106D01*
G01X5636100Y636481D02*
X5631140D01*
G01X5649430Y643564D02*
X5648500Y644189D01*
X5647415Y644606D01*
X5646175D01*
X5644780Y643981D01*
X5643695Y642939D01*
X5642920Y641689D01*
X5642300Y639606D01*
X5642145Y637731D01*
X5642455Y635856D01*
X5642920Y634606D01*
X5643850Y633356D01*
X5644935Y632523D01*
X5646020Y632106D01*
X5647105D01*
X5648190Y632523D01*
X5649120Y633147D01*
X5649895Y633981D01*
G01X5655010Y632106D02*
Y644606D01*
G01X5660900D02*
X5655010Y636897D01*
G01X5661830Y632106D02*
X5657645Y640439D01*
G01X5667410Y632106D02*
Y644606D01*
X5670510D01*
X5671750Y643981D01*
X5672680Y643148D01*
X5673455Y641898D01*
X5674075Y640439D01*
X5674230Y638356D01*
X5674075Y636273D01*
X5673455Y634814D01*
X5672680Y633564D01*
X5671750Y632731D01*
X5670510Y632106D01*
X5667410D01*
G01X5680120D02*
Y644606D01*
X5683995D01*
X5685235Y643981D01*
X5686010Y643148D01*
X5686320Y641481D01*
X5686010Y639814D01*
X5685080Y638773D01*
X5683995Y638148D01*
X5680120D01*
G01X5683995D02*
X5686320Y632106D01*
G01X5693760Y644606D02*
X5697480D01*
G01X5695620D02*
Y632106D01*
G01X5693760D02*
X5697480D01*
G01X5704920Y644606D02*
Y632106D01*
X5711120D01*
G01X5717320Y644606D02*
Y632106D01*
X5723520D01*
G01X5729565Y633772D02*
X5730805Y632731D01*
X5732200Y632106D01*
X5733440D01*
X5734680Y632731D01*
X5735610Y633772D01*
X5736075Y635231D01*
X5735765Y636689D01*
X5734990Y637939D01*
X5733595Y638773D01*
X5731735Y639189D01*
X5730650Y640023D01*
X5730185Y641481D01*
X5730495Y642939D01*
X5731270Y643981D01*
X5732355Y644606D01*
X5733440D01*
X5734525Y644189D01*
X5735455Y643148D01*
G01X5745220Y631689D02*
X5744910Y631898D01*
Y632314D01*
X5745220Y632523D01*
X5745530Y632314D01*
Y631898D01*
X5745220Y631689D01*
G01Y637314D02*
X5744910Y637523D01*
Y637939D01*
X5745220Y638148D01*
X5745530Y637939D01*
Y637523D01*
X5745220Y637314D01*
G01X5770020Y632106D02*
Y644606D01*
X5768160Y642106D01*
G01Y632106D02*
X5771880D01*
G01X5779475Y637314D02*
X5780560Y638773D01*
X5781490Y639606D01*
X5782730Y640023D01*
X5783815Y639606D01*
X5784590Y638773D01*
X5785210Y637523D01*
X5785365Y636064D01*
X5785210Y634814D01*
X5784590Y633564D01*
X5783660Y632523D01*
X5782575Y632106D01*
X5781335Y632523D01*
X5780250Y633772D01*
X5779630Y635648D01*
X5779475Y637731D01*
X5779785Y640439D01*
X5780250Y641898D01*
X5781025Y643356D01*
X5782110Y644398D01*
X5783195Y644606D01*
X5784280Y644189D01*
X5785055Y643148D01*
G01X5794820Y632106D02*
X5795905Y632314D01*
X5797145Y632939D01*
X5797920Y633981D01*
X5798230Y635439D01*
X5797920Y636897D01*
X5796990Y638148D01*
X5795595Y638773D01*
X5794045D01*
X5793115Y639189D01*
X5792340Y640231D01*
X5792030Y641689D01*
X5792495Y643148D01*
X5793580Y644189D01*
X5794820Y644606D01*
X5796060Y644189D01*
X5797145Y643148D01*
X5797610Y641689D01*
X5797300Y640231D01*
X5796525Y639189D01*
X5795595Y638773D01*
X5794045D01*
X5792650Y638148D01*
X5791720Y636897D01*
X5791410Y635439D01*
X5791720Y633981D01*
X5792495Y632939D01*
X5793735Y632314D01*
X5794820Y632106D01*
G01X5809080D02*
Y644606D01*
X5803345Y635648D01*
X5811095D01*
G01X5548820Y902106D02*
Y889606D01*
G01X5545255Y902106D02*
X5552385D01*
G01X5561220Y889606D02*
X5559980Y889814D01*
X5558895Y890647D01*
X5557965Y891898D01*
X5557345Y893356D01*
X5557035Y895023D01*
Y896689D01*
X5557345Y898356D01*
X5557965Y899814D01*
X5558895Y901064D01*
X5559980Y901898D01*
X5561220Y902106D01*
X5562460Y901898D01*
X5563545Y901064D01*
X5564475Y899814D01*
X5565095Y898356D01*
X5565405Y896689D01*
Y895023D01*
X5565095Y893356D01*
X5564475Y891898D01*
X5563545Y890647D01*
X5562460Y889814D01*
X5561220Y889606D01*
G01X5573620Y902106D02*
Y889606D01*
G01X5570055Y902106D02*
X5577185D01*
G01X5582145Y889606D02*
X5586020Y902106D01*
X5589895Y889606D01*
G01X5588500Y893981D02*
X5583540D01*
G01X5595320Y902106D02*
Y889606D01*
X5601520D01*
G01X5624460Y896273D02*
X5625080Y896898D01*
X5625545Y897939D01*
X5625855Y899398D01*
X5625545Y900648D01*
X5624925Y901481D01*
X5623840Y902106D01*
X5619655D01*
Y889606D01*
X5624770D01*
X5625855Y890439D01*
X5626475Y891689D01*
X5626785Y893148D01*
X5626475Y894606D01*
X5625545Y895856D01*
X5624460Y896273D01*
X5619655D01*
G01X5631745Y889606D02*
X5635620Y902106D01*
X5639495Y889606D01*
G01X5638100Y893981D02*
X5633140D01*
G01X5651430Y901064D02*
X5650500Y901689D01*
X5649415Y902106D01*
X5648175D01*
X5646780Y901481D01*
X5645695Y900439D01*
X5644920Y899189D01*
X5644300Y897106D01*
X5644145Y895231D01*
X5644455Y893356D01*
X5644920Y892106D01*
X5645850Y890856D01*
X5646935Y890023D01*
X5648020Y889606D01*
X5649105D01*
X5650190Y890023D01*
X5651120Y890647D01*
X5651895Y891481D01*
G01X5657010Y889606D02*
Y902106D01*
G01X5662900D02*
X5657010Y894397D01*
G01X5663830Y889606D02*
X5659645Y897939D01*
G01X5669410Y889606D02*
Y902106D01*
X5672510D01*
X5673750Y901481D01*
X5674680Y900648D01*
X5675455Y899398D01*
X5676075Y897939D01*
X5676230Y895856D01*
X5676075Y893773D01*
X5675455Y892314D01*
X5674680Y891064D01*
X5673750Y890231D01*
X5672510Y889606D01*
X5669410D01*
G01X5682120D02*
Y902106D01*
X5685995D01*
X5687235Y901481D01*
X5688010Y900648D01*
X5688320Y898981D01*
X5688010Y897314D01*
X5687080Y896273D01*
X5685995Y895648D01*
X5682120D01*
G01X5685995D02*
X5688320Y889606D01*
G01X5695760Y902106D02*
X5699480D01*
G01X5697620D02*
Y889606D01*
G01X5695760D02*
X5699480D01*
G01X5706920Y902106D02*
Y889606D01*
X5713120D01*
G01X5719320Y902106D02*
Y889606D01*
X5725520D01*
G01X5731565Y891272D02*
X5732805Y890231D01*
X5734200Y889606D01*
X5735440D01*
X5736680Y890231D01*
X5737610Y891272D01*
X5738075Y892731D01*
X5737765Y894189D01*
X5736990Y895439D01*
X5735595Y896273D01*
X5733735Y896689D01*
X5732650Y897523D01*
X5732185Y898981D01*
X5732495Y900439D01*
X5733270Y901481D01*
X5734355Y902106D01*
X5735440D01*
X5736525Y901689D01*
X5737455Y900648D01*
G01X5747220Y889189D02*
X5746910Y889398D01*
Y889814D01*
X5747220Y890023D01*
X5747530Y889814D01*
Y889398D01*
X5747220Y889189D01*
G01Y894814D02*
X5746910Y895023D01*
Y895439D01*
X5747220Y895648D01*
X5747530Y895439D01*
Y895023D01*
X5747220Y894814D01*
G01X5772020Y889606D02*
Y902106D01*
X5770160Y899606D01*
G01Y889606D02*
X5773880D01*
G01X5781785Y891064D02*
X5782870Y890023D01*
X5784110Y889606D01*
X5785350Y890023D01*
X5786435Y891272D01*
X5787210Y893148D01*
X5787520Y895023D01*
Y897314D01*
X5787210Y899189D01*
X5786435Y900856D01*
X5785505Y901689D01*
X5784420Y902106D01*
X5783180Y901689D01*
X5782250Y900856D01*
X5781630Y899606D01*
X5781320Y897939D01*
X5781630Y896481D01*
X5782405Y895023D01*
X5783335Y894189D01*
X5784420Y893981D01*
X5785660Y894397D01*
X5786590Y895439D01*
X5787520Y897314D01*
G01X5796820Y889606D02*
Y902106D01*
X5794960Y899606D01*
G01Y889606D02*
X5798680D01*
G01X5806275Y900023D02*
X5807205Y901272D01*
X5808290Y901898D01*
X5809530Y902106D01*
X5811080Y901689D01*
X5812165Y900648D01*
X5812475Y899398D01*
X5812320Y898147D01*
X5811700Y897106D01*
X5808600Y895023D01*
X5807205Y893564D01*
X5806275Y891481D01*
X5805965Y889606D01*
X5812475D01*
G01X5547820Y1216106D02*
Y1203606D01*
G01X5544255Y1216106D02*
X5551385D01*
G01X5560220Y1203606D02*
X5558980Y1203814D01*
X5557895Y1204647D01*
X5556965Y1205898D01*
X5556345Y1207356D01*
X5556035Y1209023D01*
Y1210689D01*
X5556345Y1212356D01*
X5556965Y1213814D01*
X5557895Y1215064D01*
X5558980Y1215898D01*
X5560220Y1216106D01*
X5561460Y1215898D01*
X5562545Y1215064D01*
X5563475Y1213814D01*
X5564095Y1212356D01*
X5564405Y1210689D01*
Y1209023D01*
X5564095Y1207356D01*
X5563475Y1205898D01*
X5562545Y1204647D01*
X5561460Y1203814D01*
X5560220Y1203606D01*
G01X5572620Y1216106D02*
Y1203606D01*
G01X5569055Y1216106D02*
X5576185D01*
G01X5581145Y1203606D02*
X5585020Y1216106D01*
X5588895Y1203606D01*
G01X5587500Y1207981D02*
X5582540D01*
G01X5594320Y1216106D02*
Y1203606D01*
X5600520D01*
G01X5623460Y1210273D02*
X5624080Y1210898D01*
X5624545Y1211939D01*
X5624855Y1213398D01*
X5624545Y1214648D01*
X5623925Y1215481D01*
X5622840Y1216106D01*
X5618655D01*
Y1203606D01*
X5623770D01*
X5624855Y1204439D01*
X5625475Y1205689D01*
X5625785Y1207148D01*
X5625475Y1208606D01*
X5624545Y1209856D01*
X5623460Y1210273D01*
X5618655D01*
G01X5630745Y1203606D02*
X5634620Y1216106D01*
X5638495Y1203606D01*
G01X5637100Y1207981D02*
X5632140D01*
G01X5650430Y1215064D02*
X5649500Y1215689D01*
X5648415Y1216106D01*
X5647175D01*
X5645780Y1215481D01*
X5644695Y1214439D01*
X5643920Y1213189D01*
X5643300Y1211106D01*
X5643145Y1209231D01*
X5643455Y1207356D01*
X5643920Y1206106D01*
X5644850Y1204856D01*
X5645935Y1204023D01*
X5647020Y1203606D01*
X5648105D01*
X5649190Y1204023D01*
X5650120Y1204647D01*
X5650895Y1205481D01*
G01X5656010Y1203606D02*
Y1216106D01*
G01X5661900D02*
X5656010Y1208397D01*
G01X5662830Y1203606D02*
X5658645Y1211939D01*
G01X5668410Y1203606D02*
Y1216106D01*
X5671510D01*
X5672750Y1215481D01*
X5673680Y1214648D01*
X5674455Y1213398D01*
X5675075Y1211939D01*
X5675230Y1209856D01*
X5675075Y1207773D01*
X5674455Y1206314D01*
X5673680Y1205064D01*
X5672750Y1204231D01*
X5671510Y1203606D01*
X5668410D01*
G01X5681120D02*
Y1216106D01*
X5684995D01*
X5686235Y1215481D01*
X5687010Y1214648D01*
X5687320Y1212981D01*
X5687010Y1211314D01*
X5686080Y1210273D01*
X5684995Y1209648D01*
X5681120D01*
G01X5684995D02*
X5687320Y1203606D01*
G01X5694760Y1216106D02*
X5698480D01*
G01X5696620D02*
Y1203606D01*
G01X5694760D02*
X5698480D01*
G01X5705920Y1216106D02*
Y1203606D01*
X5712120D01*
G01X5718320Y1216106D02*
Y1203606D01*
X5724520D01*
G01X5730565Y1205272D02*
X5731805Y1204231D01*
X5733200Y1203606D01*
X5734440D01*
X5735680Y1204231D01*
X5736610Y1205272D01*
X5737075Y1206731D01*
X5736765Y1208189D01*
X5735990Y1209439D01*
X5734595Y1210273D01*
X5732735Y1210689D01*
X5731650Y1211523D01*
X5731185Y1212981D01*
X5731495Y1214439D01*
X5732270Y1215481D01*
X5733355Y1216106D01*
X5734440D01*
X5735525Y1215689D01*
X5736455Y1214648D01*
G01X5746220Y1203189D02*
X5745910Y1203398D01*
Y1203814D01*
X5746220Y1204023D01*
X5746530Y1203814D01*
Y1203398D01*
X5746220Y1203189D01*
G01Y1208814D02*
X5745910Y1209023D01*
Y1209439D01*
X5746220Y1209648D01*
X5746530Y1209439D01*
Y1209023D01*
X5746220Y1208814D01*
G01X5771020Y1203606D02*
Y1216106D01*
X5769160Y1213606D01*
G01Y1203606D02*
X5772880D01*
G01X5780475Y1208814D02*
X5781560Y1210273D01*
X5782490Y1211106D01*
X5783730Y1211523D01*
X5784815Y1211106D01*
X5785590Y1210273D01*
X5786210Y1209023D01*
X5786365Y1207564D01*
X5786210Y1206314D01*
X5785590Y1205064D01*
X5784660Y1204023D01*
X5783575Y1203606D01*
X5782335Y1204023D01*
X5781250Y1205272D01*
X5780630Y1207148D01*
X5780475Y1209231D01*
X5780785Y1211939D01*
X5781250Y1213398D01*
X5782025Y1214856D01*
X5783110Y1215898D01*
X5784195Y1216106D01*
X5785280Y1215689D01*
X5786055Y1214648D01*
G01X5795510Y1203606D02*
X5795820Y1206314D01*
X5796285Y1208606D01*
X5796905Y1210689D01*
X5797680Y1212981D01*
X5798920Y1216106D01*
X5792720D01*
G01X5805275Y1208814D02*
X5806360Y1210273D01*
X5807290Y1211106D01*
X5808530Y1211523D01*
X5809615Y1211106D01*
X5810390Y1210273D01*
X5811010Y1209023D01*
X5811165Y1207564D01*
X5811010Y1206314D01*
X5810390Y1205064D01*
X5809460Y1204023D01*
X5808375Y1203606D01*
X5807135Y1204023D01*
X5806050Y1205272D01*
X5805430Y1207148D01*
X5805275Y1209231D01*
X5805585Y1211939D01*
X5806050Y1213398D01*
X5806825Y1214856D01*
X5807910Y1215898D01*
X5808995Y1216106D01*
X5810080Y1215689D01*
X5810855Y1214648D01*
G01X5544820Y1544106D02*
X5545905Y1544314D01*
X5547145Y1544939D01*
X5547920Y1545981D01*
X5548230Y1547439D01*
X5547920Y1548897D01*
X5546990Y1550148D01*
X5545595Y1550773D01*
X5544045D01*
X5543115Y1551189D01*
X5542340Y1552231D01*
X5542030Y1553689D01*
X5542495Y1555148D01*
X5543580Y1556189D01*
X5544820Y1556606D01*
X5546060Y1556189D01*
X5547145Y1555148D01*
X5547610Y1553689D01*
X5547300Y1552231D01*
X5546525Y1551189D01*
X5545595Y1550773D01*
X5544045D01*
X5542650Y1550148D01*
X5541720Y1548897D01*
X5541410Y1547439D01*
X5541720Y1545981D01*
X5542495Y1544939D01*
X5543735Y1544314D01*
X5544820Y1544106D01*
G01X5557220Y1543689D02*
X5556910Y1543898D01*
Y1544314D01*
X5557220Y1544523D01*
X5557530Y1544314D01*
Y1543898D01*
X5557220Y1543689D01*
G01X5566985Y1545564D02*
X5568070Y1544523D01*
X5569310Y1544106D01*
X5570550Y1544523D01*
X5571635Y1545772D01*
X5572410Y1547648D01*
X5572720Y1549523D01*
Y1551814D01*
X5572410Y1553689D01*
X5571635Y1555356D01*
X5570705Y1556189D01*
X5569620Y1556606D01*
X5568380Y1556189D01*
X5567450Y1555356D01*
X5566830Y1554106D01*
X5566520Y1552439D01*
X5566830Y1550981D01*
X5567605Y1549523D01*
X5568535Y1548689D01*
X5569620Y1548481D01*
X5570860Y1548897D01*
X5571790Y1549939D01*
X5572720Y1551814D01*
G01X5544820Y1569106D02*
X5545905Y1569314D01*
X5547145Y1569939D01*
X5547920Y1570981D01*
X5548230Y1572439D01*
X5547920Y1573897D01*
X5546990Y1575148D01*
X5545595Y1575773D01*
X5544045D01*
X5543115Y1576189D01*
X5542340Y1577231D01*
X5542030Y1578689D01*
X5542495Y1580148D01*
X5543580Y1581189D01*
X5544820Y1581606D01*
X5546060Y1581189D01*
X5547145Y1580148D01*
X5547610Y1578689D01*
X5547300Y1577231D01*
X5546525Y1576189D01*
X5545595Y1575773D01*
X5544045D01*
X5542650Y1575148D01*
X5541720Y1573897D01*
X5541410Y1572439D01*
X5541720Y1570981D01*
X5542495Y1569939D01*
X5543735Y1569314D01*
X5544820Y1569106D01*
G01X5557220Y1568689D02*
X5556910Y1568898D01*
Y1569314D01*
X5557220Y1569523D01*
X5557530Y1569314D01*
Y1568898D01*
X5557220Y1568689D01*
G01X5566985Y1570564D02*
X5568070Y1569523D01*
X5569310Y1569106D01*
X5570550Y1569523D01*
X5571635Y1570772D01*
X5572410Y1572648D01*
X5572720Y1574523D01*
Y1576814D01*
X5572410Y1578689D01*
X5571635Y1580356D01*
X5570705Y1581189D01*
X5569620Y1581606D01*
X5568380Y1581189D01*
X5567450Y1580356D01*
X5566830Y1579106D01*
X5566520Y1577439D01*
X5566830Y1575981D01*
X5567605Y1574523D01*
X5568535Y1573689D01*
X5569620Y1573481D01*
X5570860Y1573897D01*
X5571790Y1574939D01*
X5572720Y1576814D01*
G01X5544820Y1594106D02*
X5545905Y1594314D01*
X5547145Y1594939D01*
X5547920Y1595981D01*
X5548230Y1597439D01*
X5547920Y1598897D01*
X5546990Y1600148D01*
X5545595Y1600773D01*
X5544045D01*
X5543115Y1601189D01*
X5542340Y1602231D01*
X5542030Y1603689D01*
X5542495Y1605148D01*
X5543580Y1606189D01*
X5544820Y1606606D01*
X5546060Y1606189D01*
X5547145Y1605148D01*
X5547610Y1603689D01*
X5547300Y1602231D01*
X5546525Y1601189D01*
X5545595Y1600773D01*
X5544045D01*
X5542650Y1600148D01*
X5541720Y1598897D01*
X5541410Y1597439D01*
X5541720Y1595981D01*
X5542495Y1594939D01*
X5543735Y1594314D01*
X5544820Y1594106D01*
G01X5557220Y1593689D02*
X5556910Y1593898D01*
Y1594314D01*
X5557220Y1594523D01*
X5557530Y1594314D01*
Y1593898D01*
X5557220Y1593689D01*
G01X5566985Y1595564D02*
X5568070Y1594523D01*
X5569310Y1594106D01*
X5570550Y1594523D01*
X5571635Y1595772D01*
X5572410Y1597648D01*
X5572720Y1599523D01*
Y1601814D01*
X5572410Y1603689D01*
X5571635Y1605356D01*
X5570705Y1606189D01*
X5569620Y1606606D01*
X5568380Y1606189D01*
X5567450Y1605356D01*
X5566830Y1604106D01*
X5566520Y1602439D01*
X5566830Y1600981D01*
X5567605Y1599523D01*
X5568535Y1598689D01*
X5569620Y1598481D01*
X5570860Y1598897D01*
X5571790Y1599939D01*
X5572720Y1601814D01*
G01X5544820Y1619106D02*
X5545905Y1619314D01*
X5547145Y1619939D01*
X5547920Y1620981D01*
X5548230Y1622439D01*
X5547920Y1623897D01*
X5546990Y1625148D01*
X5545595Y1625773D01*
X5544045D01*
X5543115Y1626189D01*
X5542340Y1627231D01*
X5542030Y1628689D01*
X5542495Y1630148D01*
X5543580Y1631189D01*
X5544820Y1631606D01*
X5546060Y1631189D01*
X5547145Y1630148D01*
X5547610Y1628689D01*
X5547300Y1627231D01*
X5546525Y1626189D01*
X5545595Y1625773D01*
X5544045D01*
X5542650Y1625148D01*
X5541720Y1623897D01*
X5541410Y1622439D01*
X5541720Y1620981D01*
X5542495Y1619939D01*
X5543735Y1619314D01*
X5544820Y1619106D01*
G01X5557220Y1618689D02*
X5556910Y1618898D01*
Y1619314D01*
X5557220Y1619523D01*
X5557530Y1619314D01*
Y1618898D01*
X5557220Y1618689D01*
G01X5566985Y1620564D02*
X5568070Y1619523D01*
X5569310Y1619106D01*
X5570550Y1619523D01*
X5571635Y1620772D01*
X5572410Y1622648D01*
X5572720Y1624523D01*
Y1626814D01*
X5572410Y1628689D01*
X5571635Y1630356D01*
X5570705Y1631189D01*
X5569620Y1631606D01*
X5568380Y1631189D01*
X5567450Y1630356D01*
X5566830Y1629106D01*
X5566520Y1627439D01*
X5566830Y1625981D01*
X5567605Y1624523D01*
X5568535Y1623689D01*
X5569620Y1623481D01*
X5570860Y1623897D01*
X5571790Y1624939D01*
X5572720Y1626814D01*
G01X5560220Y1531606D02*
Y1519106D01*
G01X5556655Y1531606D02*
X5563785D01*
G01X5572620Y1519106D02*
X5571380Y1519314D01*
X5570295Y1520147D01*
X5569365Y1521398D01*
X5568745Y1522856D01*
X5568435Y1524523D01*
Y1526189D01*
X5568745Y1527856D01*
X5569365Y1529314D01*
X5570295Y1530564D01*
X5571380Y1531398D01*
X5572620Y1531606D01*
X5573860Y1531398D01*
X5574945Y1530564D01*
X5575875Y1529314D01*
X5576495Y1527856D01*
X5576805Y1526189D01*
Y1524523D01*
X5576495Y1522856D01*
X5575875Y1521398D01*
X5574945Y1520147D01*
X5573860Y1519314D01*
X5572620Y1519106D01*
G01X5585020Y1531606D02*
Y1519106D01*
G01X5581455Y1531606D02*
X5588585D01*
G01X5593545Y1519106D02*
X5597420Y1531606D01*
X5601295Y1519106D01*
G01X5599900Y1523481D02*
X5594940D01*
G01X5606720Y1531606D02*
Y1519106D01*
X5612920D01*
G01X5635860Y1525773D02*
X5636480Y1526398D01*
X5636945Y1527439D01*
X5637255Y1528898D01*
X5636945Y1530148D01*
X5636325Y1530981D01*
X5635240Y1531606D01*
X5631055D01*
Y1519106D01*
X5636170D01*
X5637255Y1519939D01*
X5637875Y1521189D01*
X5638185Y1522648D01*
X5637875Y1524106D01*
X5636945Y1525356D01*
X5635860Y1525773D01*
X5631055D01*
G01X5643145Y1519106D02*
X5647020Y1531606D01*
X5650895Y1519106D01*
G01X5649500Y1523481D02*
X5644540D01*
G01X5662830Y1530564D02*
X5661900Y1531189D01*
X5660815Y1531606D01*
X5659575D01*
X5658180Y1530981D01*
X5657095Y1529939D01*
X5656320Y1528689D01*
X5655700Y1526606D01*
X5655545Y1524731D01*
X5655855Y1522856D01*
X5656320Y1521606D01*
X5657250Y1520356D01*
X5658335Y1519523D01*
X5659420Y1519106D01*
X5660505D01*
X5661590Y1519523D01*
X5662520Y1520147D01*
X5663295Y1520981D01*
G01X5668410Y1519106D02*
Y1531606D01*
G01X5674300D02*
X5668410Y1523897D01*
G01X5675230Y1519106D02*
X5671045Y1527439D01*
G01X5680810Y1519106D02*
Y1531606D01*
X5683910D01*
X5685150Y1530981D01*
X5686080Y1530148D01*
X5686855Y1528898D01*
X5687475Y1527439D01*
X5687630Y1525356D01*
X5687475Y1523273D01*
X5686855Y1521814D01*
X5686080Y1520564D01*
X5685150Y1519731D01*
X5683910Y1519106D01*
X5680810D01*
G01X5693520D02*
Y1531606D01*
X5697395D01*
X5698635Y1530981D01*
X5699410Y1530148D01*
X5699720Y1528481D01*
X5699410Y1526814D01*
X5698480Y1525773D01*
X5697395Y1525148D01*
X5693520D01*
G01X5697395D02*
X5699720Y1519106D01*
G01X5707160Y1531606D02*
X5710880D01*
G01X5709020D02*
Y1519106D01*
G01X5707160D02*
X5710880D01*
G01X5718320Y1531606D02*
Y1519106D01*
X5724520D01*
G01X5730720Y1531606D02*
Y1519106D01*
X5736920D01*
G01X5742965Y1520772D02*
X5744205Y1519731D01*
X5745600Y1519106D01*
X5746840D01*
X5748080Y1519731D01*
X5749010Y1520772D01*
X5749475Y1522231D01*
X5749165Y1523689D01*
X5748390Y1524939D01*
X5746995Y1525773D01*
X5745135Y1526189D01*
X5744050Y1527023D01*
X5743585Y1528481D01*
X5743895Y1529939D01*
X5744670Y1530981D01*
X5745755Y1531606D01*
X5746840D01*
X5747925Y1531189D01*
X5748855Y1530148D01*
G01X5758620Y1518689D02*
X5758310Y1518898D01*
Y1519314D01*
X5758620Y1519523D01*
X5758930Y1519314D01*
Y1518898D01*
X5758620Y1518689D01*
G01Y1524314D02*
X5758310Y1524523D01*
Y1524939D01*
X5758620Y1525148D01*
X5758930Y1524939D01*
Y1524523D01*
X5758620Y1524314D01*
G01X5785280Y1519106D02*
Y1531606D01*
X5779545Y1522648D01*
X5787295D01*
G01X5792410Y1520981D02*
X5793340Y1519939D01*
X5794425Y1519314D01*
X5795820Y1519106D01*
X5797215Y1519523D01*
X5798300Y1520356D01*
X5799075Y1521814D01*
X5799230Y1523481D01*
X5798920Y1525148D01*
X5798145Y1526189D01*
X5797060Y1527023D01*
X5795975Y1527231D01*
X5794890Y1527023D01*
X5793495Y1526189D01*
X5793960Y1531606D01*
X5798145D01*
G01X5805275Y1529523D02*
X5806205Y1530772D01*
X5807290Y1531398D01*
X5808530Y1531606D01*
X5810080Y1531189D01*
X5811165Y1530148D01*
X5811475Y1528898D01*
X5811320Y1527647D01*
X5810700Y1526606D01*
X5807600Y1524523D01*
X5806205Y1523064D01*
X5805275Y1520981D01*
X5804965Y1519106D01*
X5811475D01*
G01X5633334Y163116D02*
Y175616D01*
X5637364Y165199D01*
X5641394Y175616D01*
Y163116D01*
G01X5646819D02*
Y175616D01*
X5652709D01*
G01X5650539Y169574D02*
X5646819D01*
G01X5663094Y169366D02*
X5666194D01*
Y165616D01*
X5665264Y164366D01*
X5664179Y163533D01*
X5662629Y163116D01*
X5661079Y163533D01*
X5659994Y164366D01*
X5659064Y165616D01*
X5658444Y167074D01*
X5658134Y168741D01*
Y170199D01*
X5658444Y171449D01*
X5659064Y172908D01*
X5659994Y174158D01*
X5660924Y174991D01*
X5662164Y175616D01*
X5663249D01*
X5664489Y175199D01*
X5665419Y174366D01*
G01X5669914Y158949D02*
X5679214D01*
G01X5683709Y164782D02*
X5684949Y163741D01*
X5686344Y163116D01*
X5687584D01*
X5688824Y163741D01*
X5689754Y164782D01*
X5690219Y166241D01*
X5689909Y167699D01*
X5689134Y168949D01*
X5687739Y169783D01*
X5685879Y170199D01*
X5684794Y171033D01*
X5684329Y172491D01*
X5684639Y173949D01*
X5685414Y174991D01*
X5686499Y175616D01*
X5687584D01*
X5688669Y175199D01*
X5689599Y174158D01*
G01X5699364Y175616D02*
Y163116D01*
G01X5695799Y175616D02*
X5702929D01*
G01X5708354D02*
Y166658D01*
X5708974Y164782D01*
X5710214Y163533D01*
X5711764Y163116D01*
X5713314Y163533D01*
X5714554Y164782D01*
X5715174Y166658D01*
Y175616D01*
G01X5725404Y169783D02*
X5726024Y170408D01*
X5726489Y171449D01*
X5726799Y172908D01*
X5726489Y174158D01*
X5725869Y174991D01*
X5724784Y175616D01*
X5720599D01*
Y163116D01*
X5725714D01*
X5726799Y163949D01*
X5727419Y165199D01*
X5727729Y166658D01*
X5727419Y168116D01*
X5726489Y169366D01*
X5725404Y169783D01*
X5720599D01*
G01X5633300Y435935D02*
Y448435D01*
X5637330Y438018D01*
X5641360Y448435D01*
Y435935D01*
G01X5646785D02*
Y448435D01*
X5652675D01*
G01X5650505Y442393D02*
X5646785D01*
G01X5663060Y442185D02*
X5666160D01*
Y438435D01*
X5665230Y437185D01*
X5664145Y436352D01*
X5662595Y435935D01*
X5661045Y436352D01*
X5659960Y437185D01*
X5659030Y438435D01*
X5658410Y439893D01*
X5658100Y441560D01*
Y443018D01*
X5658410Y444268D01*
X5659030Y445727D01*
X5659960Y446977D01*
X5660890Y447810D01*
X5662130Y448435D01*
X5663215D01*
X5664455Y448018D01*
X5665385Y447185D01*
G01X5669880Y431768D02*
X5679180D01*
G01X5683675Y437601D02*
X5684915Y436560D01*
X5686310Y435935D01*
X5687550D01*
X5688790Y436560D01*
X5689720Y437601D01*
X5690185Y439060D01*
X5689875Y440518D01*
X5689100Y441768D01*
X5687705Y442602D01*
X5685845Y443018D01*
X5684760Y443852D01*
X5684295Y445310D01*
X5684605Y446768D01*
X5685380Y447810D01*
X5686465Y448435D01*
X5687550D01*
X5688635Y448018D01*
X5689565Y446977D01*
G01X5699330Y448435D02*
Y435935D01*
G01X5695765Y448435D02*
X5702895D01*
G01X5708320D02*
Y439477D01*
X5708940Y437601D01*
X5710180Y436352D01*
X5711730Y435935D01*
X5713280Y436352D01*
X5714520Y437601D01*
X5715140Y439477D01*
Y448435D01*
G01X5725370Y442602D02*
X5725990Y443227D01*
X5726455Y444268D01*
X5726765Y445727D01*
X5726455Y446977D01*
X5725835Y447810D01*
X5724750Y448435D01*
X5720565D01*
Y435935D01*
X5725680D01*
X5726765Y436768D01*
X5727385Y438018D01*
X5727695Y439477D01*
X5727385Y440935D01*
X5726455Y442185D01*
X5725370Y442602D01*
X5720565D01*
G01X5635890Y707106D02*
Y719606D01*
X5639920Y709189D01*
X5643950Y719606D01*
Y707106D01*
G01X5649375D02*
Y719606D01*
X5655265D01*
G01X5653095Y713564D02*
X5649375D01*
G01X5665650Y713356D02*
X5668750D01*
Y709606D01*
X5667820Y708356D01*
X5666735Y707523D01*
X5665185Y707106D01*
X5663635Y707523D01*
X5662550Y708356D01*
X5661620Y709606D01*
X5661000Y711064D01*
X5660690Y712731D01*
Y714189D01*
X5661000Y715439D01*
X5661620Y716898D01*
X5662550Y718148D01*
X5663480Y718981D01*
X5664720Y719606D01*
X5665805D01*
X5667045Y719189D01*
X5667975Y718356D01*
G01X5672470Y702939D02*
X5681770D01*
G01X5686265Y708772D02*
X5687505Y707731D01*
X5688900Y707106D01*
X5690140D01*
X5691380Y707731D01*
X5692310Y708772D01*
X5692775Y710231D01*
X5692465Y711689D01*
X5691690Y712939D01*
X5690295Y713773D01*
X5688435Y714189D01*
X5687350Y715023D01*
X5686885Y716481D01*
X5687195Y717939D01*
X5687970Y718981D01*
X5689055Y719606D01*
X5690140D01*
X5691225Y719189D01*
X5692155Y718148D01*
G01X5701920Y719606D02*
Y707106D01*
G01X5698355Y719606D02*
X5705485D01*
G01X5710910D02*
Y710648D01*
X5711530Y708772D01*
X5712770Y707523D01*
X5714320Y707106D01*
X5715870Y707523D01*
X5717110Y708772D01*
X5717730Y710648D01*
Y719606D01*
G01X5727960Y713773D02*
X5728580Y714398D01*
X5729045Y715439D01*
X5729355Y716898D01*
X5729045Y718148D01*
X5728425Y718981D01*
X5727340Y719606D01*
X5723155D01*
Y707106D01*
X5728270D01*
X5729355Y707939D01*
X5729975Y709189D01*
X5730285Y710648D01*
X5729975Y712106D01*
X5729045Y713356D01*
X5727960Y713773D01*
X5723155D01*
G01X5637890Y1014606D02*
Y1027106D01*
X5641920Y1016689D01*
X5645950Y1027106D01*
Y1014606D01*
G01X5651375D02*
Y1027106D01*
X5657265D01*
G01X5655095Y1021064D02*
X5651375D01*
G01X5667650Y1020856D02*
X5670750D01*
Y1017106D01*
X5669820Y1015856D01*
X5668735Y1015023D01*
X5667185Y1014606D01*
X5665635Y1015023D01*
X5664550Y1015856D01*
X5663620Y1017106D01*
X5663000Y1018564D01*
X5662690Y1020231D01*
Y1021689D01*
X5663000Y1022939D01*
X5663620Y1024398D01*
X5664550Y1025648D01*
X5665480Y1026481D01*
X5666720Y1027106D01*
X5667805D01*
X5669045Y1026689D01*
X5669975Y1025856D01*
G01X5674470Y1010439D02*
X5683770D01*
G01X5688265Y1016272D02*
X5689505Y1015231D01*
X5690900Y1014606D01*
X5692140D01*
X5693380Y1015231D01*
X5694310Y1016272D01*
X5694775Y1017731D01*
X5694465Y1019189D01*
X5693690Y1020439D01*
X5692295Y1021273D01*
X5690435Y1021689D01*
X5689350Y1022523D01*
X5688885Y1023981D01*
X5689195Y1025439D01*
X5689970Y1026481D01*
X5691055Y1027106D01*
X5692140D01*
X5693225Y1026689D01*
X5694155Y1025648D01*
G01X5703920Y1027106D02*
Y1014606D01*
G01X5700355Y1027106D02*
X5707485D01*
G01X5712910D02*
Y1018148D01*
X5713530Y1016272D01*
X5714770Y1015023D01*
X5716320Y1014606D01*
X5717870Y1015023D01*
X5719110Y1016272D01*
X5719730Y1018148D01*
Y1027106D01*
G01X5729960Y1021273D02*
X5730580Y1021898D01*
X5731045Y1022939D01*
X5731355Y1024398D01*
X5731045Y1025648D01*
X5730425Y1026481D01*
X5729340Y1027106D01*
X5725155D01*
Y1014606D01*
X5730270D01*
X5731355Y1015439D01*
X5731975Y1016689D01*
X5732285Y1018148D01*
X5731975Y1019606D01*
X5731045Y1020856D01*
X5729960Y1021273D01*
X5725155D01*
G01X5636890Y1328606D02*
Y1341106D01*
X5640920Y1330689D01*
X5644950Y1341106D01*
Y1328606D01*
G01X5650375D02*
Y1341106D01*
X5656265D01*
G01X5654095Y1335064D02*
X5650375D01*
G01X5666650Y1334856D02*
X5669750D01*
Y1331106D01*
X5668820Y1329856D01*
X5667735Y1329023D01*
X5666185Y1328606D01*
X5664635Y1329023D01*
X5663550Y1329856D01*
X5662620Y1331106D01*
X5662000Y1332564D01*
X5661690Y1334231D01*
Y1335689D01*
X5662000Y1336939D01*
X5662620Y1338398D01*
X5663550Y1339648D01*
X5664480Y1340481D01*
X5665720Y1341106D01*
X5666805D01*
X5668045Y1340689D01*
X5668975Y1339856D01*
G01X5673470Y1324439D02*
X5682770D01*
G01X5687265Y1330272D02*
X5688505Y1329231D01*
X5689900Y1328606D01*
X5691140D01*
X5692380Y1329231D01*
X5693310Y1330272D01*
X5693775Y1331731D01*
X5693465Y1333189D01*
X5692690Y1334439D01*
X5691295Y1335273D01*
X5689435Y1335689D01*
X5688350Y1336523D01*
X5687885Y1337981D01*
X5688195Y1339439D01*
X5688970Y1340481D01*
X5690055Y1341106D01*
X5691140D01*
X5692225Y1340689D01*
X5693155Y1339648D01*
G01X5702920Y1341106D02*
Y1328606D01*
G01X5699355Y1341106D02*
X5706485D01*
G01X5711910D02*
Y1332148D01*
X5712530Y1330272D01*
X5713770Y1329023D01*
X5715320Y1328606D01*
X5716870Y1329023D01*
X5718110Y1330272D01*
X5718730Y1332148D01*
Y1341106D01*
G01X5728960Y1335273D02*
X5729580Y1335898D01*
X5730045Y1336939D01*
X5730355Y1338398D01*
X5730045Y1339648D01*
X5729425Y1340481D01*
X5728340Y1341106D01*
X5724155D01*
Y1328606D01*
X5729270D01*
X5730355Y1329439D01*
X5730975Y1330689D01*
X5731285Y1332148D01*
X5730975Y1333606D01*
X5730045Y1334856D01*
X5728960Y1335273D01*
X5724155D01*
G01X5636890Y1644106D02*
Y1656606D01*
X5640920Y1646189D01*
X5644950Y1656606D01*
Y1644106D01*
G01X5650375D02*
Y1656606D01*
X5656265D01*
G01X5654095Y1650564D02*
X5650375D01*
G01X5666650Y1650356D02*
X5669750D01*
Y1646606D01*
X5668820Y1645356D01*
X5667735Y1644523D01*
X5666185Y1644106D01*
X5664635Y1644523D01*
X5663550Y1645356D01*
X5662620Y1646606D01*
X5662000Y1648064D01*
X5661690Y1649731D01*
Y1651189D01*
X5662000Y1652439D01*
X5662620Y1653898D01*
X5663550Y1655148D01*
X5664480Y1655981D01*
X5665720Y1656606D01*
X5666805D01*
X5668045Y1656189D01*
X5668975Y1655356D01*
G01X5673470Y1639939D02*
X5682770D01*
G01X5687265Y1645772D02*
X5688505Y1644731D01*
X5689900Y1644106D01*
X5691140D01*
X5692380Y1644731D01*
X5693310Y1645772D01*
X5693775Y1647231D01*
X5693465Y1648689D01*
X5692690Y1649939D01*
X5691295Y1650773D01*
X5689435Y1651189D01*
X5688350Y1652023D01*
X5687885Y1653481D01*
X5688195Y1654939D01*
X5688970Y1655981D01*
X5690055Y1656606D01*
X5691140D01*
X5692225Y1656189D01*
X5693155Y1655148D01*
G01X5702920Y1656606D02*
Y1644106D01*
G01X5699355Y1656606D02*
X5706485D01*
G01X5711910D02*
Y1647648D01*
X5712530Y1645772D01*
X5713770Y1644523D01*
X5715320Y1644106D01*
X5716870Y1644523D01*
X5718110Y1645772D01*
X5718730Y1647648D01*
Y1656606D01*
G01X5728960Y1650773D02*
X5729580Y1651398D01*
X5730045Y1652439D01*
X5730355Y1653898D01*
X5730045Y1655148D01*
X5729425Y1655981D01*
X5728340Y1656606D01*
X5724155D01*
Y1644106D01*
X5729270D01*
X5730355Y1644939D01*
X5730975Y1646189D01*
X5731285Y1647648D01*
X5730975Y1649106D01*
X5730045Y1650356D01*
X5728960Y1650773D01*
X5724155D01*
G01X5678749Y117283D02*
X5682779D01*
G01X5678749Y142283D02*
X5682779D01*
G01X5678715Y390102D02*
X5682745D01*
G01X5678715Y415102D02*
X5682745D01*
G01X5681305Y661273D02*
X5685335D01*
G01X5681305Y686273D02*
X5685335D01*
G01X5683305Y918773D02*
X5687335D01*
G01X5683305Y943773D02*
X5687335D01*
G01X5683305Y968773D02*
X5687335D01*
G01X5683305Y993773D02*
X5687335D01*
G01X5682305Y1232773D02*
X5686335D01*
G01X5682305Y1257773D02*
X5686335D01*
G01X5682305Y1282773D02*
X5686335D01*
G01X5682305Y1307773D02*
X5686335D01*
G01X5682305Y1548273D02*
X5686335D01*
G01X5682305Y1573273D02*
X5686335D01*
G01X5682305Y1598273D02*
X5686335D01*
G01X5682305Y1623273D02*
X5686335D01*
G01X5764430Y410935D02*
Y423435D01*
X5762570Y420935D01*
G01Y410935D02*
X5766290D01*
G01X5776830Y423435D02*
X5775590Y423018D01*
X5774660Y421977D01*
X5774040Y420727D01*
X5773575Y419060D01*
X5773420Y417185D01*
X5773575Y415310D01*
X5774040Y413643D01*
X5774660Y412393D01*
X5775590Y411352D01*
X5776830Y410935D01*
X5778070Y411352D01*
X5779000Y412393D01*
X5779620Y413643D01*
X5780085Y415310D01*
X5780240Y417185D01*
X5780085Y419060D01*
X5779620Y420727D01*
X5779000Y421977D01*
X5778070Y423018D01*
X5776830Y423435D01*
G01X5789230D02*
X5787990Y423018D01*
X5787060Y421977D01*
X5786440Y420727D01*
X5785975Y419060D01*
X5785820Y417185D01*
X5785975Y415310D01*
X5786440Y413643D01*
X5787060Y412393D01*
X5787990Y411352D01*
X5789230Y410935D01*
X5790470Y411352D01*
X5791400Y412393D01*
X5792020Y413643D01*
X5792485Y415310D01*
X5792640Y417185D01*
X5792485Y419060D01*
X5792020Y420727D01*
X5791400Y421977D01*
X5790470Y423018D01*
X5789230Y423435D01*
G01X5801630D02*
X5800390Y423018D01*
X5799460Y421977D01*
X5798840Y420727D01*
X5798375Y419060D01*
X5798220Y417185D01*
X5798375Y415310D01*
X5798840Y413643D01*
X5799460Y412393D01*
X5800390Y411352D01*
X5801630Y410935D01*
X5802870Y411352D01*
X5803800Y412393D01*
X5804420Y413643D01*
X5804885Y415310D01*
X5805040Y417185D01*
X5804885Y419060D01*
X5804420Y420727D01*
X5803800Y421977D01*
X5802870Y423018D01*
X5801630Y423435D01*
G01X5767719Y118324D02*
X5768804Y119783D01*
X5769734Y120616D01*
X5770974Y121033D01*
X5772059Y120616D01*
X5772834Y119783D01*
X5773454Y118533D01*
X5773609Y117074D01*
X5773454Y115824D01*
X5772834Y114574D01*
X5771904Y113533D01*
X5770819Y113116D01*
X5769579Y113533D01*
X5768494Y114782D01*
X5767874Y116658D01*
X5767719Y118741D01*
X5768029Y121449D01*
X5768494Y122908D01*
X5769269Y124366D01*
X5770354Y125408D01*
X5771439Y125616D01*
X5772524Y125199D01*
X5773299Y124158D01*
G01X5783064Y113116D02*
Y125616D01*
X5781204Y123116D01*
G01Y113116D02*
X5784924D01*
G01X5792519Y123533D02*
X5793449Y124782D01*
X5794534Y125408D01*
X5795774Y125616D01*
X5797324Y125199D01*
X5798409Y124158D01*
X5798719Y122908D01*
X5798564Y121657D01*
X5797944Y120616D01*
X5794844Y118533D01*
X5793449Y117074D01*
X5792519Y114991D01*
X5792209Y113116D01*
X5798719D01*
G01X5767719Y143324D02*
X5768804Y144783D01*
X5769734Y145616D01*
X5770974Y146033D01*
X5772059Y145616D01*
X5772834Y144783D01*
X5773454Y143533D01*
X5773609Y142074D01*
X5773454Y140824D01*
X5772834Y139574D01*
X5771904Y138533D01*
X5770819Y138116D01*
X5769579Y138533D01*
X5768494Y139782D01*
X5767874Y141658D01*
X5767719Y143741D01*
X5768029Y146449D01*
X5768494Y147908D01*
X5769269Y149366D01*
X5770354Y150408D01*
X5771439Y150616D01*
X5772524Y150199D01*
X5773299Y149158D01*
G01X5783064Y138116D02*
X5784149Y138324D01*
X5785389Y138949D01*
X5786164Y139991D01*
X5786474Y141449D01*
X5786164Y142907D01*
X5785234Y144158D01*
X5783839Y144783D01*
X5782289D01*
X5781359Y145199D01*
X5780584Y146241D01*
X5780274Y147699D01*
X5780739Y149158D01*
X5781824Y150199D01*
X5783064Y150616D01*
X5784304Y150199D01*
X5785389Y149158D01*
X5785854Y147699D01*
X5785544Y146241D01*
X5784769Y145199D01*
X5783839Y144783D01*
X5782289D01*
X5780894Y144158D01*
X5779964Y142907D01*
X5779654Y141449D01*
X5779964Y139991D01*
X5780739Y138949D01*
X5781979Y138324D01*
X5783064Y138116D01*
G01X5795464Y150616D02*
X5794224Y150199D01*
X5793294Y149158D01*
X5792674Y147908D01*
X5792209Y146241D01*
X5792054Y144366D01*
X5792209Y142491D01*
X5792674Y140824D01*
X5793294Y139574D01*
X5794224Y138533D01*
X5795464Y138116D01*
X5796704Y138533D01*
X5797634Y139574D01*
X5798254Y140824D01*
X5798719Y142491D01*
X5798874Y144366D01*
X5798719Y146241D01*
X5798254Y147908D01*
X5797634Y149158D01*
X5796704Y150199D01*
X5795464Y150616D01*
G01X5770664Y163116D02*
X5769424Y163324D01*
X5768339Y164157D01*
X5767409Y165408D01*
X5766789Y166866D01*
X5766479Y168533D01*
Y170199D01*
X5766789Y171866D01*
X5767409Y173324D01*
X5768339Y174574D01*
X5769424Y175408D01*
X5770664Y175616D01*
X5771904Y175408D01*
X5772989Y174574D01*
X5773919Y173324D01*
X5774539Y171866D01*
X5774849Y170199D01*
Y168533D01*
X5774539Y166866D01*
X5773919Y165408D01*
X5772989Y164157D01*
X5771904Y163324D01*
X5770664Y163116D01*
G01X5771904Y166449D02*
X5773764Y163116D01*
G01X5783064Y175616D02*
Y163116D01*
G01X5779499Y175616D02*
X5786629D01*
G01X5795464Y163116D02*
Y168741D01*
X5792364Y175616D01*
G01X5798564D02*
X5795464Y168741D01*
G01X5770630Y385935D02*
X5771715Y386143D01*
X5772955Y386768D01*
X5773730Y387810D01*
X5774040Y389268D01*
X5773730Y390726D01*
X5772800Y391977D01*
X5771405Y392602D01*
X5769855D01*
X5768925Y393018D01*
X5768150Y394060D01*
X5767840Y395518D01*
X5768305Y396977D01*
X5769390Y398018D01*
X5770630Y398435D01*
X5771870Y398018D01*
X5772955Y396977D01*
X5773420Y395518D01*
X5773110Y394060D01*
X5772335Y393018D01*
X5771405Y392602D01*
X5769855D01*
X5768460Y391977D01*
X5767530Y390726D01*
X5767220Y389268D01*
X5767530Y387810D01*
X5768305Y386768D01*
X5769545Y386143D01*
X5770630Y385935D01*
G01X5783030D02*
Y398435D01*
X5781170Y395935D01*
G01Y385935D02*
X5784890D01*
G01X5795430D02*
X5796515Y386143D01*
X5797755Y386768D01*
X5798530Y387810D01*
X5798840Y389268D01*
X5798530Y390726D01*
X5797600Y391977D01*
X5796205Y392602D01*
X5794655D01*
X5793725Y393018D01*
X5792950Y394060D01*
X5792640Y395518D01*
X5793105Y396977D01*
X5794190Y398018D01*
X5795430Y398435D01*
X5796670Y398018D01*
X5797755Y396977D01*
X5798220Y395518D01*
X5797910Y394060D01*
X5797135Y393018D01*
X5796205Y392602D01*
X5794655D01*
X5793260Y391977D01*
X5792330Y390726D01*
X5792020Y389268D01*
X5792330Y387810D01*
X5793105Y386768D01*
X5794345Y386143D01*
X5795430Y385935D01*
G01X5770630Y435935D02*
X5769390Y436143D01*
X5768305Y436976D01*
X5767375Y438227D01*
X5766755Y439685D01*
X5766445Y441352D01*
Y443018D01*
X5766755Y444685D01*
X5767375Y446143D01*
X5768305Y447393D01*
X5769390Y448227D01*
X5770630Y448435D01*
X5771870Y448227D01*
X5772955Y447393D01*
X5773885Y446143D01*
X5774505Y444685D01*
X5774815Y443018D01*
Y441352D01*
X5774505Y439685D01*
X5773885Y438227D01*
X5772955Y436976D01*
X5771870Y436143D01*
X5770630Y435935D01*
G01X5771870Y439268D02*
X5773730Y435935D01*
G01X5783030Y448435D02*
Y435935D01*
G01X5779465Y448435D02*
X5786595D01*
G01X5795430Y435935D02*
Y441560D01*
X5792330Y448435D01*
G01X5798530D02*
X5795430Y441560D01*
G01X5772910Y657106D02*
X5773220Y659814D01*
X5773685Y662106D01*
X5774305Y664189D01*
X5775080Y666481D01*
X5776320Y669606D01*
X5770120D01*
G01X5785620Y657106D02*
Y669606D01*
X5783760Y667106D01*
G01Y657106D02*
X5787480D01*
G01X5795075Y662314D02*
X5796160Y663773D01*
X5797090Y664606D01*
X5798330Y665023D01*
X5799415Y664606D01*
X5800190Y663773D01*
X5800810Y662523D01*
X5800965Y661064D01*
X5800810Y659814D01*
X5800190Y658564D01*
X5799260Y657523D01*
X5798175Y657106D01*
X5796935Y657523D01*
X5795850Y658772D01*
X5795230Y660648D01*
X5795075Y662731D01*
X5795385Y665439D01*
X5795850Y666898D01*
X5796625Y668356D01*
X5797710Y669398D01*
X5798795Y669606D01*
X5799880Y669189D01*
X5800655Y668148D01*
G01X5770585Y683564D02*
X5771670Y682523D01*
X5772910Y682106D01*
X5774150Y682523D01*
X5775235Y683772D01*
X5776010Y685648D01*
X5776320Y687523D01*
Y689814D01*
X5776010Y691689D01*
X5775235Y693356D01*
X5774305Y694189D01*
X5773220Y694606D01*
X5771980Y694189D01*
X5771050Y693356D01*
X5770430Y692106D01*
X5770120Y690439D01*
X5770430Y688981D01*
X5771205Y687523D01*
X5772135Y686689D01*
X5773220Y686481D01*
X5774460Y686897D01*
X5775390Y687939D01*
X5776320Y689814D01*
G01X5782675Y687314D02*
X5783760Y688773D01*
X5784690Y689606D01*
X5785930Y690023D01*
X5787015Y689606D01*
X5787790Y688773D01*
X5788410Y687523D01*
X5788565Y686064D01*
X5788410Y684814D01*
X5787790Y683564D01*
X5786860Y682523D01*
X5785775Y682106D01*
X5784535Y682523D01*
X5783450Y683772D01*
X5782830Y685648D01*
X5782675Y687731D01*
X5782985Y690439D01*
X5783450Y691898D01*
X5784225Y693356D01*
X5785310Y694398D01*
X5786395Y694606D01*
X5787480Y694189D01*
X5788255Y693148D01*
G01X5798020Y682106D02*
X5799105Y682314D01*
X5800345Y682939D01*
X5801120Y683981D01*
X5801430Y685439D01*
X5801120Y686897D01*
X5800190Y688148D01*
X5798795Y688773D01*
X5797245D01*
X5796315Y689189D01*
X5795540Y690231D01*
X5795230Y691689D01*
X5795695Y693148D01*
X5796780Y694189D01*
X5798020Y694606D01*
X5799260Y694189D01*
X5800345Y693148D01*
X5800810Y691689D01*
X5800500Y690231D01*
X5799725Y689189D01*
X5798795Y688773D01*
X5797245D01*
X5795850Y688148D01*
X5794920Y686897D01*
X5794610Y685439D01*
X5794920Y683981D01*
X5795695Y682939D01*
X5796935Y682314D01*
X5798020Y682106D01*
G01X5773220Y707106D02*
X5771980Y707314D01*
X5770895Y708147D01*
X5769965Y709398D01*
X5769345Y710856D01*
X5769035Y712523D01*
Y714189D01*
X5769345Y715856D01*
X5769965Y717314D01*
X5770895Y718564D01*
X5771980Y719398D01*
X5773220Y719606D01*
X5774460Y719398D01*
X5775545Y718564D01*
X5776475Y717314D01*
X5777095Y715856D01*
X5777405Y714189D01*
Y712523D01*
X5777095Y710856D01*
X5776475Y709398D01*
X5775545Y708147D01*
X5774460Y707314D01*
X5773220Y707106D01*
G01X5774460Y710439D02*
X5776320Y707106D01*
G01X5785620Y719606D02*
Y707106D01*
G01X5782055Y719606D02*
X5789185D01*
G01X5798020Y707106D02*
Y712731D01*
X5794920Y719606D01*
G01X5801120D02*
X5798020Y712731D01*
G01X5775220Y914606D02*
Y927106D01*
X5773360Y924606D01*
G01Y914606D02*
X5777080D01*
G01X5784675Y925023D02*
X5785605Y926272D01*
X5786690Y926898D01*
X5787930Y927106D01*
X5789480Y926689D01*
X5790565Y925648D01*
X5790875Y924398D01*
X5790720Y923147D01*
X5790100Y922106D01*
X5787000Y920023D01*
X5785605Y918564D01*
X5784675Y916481D01*
X5784365Y914606D01*
X5790875D01*
G01X5800020D02*
X5801105Y914814D01*
X5802345Y915439D01*
X5803120Y916481D01*
X5803430Y917939D01*
X5803120Y919397D01*
X5802190Y920648D01*
X5800795Y921273D01*
X5799245D01*
X5798315Y921689D01*
X5797540Y922731D01*
X5797230Y924189D01*
X5797695Y925648D01*
X5798780Y926689D01*
X5800020Y927106D01*
X5801260Y926689D01*
X5802345Y925648D01*
X5802810Y924189D01*
X5802500Y922731D01*
X5801725Y921689D01*
X5800795Y921273D01*
X5799245D01*
X5797850Y920648D01*
X5796920Y919397D01*
X5796610Y917939D01*
X5796920Y916481D01*
X5797695Y915439D01*
X5798935Y914814D01*
X5800020Y914606D01*
G01X5775220Y939606D02*
X5776305Y939814D01*
X5777545Y940439D01*
X5778320Y941481D01*
X5778630Y942939D01*
X5778320Y944397D01*
X5777390Y945648D01*
X5775995Y946273D01*
X5774445D01*
X5773515Y946689D01*
X5772740Y947731D01*
X5772430Y949189D01*
X5772895Y950648D01*
X5773980Y951689D01*
X5775220Y952106D01*
X5776460Y951689D01*
X5777545Y950648D01*
X5778010Y949189D01*
X5777700Y947731D01*
X5776925Y946689D01*
X5775995Y946273D01*
X5774445D01*
X5773050Y945648D01*
X5772120Y944397D01*
X5771810Y942939D01*
X5772120Y941481D01*
X5772895Y940439D01*
X5774135Y939814D01*
X5775220Y939606D01*
G01X5789480D02*
Y952106D01*
X5783745Y943148D01*
X5791495D01*
G01X5800020Y939606D02*
X5801105Y939814D01*
X5802345Y940439D01*
X5803120Y941481D01*
X5803430Y942939D01*
X5803120Y944397D01*
X5802190Y945648D01*
X5800795Y946273D01*
X5799245D01*
X5798315Y946689D01*
X5797540Y947731D01*
X5797230Y949189D01*
X5797695Y950648D01*
X5798780Y951689D01*
X5800020Y952106D01*
X5801260Y951689D01*
X5802345Y950648D01*
X5802810Y949189D01*
X5802500Y947731D01*
X5801725Y946689D01*
X5800795Y946273D01*
X5799245D01*
X5797850Y945648D01*
X5796920Y944397D01*
X5796610Y942939D01*
X5796920Y941481D01*
X5797695Y940439D01*
X5798935Y939814D01*
X5800020Y939606D01*
G01X5775220Y964606D02*
Y977106D01*
X5773360Y974606D01*
G01Y964606D02*
X5777080D01*
G01X5784675Y975023D02*
X5785605Y976272D01*
X5786690Y976898D01*
X5787930Y977106D01*
X5789480Y976689D01*
X5790565Y975648D01*
X5790875Y974398D01*
X5790720Y973147D01*
X5790100Y972106D01*
X5787000Y970023D01*
X5785605Y968564D01*
X5784675Y966481D01*
X5784365Y964606D01*
X5790875D01*
G01X5800020D02*
X5801105Y964814D01*
X5802345Y965439D01*
X5803120Y966481D01*
X5803430Y967939D01*
X5803120Y969397D01*
X5802190Y970648D01*
X5800795Y971273D01*
X5799245D01*
X5798315Y971689D01*
X5797540Y972731D01*
X5797230Y974189D01*
X5797695Y975648D01*
X5798780Y976689D01*
X5800020Y977106D01*
X5801260Y976689D01*
X5802345Y975648D01*
X5802810Y974189D01*
X5802500Y972731D01*
X5801725Y971689D01*
X5800795Y971273D01*
X5799245D01*
X5797850Y970648D01*
X5796920Y969397D01*
X5796610Y967939D01*
X5796920Y966481D01*
X5797695Y965439D01*
X5798935Y964814D01*
X5800020Y964606D01*
G01X5775220Y989606D02*
X5776305Y989814D01*
X5777545Y990439D01*
X5778320Y991481D01*
X5778630Y992939D01*
X5778320Y994397D01*
X5777390Y995648D01*
X5775995Y996273D01*
X5774445D01*
X5773515Y996689D01*
X5772740Y997731D01*
X5772430Y999189D01*
X5772895Y1000648D01*
X5773980Y1001689D01*
X5775220Y1002106D01*
X5776460Y1001689D01*
X5777545Y1000648D01*
X5778010Y999189D01*
X5777700Y997731D01*
X5776925Y996689D01*
X5775995Y996273D01*
X5774445D01*
X5773050Y995648D01*
X5772120Y994397D01*
X5771810Y992939D01*
X5772120Y991481D01*
X5772895Y990439D01*
X5774135Y989814D01*
X5775220Y989606D01*
G01X5787620Y1002106D02*
X5786380Y1001689D01*
X5785450Y1000648D01*
X5784830Y999398D01*
X5784365Y997731D01*
X5784210Y995856D01*
X5784365Y993981D01*
X5784830Y992314D01*
X5785450Y991064D01*
X5786380Y990023D01*
X5787620Y989606D01*
X5788860Y990023D01*
X5789790Y991064D01*
X5790410Y992314D01*
X5790875Y993981D01*
X5791030Y995856D01*
X5790875Y997731D01*
X5790410Y999398D01*
X5789790Y1000648D01*
X5788860Y1001689D01*
X5787620Y1002106D01*
G01X5800020Y989606D02*
X5801105Y989814D01*
X5802345Y990439D01*
X5803120Y991481D01*
X5803430Y992939D01*
X5803120Y994397D01*
X5802190Y995648D01*
X5800795Y996273D01*
X5799245D01*
X5798315Y996689D01*
X5797540Y997731D01*
X5797230Y999189D01*
X5797695Y1000648D01*
X5798780Y1001689D01*
X5800020Y1002106D01*
X5801260Y1001689D01*
X5802345Y1000648D01*
X5802810Y999189D01*
X5802500Y997731D01*
X5801725Y996689D01*
X5800795Y996273D01*
X5799245D01*
X5797850Y995648D01*
X5796920Y994397D01*
X5796610Y992939D01*
X5796920Y991481D01*
X5797695Y990439D01*
X5798935Y989814D01*
X5800020Y989606D01*
G01X5775220Y1014606D02*
X5773980Y1014814D01*
X5772895Y1015647D01*
X5771965Y1016898D01*
X5771345Y1018356D01*
X5771035Y1020023D01*
Y1021689D01*
X5771345Y1023356D01*
X5771965Y1024814D01*
X5772895Y1026064D01*
X5773980Y1026898D01*
X5775220Y1027106D01*
X5776460Y1026898D01*
X5777545Y1026064D01*
X5778475Y1024814D01*
X5779095Y1023356D01*
X5779405Y1021689D01*
Y1020023D01*
X5779095Y1018356D01*
X5778475Y1016898D01*
X5777545Y1015647D01*
X5776460Y1014814D01*
X5775220Y1014606D01*
G01X5776460Y1017939D02*
X5778320Y1014606D01*
G01X5787620Y1027106D02*
Y1014606D01*
G01X5784055Y1027106D02*
X5791185D01*
G01X5800020Y1014606D02*
Y1020231D01*
X5796920Y1027106D01*
G01X5803120D02*
X5800020Y1020231D01*
G01X5774220Y1228606D02*
Y1241106D01*
X5772360Y1238606D01*
G01Y1228606D02*
X5776080D01*
G01X5783675Y1239023D02*
X5784605Y1240272D01*
X5785690Y1240898D01*
X5786930Y1241106D01*
X5788480Y1240689D01*
X5789565Y1239648D01*
X5789875Y1238398D01*
X5789720Y1237147D01*
X5789100Y1236106D01*
X5786000Y1234023D01*
X5784605Y1232564D01*
X5783675Y1230481D01*
X5783365Y1228606D01*
X5789875D01*
G01X5799020D02*
X5800105Y1228814D01*
X5801345Y1229439D01*
X5802120Y1230481D01*
X5802430Y1231939D01*
X5802120Y1233397D01*
X5801190Y1234648D01*
X5799795Y1235273D01*
X5798245D01*
X5797315Y1235689D01*
X5796540Y1236731D01*
X5796230Y1238189D01*
X5796695Y1239648D01*
X5797780Y1240689D01*
X5799020Y1241106D01*
X5800260Y1240689D01*
X5801345Y1239648D01*
X5801810Y1238189D01*
X5801500Y1236731D01*
X5800725Y1235689D01*
X5799795Y1235273D01*
X5798245D01*
X5796850Y1234648D01*
X5795920Y1233397D01*
X5795610Y1231939D01*
X5795920Y1230481D01*
X5796695Y1229439D01*
X5797935Y1228814D01*
X5799020Y1228606D01*
G01X5773910Y1253606D02*
X5774220Y1256314D01*
X5774685Y1258606D01*
X5775305Y1260689D01*
X5776080Y1262981D01*
X5777320Y1266106D01*
X5771120D01*
G01X5786310Y1253606D02*
X5786620Y1256314D01*
X5787085Y1258606D01*
X5787705Y1260689D01*
X5788480Y1262981D01*
X5789720Y1266106D01*
X5783520D01*
G01X5796075Y1264023D02*
X5797005Y1265272D01*
X5798090Y1265898D01*
X5799330Y1266106D01*
X5800880Y1265689D01*
X5801965Y1264648D01*
X5802275Y1263398D01*
X5802120Y1262147D01*
X5801500Y1261106D01*
X5798400Y1259023D01*
X5797005Y1257564D01*
X5796075Y1255481D01*
X5795765Y1253606D01*
X5802275D01*
G01X5777785Y1280064D02*
X5778870Y1279023D01*
X5780110Y1278606D01*
X5781350Y1279023D01*
X5782435Y1280272D01*
X5783210Y1282148D01*
X5783520Y1284023D01*
Y1286314D01*
X5783210Y1288189D01*
X5782435Y1289856D01*
X5781505Y1290689D01*
X5780420Y1291106D01*
X5779180Y1290689D01*
X5778250Y1289856D01*
X5777630Y1288606D01*
X5777320Y1286939D01*
X5777630Y1285481D01*
X5778405Y1284023D01*
X5779335Y1283189D01*
X5780420Y1282981D01*
X5781660Y1283397D01*
X5782590Y1284439D01*
X5783520Y1286314D01*
G01X5789875Y1283814D02*
X5790960Y1285273D01*
X5791890Y1286106D01*
X5793130Y1286523D01*
X5794215Y1286106D01*
X5794990Y1285273D01*
X5795610Y1284023D01*
X5795765Y1282564D01*
X5795610Y1281314D01*
X5794990Y1280064D01*
X5794060Y1279023D01*
X5792975Y1278606D01*
X5791735Y1279023D01*
X5790650Y1280272D01*
X5790030Y1282148D01*
X5789875Y1284231D01*
X5790185Y1286939D01*
X5790650Y1288398D01*
X5791425Y1289856D01*
X5792510Y1290898D01*
X5793595Y1291106D01*
X5794680Y1290689D01*
X5795455Y1289648D01*
G01X5771275Y1308814D02*
X5772360Y1310273D01*
X5773290Y1311106D01*
X5774530Y1311523D01*
X5775615Y1311106D01*
X5776390Y1310273D01*
X5777010Y1309023D01*
X5777165Y1307564D01*
X5777010Y1306314D01*
X5776390Y1305064D01*
X5775460Y1304023D01*
X5774375Y1303606D01*
X5773135Y1304023D01*
X5772050Y1305272D01*
X5771430Y1307148D01*
X5771275Y1309231D01*
X5771585Y1311939D01*
X5772050Y1313398D01*
X5772825Y1314856D01*
X5773910Y1315898D01*
X5774995Y1316106D01*
X5776080Y1315689D01*
X5776855Y1314648D01*
G01X5786620Y1303606D02*
X5787705Y1303814D01*
X5788945Y1304439D01*
X5789720Y1305481D01*
X5790030Y1306939D01*
X5789720Y1308397D01*
X5788790Y1309648D01*
X5787395Y1310273D01*
X5785845D01*
X5784915Y1310689D01*
X5784140Y1311731D01*
X5783830Y1313189D01*
X5784295Y1314648D01*
X5785380Y1315689D01*
X5786620Y1316106D01*
X5787860Y1315689D01*
X5788945Y1314648D01*
X5789410Y1313189D01*
X5789100Y1311731D01*
X5788325Y1310689D01*
X5787395Y1310273D01*
X5785845D01*
X5784450Y1309648D01*
X5783520Y1308397D01*
X5783210Y1306939D01*
X5783520Y1305481D01*
X5784295Y1304439D01*
X5785535Y1303814D01*
X5786620Y1303606D01*
G01X5799020Y1316106D02*
X5797780Y1315689D01*
X5796850Y1314648D01*
X5796230Y1313398D01*
X5795765Y1311731D01*
X5795610Y1309856D01*
X5795765Y1307981D01*
X5796230Y1306314D01*
X5796850Y1305064D01*
X5797780Y1304023D01*
X5799020Y1303606D01*
X5800260Y1304023D01*
X5801190Y1305064D01*
X5801810Y1306314D01*
X5802275Y1307981D01*
X5802430Y1309856D01*
X5802275Y1311731D01*
X5801810Y1313398D01*
X5801190Y1314648D01*
X5800260Y1315689D01*
X5799020Y1316106D01*
G01X5774220Y1328606D02*
X5772980Y1328814D01*
X5771895Y1329647D01*
X5770965Y1330898D01*
X5770345Y1332356D01*
X5770035Y1334023D01*
Y1335689D01*
X5770345Y1337356D01*
X5770965Y1338814D01*
X5771895Y1340064D01*
X5772980Y1340898D01*
X5774220Y1341106D01*
X5775460Y1340898D01*
X5776545Y1340064D01*
X5777475Y1338814D01*
X5778095Y1337356D01*
X5778405Y1335689D01*
Y1334023D01*
X5778095Y1332356D01*
X5777475Y1330898D01*
X5776545Y1329647D01*
X5775460Y1328814D01*
X5774220Y1328606D01*
G01X5775460Y1331939D02*
X5777320Y1328606D01*
G01X5786620Y1341106D02*
Y1328606D01*
G01X5783055Y1341106D02*
X5790185D01*
G01X5799020Y1328606D02*
Y1334231D01*
X5795920Y1341106D01*
G01X5802120D02*
X5799020Y1334231D01*
G01X5774220Y1544106D02*
Y1556606D01*
X5772360Y1554106D01*
G01Y1544106D02*
X5776080D01*
G01X5783675Y1554523D02*
X5784605Y1555772D01*
X5785690Y1556398D01*
X5786930Y1556606D01*
X5788480Y1556189D01*
X5789565Y1555148D01*
X5789875Y1553898D01*
X5789720Y1552647D01*
X5789100Y1551606D01*
X5786000Y1549523D01*
X5784605Y1548064D01*
X5783675Y1545981D01*
X5783365Y1544106D01*
X5789875D01*
G01X5799020D02*
X5800105Y1544314D01*
X5801345Y1544939D01*
X5802120Y1545981D01*
X5802430Y1547439D01*
X5802120Y1548897D01*
X5801190Y1550148D01*
X5799795Y1550773D01*
X5798245D01*
X5797315Y1551189D01*
X5796540Y1552231D01*
X5796230Y1553689D01*
X5796695Y1555148D01*
X5797780Y1556189D01*
X5799020Y1556606D01*
X5800260Y1556189D01*
X5801345Y1555148D01*
X5801810Y1553689D01*
X5801500Y1552231D01*
X5800725Y1551189D01*
X5799795Y1550773D01*
X5798245D01*
X5796850Y1550148D01*
X5795920Y1548897D01*
X5795610Y1547439D01*
X5795920Y1545981D01*
X5796695Y1544939D01*
X5797935Y1544314D01*
X5799020Y1544106D01*
G01X5774220Y1569106D02*
Y1581606D01*
X5772360Y1579106D01*
G01Y1569106D02*
X5776080D01*
G01X5783985Y1570564D02*
X5785070Y1569523D01*
X5786310Y1569106D01*
X5787550Y1569523D01*
X5788635Y1570772D01*
X5789410Y1572648D01*
X5789720Y1574523D01*
Y1576814D01*
X5789410Y1578689D01*
X5788635Y1580356D01*
X5787705Y1581189D01*
X5786620Y1581606D01*
X5785380Y1581189D01*
X5784450Y1580356D01*
X5783830Y1579106D01*
X5783520Y1577439D01*
X5783830Y1575981D01*
X5784605Y1574523D01*
X5785535Y1573689D01*
X5786620Y1573481D01*
X5787860Y1573897D01*
X5788790Y1574939D01*
X5789720Y1576814D01*
G01X5796075Y1579523D02*
X5797005Y1580772D01*
X5798090Y1581398D01*
X5799330Y1581606D01*
X5800880Y1581189D01*
X5801965Y1580148D01*
X5802275Y1578898D01*
X5802120Y1577647D01*
X5801500Y1576606D01*
X5798400Y1574523D01*
X5797005Y1573064D01*
X5796075Y1570981D01*
X5795765Y1569106D01*
X5802275D01*
G01X5777010Y1596606D02*
X5777940Y1595147D01*
X5779180Y1594314D01*
X5780575Y1594106D01*
X5781815Y1594314D01*
X5783055Y1595356D01*
X5783830Y1596606D01*
X5783985Y1597856D01*
X5783675Y1599314D01*
X5782590Y1600356D01*
X5781505Y1600773D01*
X5780110D01*
G01X5781505D02*
X5782435Y1601398D01*
X5783210Y1602439D01*
X5783520Y1603689D01*
X5783210Y1604939D01*
X5782435Y1605981D01*
X5781040Y1606606D01*
X5779645Y1606398D01*
X5778250Y1605564D01*
G01X5789875Y1604523D02*
X5790805Y1605772D01*
X5791890Y1606398D01*
X5793130Y1606606D01*
X5794680Y1606189D01*
X5795765Y1605148D01*
X5796075Y1603898D01*
X5795920Y1602647D01*
X5795300Y1601606D01*
X5792200Y1599523D01*
X5790805Y1598064D01*
X5789875Y1595981D01*
X5789565Y1594106D01*
X5796075D01*
G01X5774220Y1619106D02*
Y1631606D01*
X5772360Y1629106D01*
G01Y1619106D02*
X5776080D01*
G01X5786620Y1631606D02*
X5785380Y1631189D01*
X5784450Y1630148D01*
X5783830Y1628898D01*
X5783365Y1627231D01*
X5783210Y1625356D01*
X5783365Y1623481D01*
X5783830Y1621814D01*
X5784450Y1620564D01*
X5785380Y1619523D01*
X5786620Y1619106D01*
X5787860Y1619523D01*
X5788790Y1620564D01*
X5789410Y1621814D01*
X5789875Y1623481D01*
X5790030Y1625356D01*
X5789875Y1627231D01*
X5789410Y1628898D01*
X5788790Y1630148D01*
X5787860Y1631189D01*
X5786620Y1631606D01*
G01X5799020D02*
X5797780Y1631189D01*
X5796850Y1630148D01*
X5796230Y1628898D01*
X5795765Y1627231D01*
X5795610Y1625356D01*
X5795765Y1623481D01*
X5796230Y1621814D01*
X5796850Y1620564D01*
X5797780Y1619523D01*
X5799020Y1619106D01*
X5800260Y1619523D01*
X5801190Y1620564D01*
X5801810Y1621814D01*
X5802275Y1623481D01*
X5802430Y1625356D01*
X5802275Y1627231D01*
X5801810Y1628898D01*
X5801190Y1630148D01*
X5800260Y1631189D01*
X5799020Y1631606D01*
G01X5774220Y1644106D02*
X5772980Y1644314D01*
X5771895Y1645147D01*
X5770965Y1646398D01*
X5770345Y1647856D01*
X5770035Y1649523D01*
Y1651189D01*
X5770345Y1652856D01*
X5770965Y1654314D01*
X5771895Y1655564D01*
X5772980Y1656398D01*
X5774220Y1656606D01*
X5775460Y1656398D01*
X5776545Y1655564D01*
X5777475Y1654314D01*
X5778095Y1652856D01*
X5778405Y1651189D01*
Y1649523D01*
X5778095Y1647856D01*
X5777475Y1646398D01*
X5776545Y1645147D01*
X5775460Y1644314D01*
X5774220Y1644106D01*
G01X5775460Y1647439D02*
X5777320Y1644106D01*
G01X5786620Y1656606D02*
Y1644106D01*
G01X5783055Y1656606D02*
X5790185D01*
G01X5799020Y1644106D02*
Y1649731D01*
X5795920Y1656606D01*
G01X5802120D02*
X5799020Y1649731D01*
G54D18*
X79729Y289822D03*
Y310256D03*
X89729Y289822D03*
X99729D03*
X89729Y310256D03*
X99729D03*
X757184Y1702772D03*
Y1712772D03*
Y1722772D03*
X1072863Y1409176D03*
Y1419176D03*
Y1429176D03*
X1080970Y1640958D03*
Y1650958D03*
Y1660958D03*
X1299439Y92812D03*
Y102812D03*
Y112812D03*
X1530377Y581353D03*
X1540377D03*
X1550377D03*
X2392820Y863706D03*
G54D36*
X887519Y1528191D03*
X2392820Y450006D03*
G54D27*
X326731Y653394D03*
Y663237D03*
X363731Y653394D03*
Y663237D03*
X433624Y594259D03*
X443467D03*
X754645Y1426892D03*
Y1436735D03*
X1077638Y133866D03*
X1166535Y1412479D03*
Y1422322D03*
X1291146Y1375715D03*
Y1385558D03*
X1320516Y1375715D03*
Y1385558D03*
X1425533Y601230D03*
X1415690D03*
X1487677Y640145D03*
Y649988D03*
X1524437Y640365D03*
Y650208D03*
X1701285Y208455D03*
Y198612D03*
X1700840Y1434362D03*
Y1424519D03*
X1731660Y208455D03*
Y198612D03*
X1770442Y284934D03*
Y294777D03*
X1800002Y284934D03*
Y294777D03*
X2392820Y981906D03*
Y1041006D03*
G54D19*
X77394Y734588D03*
Y1021399D03*
Y1277698D03*
X107095Y734588D03*
Y1021399D03*
Y1277698D03*
X136795Y734588D03*
Y1021399D03*
Y1277698D03*
X166496Y734588D03*
Y1021399D03*
Y1277698D03*
X196197Y734588D03*
Y1021399D03*
Y1277698D03*
X225898Y734588D03*
Y1021399D03*
Y1277698D03*
X655425Y734588D03*
Y1021399D03*
Y1277698D03*
X685126Y734588D03*
Y1021399D03*
Y1277698D03*
X714827Y734588D03*
Y1021399D03*
Y1277698D03*
X744528Y734588D03*
Y1021399D03*
Y1277698D03*
X774229Y734588D03*
Y1021399D03*
Y1277698D03*
X803929Y734588D03*
Y1021399D03*
Y1277698D03*
X1053536Y734587D03*
Y1021398D03*
Y1277697D03*
X1083237Y734587D03*
Y1021398D03*
Y1277697D03*
X1112937Y734587D03*
Y1021398D03*
Y1277697D03*
X1142638Y734587D03*
Y1021398D03*
Y1277697D03*
X1172339Y734587D03*
Y1021398D03*
Y1277697D03*
X1202040Y734587D03*
Y1021398D03*
Y1277697D03*
X1631567Y734587D03*
Y1021398D03*
Y1277697D03*
X1661268Y734587D03*
Y1021398D03*
Y1277697D03*
X1690969Y734587D03*
Y1021398D03*
Y1277697D03*
X1720670Y734587D03*
Y1021398D03*
Y1277697D03*
X1750371Y734587D03*
Y1021398D03*
Y1277697D03*
X1780071Y734587D03*
Y1021398D03*
Y1277697D03*
X2392820Y-495594D03*
G54D28*
X373673Y-28871D03*
Y-18871D03*
D03*
Y-8871D03*
X398673Y-28871D03*
Y-18871D03*
D03*
Y-8871D03*
X718093Y-28871D03*
Y-18871D03*
D03*
Y-8871D03*
X743093Y-28871D03*
Y-18871D03*
D03*
Y-8871D03*
X825152Y-35011D03*
Y-25011D03*
Y-15011D03*
Y-25011D03*
Y-15011D03*
Y-5011D03*
D03*
Y4989D03*
Y14989D03*
D03*
Y4989D03*
Y24989D03*
X850152Y-35011D03*
Y-25011D03*
Y-15011D03*
Y-25011D03*
Y-15011D03*
Y-5011D03*
D03*
Y4989D03*
Y14989D03*
D03*
Y4989D03*
Y24989D03*
X1169572Y-35011D03*
Y-15011D03*
Y-25011D03*
D03*
Y-15011D03*
Y-5011D03*
D03*
Y4989D03*
Y14989D03*
Y4989D03*
Y14989D03*
Y24989D03*
X1194572Y-35011D03*
Y-15011D03*
Y-25011D03*
D03*
Y-15011D03*
Y-5011D03*
D03*
Y4989D03*
Y14989D03*
Y4989D03*
Y14989D03*
Y24989D03*
X1228672Y-35011D03*
Y-25011D03*
Y-15011D03*
Y-25011D03*
Y-15011D03*
Y-5011D03*
D03*
Y4989D03*
Y14989D03*
D03*
Y4989D03*
Y24989D03*
X1253672Y-35011D03*
Y-25011D03*
Y-15011D03*
Y-25011D03*
Y-15011D03*
Y-5011D03*
D03*
Y4989D03*
Y14989D03*
D03*
Y4989D03*
Y24989D03*
X1428431Y-35011D03*
Y-15011D03*
Y-25011D03*
D03*
Y-15011D03*
Y-5011D03*
D03*
Y4989D03*
Y14989D03*
Y4989D03*
Y14989D03*
Y24989D03*
X1453431Y-35011D03*
Y-15011D03*
Y-25011D03*
D03*
Y-15011D03*
Y-5011D03*
D03*
Y4989D03*
Y14989D03*
Y4989D03*
Y14989D03*
Y24989D03*
X1521966Y-29212D03*
D03*
Y-39212D03*
Y-19212D03*
X1546966Y-29212D03*
D03*
Y-39212D03*
Y-19212D03*
X1721725Y-29212D03*
Y-39212D03*
Y-29212D03*
Y-19212D03*
X1746725Y-29212D03*
Y-39212D03*
Y-29212D03*
Y-19212D03*
X2392820Y272706D03*
G54D37*
X900197Y175177D03*
X944685Y155197D03*
X2392820Y627306D03*
G54D38*
X922441Y154311D03*
Y243799D03*
X2392820Y-436494D03*
G54D29*
X539016Y274272D03*
X549016D03*
X559016D03*
X569016D03*
X579016D03*
X589016D03*
X599016D03*
X609016D03*
X2392820Y745506D03*
G54D39*
X928740Y321654D03*
X2392820Y-613794D03*
M02*
